FILE_TYPE=EXPANDEDPARTLIST;
{ Packager-XL run on 25-Aug-2023 AT 17:03:33 }
DIRECTIVES
 PST_VERSION='PST_HDL_CENTRIC_VERSION_0';
 ROOT_DRAWING='SCM';
 POST_TIME='25-Aug-2023 AT 17:03:33';
 SOURCE_TOOL='PACKAGER_XL';
END_DIRECTIVES;

PART_NAME
 C1 'Q_CAP_C0603-4.7UF,25V,10%,X6S,A':;

SECTION_NUMBER 1
 '@SCM_LIB.SCM(SCH_1):PAGE20_I4@PURE_QUANTA.Q_CAP(CHIPS)':
 C_PATH='@scm_lib.scm(sch_1):page20_i4@pure_quanta.q_cap(chips)',
 P_PATH='@scm_lib.scm(sch_1):page20_i4@pure_quanta.q_cap(chips)',
 PATH='I4',
 DRAWING='@SCM_LIB.SCM(SCH_1):PAGE20',
 SEC_TYPE='C0603',
 PHYS_PAGE='20',
 XY='(-3700,2475)',
 ROT='0',
 VER='1',
 PACK_TYPE='C0603',
 LOCATION='C1',
 SEC='1',
 CDS_LIB='pure_quanta',
 CDS_PART_NAME='Q_CAP_C0603-4.7UF,25V,10%,X6S,A',
 TOLERANCE='10%',
 MATERIAL='X6S',
 VOLTAGE='25V',
 VALUE='4.7UF',
 PRIM_FILE='W:/<user>/logical/q_cap/chips/chips.prt';

PART_NAME
 C2 'Q_CAP_C0402-1UF,25V,10%,X6S,CHA':;

SECTION_NUMBER 1
 '@SCM_LIB.SCM(SCH_1):PAGE20_I5@PURE_QUANTA.Q_CAP(CHIPS)':
 C_PATH='@scm_lib.scm(sch_1):page20_i5@pure_quanta.q_cap(chips)',
 P_PATH='@scm_lib.scm(sch_1):page20_i5@pure_quanta.q_cap(chips)',
 PATH='I5',
 DRAWING='@SCM_LIB.SCM(SCH_1):PAGE20',
 SEC_TYPE='C0402',
 PHYS_PAGE='20',
 XY='(-3475,2475)',
 ROT='0',
 VER='1',
 PACK_TYPE='C0402',
 LOCATION='C2',
 SEC='1',
 CDS_LIB='pure_quanta',
 CDS_PART_NAME='Q_CAP_C0402-1UF,25V,10%,X6S,CHA',
 TOLERANCE='10%',
 MATERIAL='X6S',
 VOLTAGE='25V',
 VALUE='1UF',
 PRIM_FILE='W:/<user>/logical/q_cap/chips/chips.prt';

PART_NAME
 C3 'Q_CAP_C0402-1UF,25V,10%,X6S,CHA':;

SECTION_NUMBER 1
 '@SCM_LIB.SCM(SCH_1):PAGE20_I6@PURE_QUANTA.Q_CAP(CHIPS)':
 C_PATH='@scm_lib.scm(sch_1):page20_i6@pure_quanta.q_cap(chips)',
 P_PATH='@scm_lib.scm(sch_1):page20_i6@pure_quanta.q_cap(chips)',
 PATH='I6',
 DRAWING='@SCM_LIB.SCM(SCH_1):PAGE20',
 SEC_TYPE='C0402',
 PHYS_PAGE='20',
 XY='(-3275,2475)',
 ROT='0',
 VER='1',
 PACK_TYPE='C0402',
 LOCATION='C3',
 SEC='1',
 CDS_LIB='pure_quanta',
 CDS_PART_NAME='Q_CAP_C0402-1UF,25V,10%,X6S,CHA',
 TOLERANCE='10%',
 MATERIAL='X6S',
 VOLTAGE='25V',
 VALUE='1UF',
 PRIM_FILE='W:/<user>/logical/q_cap/chips/chips.prt';

PART_NAME
 C4 'Q_CAP_C0402-1UF,25V,10%,X6S,CHA':;

SECTION_NUMBER 1
 '@SCM_LIB.SCM(SCH_1):PAGE20_I7@PURE_QUANTA.Q_CAP(CHIPS)':
 C_PATH='@scm_lib.scm(sch_1):page20_i7@pure_quanta.q_cap(chips)',
 P_PATH='@scm_lib.scm(sch_1):page20_i7@pure_quanta.q_cap(chips)',
 PATH='I7',
 DRAWING='@SCM_LIB.SCM(SCH_1):PAGE20',
 SEC_TYPE='C0402',
 PHYS_PAGE='20',
 XY='(-3075,2475)',
 ROT='0',
 VER='1',
 PACK_TYPE='C0402',
 LOCATION='C4',
 SEC='1',
 CDS_LIB='pure_quanta',
 CDS_PART_NAME='Q_CAP_C0402-1UF,25V,10%,X6S,CHA',
 TOLERANCE='10%',
 MATERIAL='X6S',
 VOLTAGE='25V',
 VALUE='1UF',
 PRIM_FILE='W:/<user>/logical/q_cap/chips/chips.prt';

PART_NAME
 C5 'Q_CAP_C0402-1UF,25V,10%,X6S,CHA':;

SECTION_NUMBER 1
 '@SCM_LIB.SCM(SCH_1):PAGE20_I23@PURE_QUANTA.Q_CAP(CHIPS)':
 C_PATH='@scm_lib.scm(sch_1):page20_i23@pure_quanta.q_cap(chips)',
 P_PATH='@scm_lib.scm(sch_1):page20_i23@pure_quanta.q_cap(chips)',
 PATH='I23',
 DRAWING='@SCM_LIB.SCM(SCH_1):PAGE20',
 SEC_TYPE='C0402',
 PHYS_PAGE='20',
 XY='(-2875,2475)',
 ROT='0',
 VER='1',
 PACK_TYPE='C0402',
 LOCATION='C5',
 SEC='1',
 CDS_LIB='pure_quanta',
 CDS_PART_NAME='Q_CAP_C0402-1UF,25V,10%,X6S,CHA',
 TOLERANCE='10%',
 MATERIAL='X6S',
 VOLTAGE='25V',
 VALUE='1UF',
 PRIM_FILE='W:/<user>/logical/q_cap/chips/chips.prt';

PART_NAME
 C6 'Q_CAP_0402-0.1UF,25V,10%,X7R,CA':;

SECTION_NUMBER 1
 '@SCM_LIB.SCM(SCH_1):PAGE20_I19@PURE_QUANTA.Q_CAP(CHIPS)':
 C_PATH='@scm_lib.scm(sch_1):page20_i19@pure_quanta.q_cap(chips)',
 P_PATH='@scm_lib.scm(sch_1):page20_i19@pure_quanta.q_cap(chips)',
 PATH='I19',
 DRAWING='@SCM_LIB.SCM(SCH_1):PAGE20',
 SEC_TYPE='0402',
 PHYS_PAGE='20',
 XY='(-3050,1300)',
 ROT='0',
 VER='1',
 PACK_TYPE='0402',
 LOCATION='C6',
 SEC='1',
 CDS_LIB='pure_quanta',
 CDS_PART_NAME='Q_CAP_0402-0.1UF,25V,10%,X7R,CA',
 TOLERANCE='10%',
 MATERIAL='X7R',
 VOLTAGE='25V',
 VALUE='0.1UF',
 PRIM_FILE='W:/<user>/logical/q_cap/chips/chips.prt';

PART_NAME
 C7 'Q_CAP_0402-0.1UF,25V,10%,X7R,CA':;

SECTION_NUMBER 1
 '@SCM_LIB.SCM(SCH_1):PAGE20_I24@PURE_QUANTA.Q_CAP(CHIPS)':
 C_PATH='@scm_lib.scm(sch_1):page20_i24@pure_quanta.q_cap(chips)',
 P_PATH='@scm_lib.scm(sch_1):page20_i24@pure_quanta.q_cap(chips)',
 PATH='I24',
 DRAWING='@SCM_LIB.SCM(SCH_1):PAGE20',
 SEC_TYPE='0402',
 PHYS_PAGE='20',
 XY='(-2650,2475)',
 ROT='0',
 VER='1',
 PACK_TYPE='0402',
 LOCATION='C7',
 SEC='1',
 CDS_LIB='pure_quanta',
 CDS_PART_NAME='Q_CAP_0402-0.1UF,25V,10%,X7R,CA',
 TOLERANCE='10%',
 MATERIAL='X7R',
 VOLTAGE='25V',
 VALUE='0.1UF',
 PRIM_FILE='W:/<user>/logical/q_cap/chips/chips.prt';

PART_NAME
 C8 'Q_CAP_0402-0.1UF,25V,10%,X7R,CA':;

SECTION_NUMBER 1
 '@SCM_LIB.SCM(SCH_1):PAGE20_I21@PURE_QUANTA.Q_CAP(CHIPS)':
 C_PATH='@scm_lib.scm(sch_1):page20_i21@pure_quanta.q_cap(chips)',
 P_PATH='@scm_lib.scm(sch_1):page20_i21@pure_quanta.q_cap(chips)',
 PATH='I21',
 DRAWING='@SCM_LIB.SCM(SCH_1):PAGE20',
 SEC_TYPE='0402',
 PHYS_PAGE='20',
 XY='(-2775,1300)',
 ROT='0',
 VER='1',
 PACK_TYPE='0402',
 LOCATION='C8',
 SEC='1',
 CDS_LIB='pure_quanta',
 CDS_PART_NAME='Q_CAP_0402-0.1UF,25V,10%,X7R,CA',
 TOLERANCE='10%',
 MATERIAL='X7R',
 VOLTAGE='25V',
 VALUE='0.1UF',
 PRIM_FILE='W:/<user>/logical/q_cap/chips/chips.prt';

PART_NAME
 C9 'Q_CAP_0402-100PF,50V,5%,NPO,CHA':;

SECTION_NUMBER 1
 '@SCM_LIB.SCM(SCH_1):PAGE20_I25@PURE_QUANTA.Q_CAP(CHIPS)':
 C_PATH='@scm_lib.scm(sch_1):page20_i25@pure_quanta.q_cap(chips)',
 P_PATH='@scm_lib.scm(sch_1):page20_i25@pure_quanta.q_cap(chips)',
 PATH='I25',
 DRAWING='@SCM_LIB.SCM(SCH_1):PAGE20',
 SEC_TYPE='0402',
 PHYS_PAGE='20',
 XY='(-2400,2475)',
 ROT='0',
 VER='1',
 PACK_TYPE='0402',
 LOCATION='C9',
 SEC='1',
 CDS_LIB='pure_quanta',
 CDS_PART_NAME='Q_CAP_0402-100PF,50V,5%,NPO,CHA',
 TOLERANCE='5%',
 MATERIAL='NPO',
 VOLTAGE='50V',
 VALUE='100PF',
 PRIM_FILE='W:/<user>/logical/q_cap/chips/chips.prt';

PART_NAME
 C10 'Q_CAP_0402-0.1UF,25V,10%,X7R,CA':;

SECTION_NUMBER 1
 '@SCM_LIB.SCM(SCH_1):PAGE20_I85@PURE_QUANTA.Q_CAP(CHIPS)':
 C_PATH='@scm_lib.scm(sch_1):page20_i85@pure_quanta.q_cap(chips)',
 P_PATH='@scm_lib.scm(sch_1):page20_i85@pure_quanta.q_cap(chips)',
 PATH='I85',
 DRAWING='@SCM_LIB.SCM(SCH_1):PAGE20',
 SEC_TYPE='0402',
 PHYS_PAGE='20',
 XY='(800,2650)',
 ROT='0',
 VER='1',
 PACK_TYPE='0402',
 LOCATION='C10',
 SEC='1',
 CDS_LIB='pure_quanta',
 CDS_PART_NAME='Q_CAP_0402-0.1UF,25V,10%,X7R,CA',
 TOLERANCE='10%',
 MATERIAL='X7R',
 VOLTAGE='25V',
 VALUE='0.1UF',
 PRIM_FILE='W:/<user>/logical/q_cap/chips/chips.prt';

PART_NAME
 C11 'Q_CAP_0402-0.1UF,25V,10%,X7R,CA':;

SECTION_NUMBER 1
 '@SCM_LIB.SCM(SCH_1):PAGE31_I31@PURE_QUANTA.Q_CAP(CHIPS)':
 C_PATH='@scm_lib.scm(sch_1):page31_i31@pure_quanta.q_cap(chips)',
 P_PATH='@scm_lib.scm(sch_1):page31_i31@pure_quanta.q_cap(chips)',
 PATH='I31',
 DRAWING='@SCM_LIB.SCM(SCH_1):PAGE31',
 PHYS_PAGE='31',
 XY='(-4125,3350)',
 ROT='2',
 VER='1',
 PACK_TYPE='0402',
 CDS_LIB='pure_quanta',
 CDS_PART_NAME='Q_CAP_0402-0.1UF,25V,10%,X7R,CA',
 TOLERANCE='10%',
 MATERIAL='X7R',
 VOLTAGE='25V',
 VALUE='0.1UF',
 PRIM_FILE='W:/<user>/logical/q_cap/chips/chips.prt';

PART_NAME
 C12 'Q_CAP_0402-0.22UF,16V,10%,X7R,A':;

SECTION_NUMBER 1
 '@SCM_LIB.SCM(SCH_1):PAGE20_I106@PURE_QUANTA.Q_CAP(CHIPS)':
 C_PATH='@scm_lib.scm(sch_1):page20_i106@pure_quanta.q_cap(chips)',
 P_PATH='@scm_lib.scm(sch_1):page20_i106@pure_quanta.q_cap(chips)',
 PATH='I106',
 DRAWING='@SCM_LIB.SCM(SCH_1):PAGE20',
 SEC_TYPE='0402',
 PHYS_PAGE='20',
 XY='(3700,-1050)',
 ROT='0',
 VER='2',
 PACK_TYPE='0402',
 LOCATION='C12',
 SEC='1',
 CDS_LIB='pure_quanta',
 CDS_PART_NAME='Q_CAP_0402-0.22UF,16V,10%,X7R,A',
 TOLERANCE='10%',
 MATERIAL='X7R',
 VOLTAGE='16V',
 VALUE='0.22UF',
 PRIM_FILE='W:/<user>/logical/q_cap/chips/chips.prt';

PART_NAME
 C13 'Q_CAP_0402-0.1UF,25V,10%,X7R,CA':;

SECTION_NUMBER 1
 '@SCM_LIB.SCM(SCH_1):PAGE20_I186@PURE_QUANTA.Q_CAP(CHIPS)':
 C_PATH='@scm_lib.scm(sch_1):page20_i186@pure_quanta.q_cap(chips)',
 P_PATH='@scm_lib.scm(sch_1):page20_i186@pure_quanta.q_cap(chips)',
 PATH='I186',
 DRAWING='@SCM_LIB.SCM(SCH_1):PAGE20',
 SEC_TYPE='0402',
 PHYS_PAGE='20',
 XY='(4875,3650)',
 ROT='0',
 VER='1',
 PACK_TYPE='0402',
 LOCATION='C13',
 SEC='1',
 CDS_LIB='pure_quanta',
 CDS_PART_NAME='Q_CAP_0402-0.1UF,25V,10%,X7R,CA',
 TOLERANCE='10%',
 MATERIAL='X7R',
 VOLTAGE='25V',
 VALUE='0.1UF',
 PRIM_FILE='W:/<user>/logical/q_cap/chips/chips.prt';

PART_NAME
 C14 'Q_CAP_0402-0.1UF,25V,10%,X7R,CA':;

SECTION_NUMBER 1
 '@SCM_LIB.SCM(SCH_1):PAGE20_I187@PURE_QUANTA.Q_CAP(CHIPS)':
 C_PATH='@scm_lib.scm(sch_1):page20_i187@pure_quanta.q_cap(chips)',
 P_PATH='@scm_lib.scm(sch_1):page20_i187@pure_quanta.q_cap(chips)',
 PATH='I187',
 DRAWING='@SCM_LIB.SCM(SCH_1):PAGE20',
 SEC_TYPE='0402',
 PHYS_PAGE='20',
 XY='(4950,3975)',
 ROT='0',
 VER='1',
 PACK_TYPE='0402',
 LOCATION='C14',
 SEC='1',
 CDS_LIB='pure_quanta',
 CDS_PART_NAME='Q_CAP_0402-0.1UF,25V,10%,X7R,CA',
 TOLERANCE='10%',
 MATERIAL='X7R',
 VOLTAGE='25V',
 VALUE='0.1UF',
 PRIM_FILE='W:/<user>/logical/q_cap/chips/chips.prt';

PART_NAME
 C15 'Q_CAP_C0402-10UF,6.3V,20%,X6S,A':;

SECTION_NUMBER 1
 '@SCM_LIB.SCM(SCH_1):PAGE20_I134@PURE_QUANTA.Q_CAP(CHIPS)':
 C_PATH='@scm_lib.scm(sch_1):page20_i134@pure_quanta.q_cap(chips)',
 P_PATH='@scm_lib.scm(sch_1):page20_i134@pure_quanta.q_cap(chips)',
 PATH='I134',
 DRAWING='@SCM_LIB.SCM(SCH_1):PAGE20',
 SEC_TYPE='C0402',
 PHYS_PAGE='20',
 XY='(4975,1075)',
 ROT='0',
 VER='1',
 PACK_TYPE='C0402',
 LOCATION='C15',
 SEC='1',
 CDS_LIB='pure_quanta',
 CDS_PART_NAME='Q_CAP_C0402-10UF,6.3V,20%,X6S,A',
 TOLERANCE='20%',
 MATERIAL='X6S',
 VOLTAGE='6.3V',
 VALUE='10UF',
 PRIM_FILE='W:/<user>/logical/q_cap/chips/chips.prt';

PART_NAME
 C16 'Q_CAP_C0402-10UF,6.3V,20%,X6S,A':;

SECTION_NUMBER 1
 '@SCM_LIB.SCM(SCH_1):PAGE20_I113@PURE_QUANTA.Q_CAP(CHIPS)':
 C_PATH='@scm_lib.scm(sch_1):page20_i113@pure_quanta.q_cap(chips)',
 P_PATH='@scm_lib.scm(sch_1):page20_i113@pure_quanta.q_cap(chips)',
 PATH='I113',
 DRAWING='@SCM_LIB.SCM(SCH_1):PAGE20',
 SEC_TYPE='C0402',
 PHYS_PAGE='20',
 XY='(4975,325)',
 ROT='0',
 VER='1',
 PACK_TYPE='C0402',
 LOCATION='C16',
 SEC='1',
 CDS_LIB='pure_quanta',
 CDS_PART_NAME='Q_CAP_C0402-10UF,6.3V,20%,X6S,A',
 TOLERANCE='20%',
 MATERIAL='X6S',
 VOLTAGE='6.3V',
 VALUE='10UF',
 PRIM_FILE='W:/<user>/logical/q_cap/chips/chips.prt';

PART_NAME
 C17 'Q_CAP_0402-0.1UF,25V,10%,X7R,CA':;

SECTION_NUMBER 1
 '@SCM_LIB.SCM(SCH_1):PAGE20_I190@PURE_QUANTA.Q_CAP(CHIPS)':
 C_PATH='@scm_lib.scm(sch_1):page20_i190@pure_quanta.q_cap(chips)',
 P_PATH='@scm_lib.scm(sch_1):page20_i190@pure_quanta.q_cap(chips)',
 PATH='I190',
 DRAWING='@SCM_LIB.SCM(SCH_1):PAGE20',
 SEC_TYPE='0402',
 PHYS_PAGE='20',
 XY='(5025,4275)',
 ROT='0',
 VER='1',
 PACK_TYPE='0402',
 LOCATION='C17',
 SEC='1',
 CDS_LIB='pure_quanta',
 CDS_PART_NAME='Q_CAP_0402-0.1UF,25V,10%,X7R,CA',
 TOLERANCE='10%',
 MATERIAL='X7R',
 VOLTAGE='25V',
 VALUE='0.1UF',
 PRIM_FILE='W:/<user>/logical/q_cap/chips/chips.prt';

PART_NAME
 C18 'Q_CAP_0402-0.1UF,25V,10%,X7R,CA':;

SECTION_NUMBER 1
 '@SCM_LIB.SCM(SCH_1):PAGE20_I192@PURE_QUANTA.Q_CAP(CHIPS)':
 C_PATH='@scm_lib.scm(sch_1):page20_i192@pure_quanta.q_cap(chips)',
 P_PATH='@scm_lib.scm(sch_1):page20_i192@pure_quanta.q_cap(chips)',
 PATH='I192',
 DRAWING='@SCM_LIB.SCM(SCH_1):PAGE20',
 SEC_TYPE='0402',
 PHYS_PAGE='20',
 XY='(5175,4600)',
 ROT='0',
 VER='1',
 PACK_TYPE='0402',
 LOCATION='C18',
 SEC='1',
 CDS_LIB='pure_quanta',
 CDS_PART_NAME='Q_CAP_0402-0.1UF,25V,10%,X7R,CA',
 TOLERANCE='10%',
 MATERIAL='X7R',
 VOLTAGE='25V',
 VALUE='0.1UF',
 PRIM_FILE='W:/<user>/logical/q_cap/chips/chips.prt';

PART_NAME
 C19 'Q_CAP_0402-0.1UF,25V,10%,X7R,CA':;

SECTION_NUMBER 1
 '@SCM_LIB.SCM(SCH_1):PAGE30_I261@PURE_QUANTA.Q_CAP(CHIPS)':
 C_PATH='@scm_lib.scm(sch_1):page30_i261@pure_quanta.q_cap(chips)',
 P_PATH='@scm_lib.scm(sch_1):page30_i261@pure_quanta.q_cap(chips)',
 PATH='I261',
 DRAWING='@SCM_LIB.SCM(SCH_1):PAGE30',
 SEC_TYPE='0402',
 PHYS_PAGE='30',
 XY='(3000,4550)',
 ROT='0',
 VER='1',
 PACK_TYPE='0402',
 LOCATION='C19',
 SEC='1',
 CDS_LIB='pure_quanta',
 CDS_PART_NAME='Q_CAP_0402-0.1UF,25V,10%,X7R,CA',
 TOLERANCE='10%',
 MATERIAL='X7R',
 VOLTAGE='25V',
 VALUE='0.1UF',
 PRIM_FILE='W:/<user>/logical/q_cap/chips/chips.prt';

PART_NAME
 C20 'Q_CAP_0402-0.1UF,25V,10%,X7R,CA':;

SECTION_NUMBER 1
 '@SCM_LIB.SCM(SCH_1):PAGE30_I254@PURE_QUANTA.Q_CAP(CHIPS)':
 C_PATH='@scm_lib.scm(sch_1):page30_i254@pure_quanta.q_cap(chips)',
 P_PATH='@scm_lib.scm(sch_1):page30_i254@pure_quanta.q_cap(chips)',
 PATH='I254',
 DRAWING='@SCM_LIB.SCM(SCH_1):PAGE30',
 SEC_TYPE='0402',
 PHYS_PAGE='30',
 XY='(2825,3575)',
 ROT='0',
 VER='1',
 PACK_TYPE='0402',
 LOCATION='C20',
 SEC='1',
 CDS_LIB='pure_quanta',
 CDS_PART_NAME='Q_CAP_0402-0.1UF,25V,10%,X7R,CA',
 TOLERANCE='10%',
 MATERIAL='X7R',
 VOLTAGE='25V',
 VALUE='0.1UF',
 PRIM_FILE='W:/<user>/logical/q_cap/chips/chips.prt';

PART_NAME
 C21 'Q_CAP_C0402-0.01UF,50V,10%,EMPA':;

SECTION_NUMBER 1
 '@SCM_LIB.SCM(SCH_1):PAGE12_I24@PURE_QUANTA.Q_CAP(CHIPS)':
 C_PATH='@scm_lib.scm(sch_1):page12_i24@pure_quanta.q_cap(chips)',
 P_PATH='@scm_lib.scm(sch_1):page12_i24@pure_quanta.q_cap(chips)',
 PATH='I24',
 DRAWING='@SCM_LIB.SCM(SCH_1):PAGE12',
 PHYS_PAGE='12',
 XY='(-2200,2625)',
 ROT='0',
 VER='1',
 PACK_TYPE='C0402',
 LOCATION='C21',
 CDS_LIB='pure_quanta',
 CDS_PART_NAME='Q_CAP_C0402-0.01UF,50V,10%,EMPA',
 TOLERANCE='10%',
 MATERIAL='EMPTY',
 VOLTAGE='50V',
 VALUE='0.01UF',
 PRIM_FILE='W:/<user>/logical/q_cap/chips/chips.prt';

PART_NAME
 C22 'Q_CAP_0402-0.1UF,25V,10%,X7R,CA':;

SECTION_NUMBER 1
 '@SCM_LIB.SCM(SCH_1):PAGE12_I448@PURE_QUANTA.Q_CAP(CHIPS)':
 C_PATH='@scm_lib.scm(sch_1):page12_i448@pure_quanta.q_cap(chips)',
 P_PATH='@scm_lib.scm(sch_1):page12_i448@pure_quanta.q_cap(chips)',
 PATH='I448',
 DRAWING='@SCM_LIB.SCM(SCH_1):PAGE12',
 PHYS_PAGE='12',
 XY='(-1875,2625)',
 ROT='0',
 VER='1',
 PACK_TYPE='0402',
 LOCATION='C22',
 CDS_LIB='pure_quanta',
 CDS_PART_NAME='Q_CAP_0402-0.1UF,25V,10%,X7R,CA',
 TOLERANCE='10%',
 MATERIAL='X7R',
 VOLTAGE='25V',
 VALUE='0.1UF',
 PRIM_FILE='W:/<user>/logical/q_cap/chips/chips.prt';

PART_NAME
 C23 'Q_CAP_0402-0.1UF,25V,10%,X7R,CA':;

SECTION_NUMBER 1
 '@SCM_LIB.SCM(SCH_1):PAGE12_I28@PURE_QUANTA.Q_CAP(CHIPS)':
 C_PATH='@scm_lib.scm(sch_1):page12_i28@pure_quanta.q_cap(chips)',
 P_PATH='@scm_lib.scm(sch_1):page12_i28@pure_quanta.q_cap(chips)',
 PATH='I28',
 DRAWING='@SCM_LIB.SCM(SCH_1):PAGE12',
 PHYS_PAGE='12',
 XY='(-1550,2625)',
 ROT='0',
 VER='1',
 PACK_TYPE='0402',
 LOCATION='C23',
 CDS_LIB='pure_quanta',
 CDS_PART_NAME='Q_CAP_0402-0.1UF,25V,10%,X7R,CA',
 TOLERANCE='10%',
 MATERIAL='X7R',
 VOLTAGE='25V',
 VALUE='0.1UF',
 PRIM_FILE='W:/<user>/logical/q_cap/chips/chips.prt';

PART_NAME
 C24 'Q_CAP_0402-0.1UF,25V,10%,X7R,CA':;

SECTION_NUMBER 1
 '@SCM_LIB.SCM(SCH_1):PAGE12_I152@PURE_QUANTA.Q_CAP(CHIPS)':
 C_PATH='@scm_lib.scm(sch_1):page12_i152@pure_quanta.q_cap(chips)',
 P_PATH='@scm_lib.scm(sch_1):page12_i152@pure_quanta.q_cap(chips)',
 PATH='I152',
 DRAWING='@SCM_LIB.SCM(SCH_1):PAGE12',
 PHYS_PAGE='12',
 XY='(3825,4600)',
 ROT='0',
 VER='2',
 PACK_TYPE='0402',
 LOCATION='C24',
 CDS_LIB='pure_quanta',
 CDS_PART_NAME='Q_CAP_0402-0.1UF,25V,10%,X7R,CA',
 TOLERANCE='10%',
 MATERIAL='X7R',
 VOLTAGE='25V',
 VALUE='0.1UF',
 PRIM_FILE='W:/<user>/logical/q_cap/chips/chips.prt';

PART_NAME
 C25 'Q_CAP_0402-0.1UF,25V,10%,X7R,CA':;

SECTION_NUMBER 1
 '@SCM_LIB.SCM(SCH_1):PAGE12_I153@PURE_QUANTA.Q_CAP(CHIPS)':
 C_PATH='@scm_lib.scm(sch_1):page12_i153@pure_quanta.q_cap(chips)',
 P_PATH='@scm_lib.scm(sch_1):page12_i153@pure_quanta.q_cap(chips)',
 PATH='I153',
 DRAWING='@SCM_LIB.SCM(SCH_1):PAGE12',
 PHYS_PAGE='12',
 XY='(3825,4550)',
 ROT='0',
 VER='2',
 PACK_TYPE='0402',
 LOCATION='C25',
 CDS_LIB='pure_quanta',
 CDS_PART_NAME='Q_CAP_0402-0.1UF,25V,10%,X7R,CA',
 TOLERANCE='10%',
 MATERIAL='X7R',
 VOLTAGE='25V',
 VALUE='0.1UF',
 PRIM_FILE='W:/<user>/logical/q_cap/chips/chips.prt';

PART_NAME
 C26 'Q_CAP_0402-0.1UF,25V,10%,X7R,CA':;

SECTION_NUMBER 1
 '@SCM_LIB.SCM(SCH_1):PAGE15_I398@PURE_QUANTA.Q_CAP(CHIPS)':
 C_PATH='@scm_lib.scm(sch_1):page15_i398@pure_quanta.q_cap(chips)',
 P_PATH='@scm_lib.scm(sch_1):page15_i398@pure_quanta.q_cap(chips)',
 PATH='I398',
 DRAWING='@SCM_LIB.SCM(SCH_1):PAGE15',
 PHYS_PAGE='15',
 XY='(5575,2025)',
 ROT='2',
 VER='1',
 PACK_TYPE='0402',
 CDS_LIB='pure_quanta',
 CDS_PART_NAME='Q_CAP_0402-0.1UF,25V,10%,X7R,CA',
 TOLERANCE='10%',
 MATERIAL='X7R',
 VOLTAGE='25V',
 VALUE='0.1UF',
 PRIM_FILE='W:/<user>/logical/q_cap/chips/chips.prt';

PART_NAME
 C27 'Q_CAP_0402-0.1UF,25V,10%,X7R,CA':;

SECTION_NUMBER 1
 '@SCM_LIB.SCM(SCH_1):PAGE50_I212@PURE_QUANTA.Q_CAP(CHIPS)':
 C_PATH='@scm_lib.scm(sch_1):page50_i212@pure_quanta.q_cap(chips)',
 P_PATH='@scm_lib.scm(sch_1):page50_i212@pure_quanta.q_cap(chips)',
 PATH='I212',
 DRAWING='@SCM_LIB.SCM(SCH_1):PAGE50',
 PHYS_PAGE='50',
 XY='(750,-200)',
 ROT='0',
 VER='1',
 PACK_TYPE='0402',
 CDS_LIB='pure_quanta',
 CDS_PART_NAME='Q_CAP_0402-0.1UF,25V,10%,X7R,CA',
 TOLERANCE='10%',
 MATERIAL='X7R',
 VOLTAGE='25V',
 VALUE='0.1UF',
 PRIM_FILE='W:/<user>/logical/q_cap/chips/chips.prt';

PART_NAME
 C28 'Q_CAP_C0402-1UF,25V,10%,EMPTY,A':;

SECTION_NUMBER 1
 '@SCM_LIB.SCM(SCH_1):PAGE50_I236@PURE_QUANTA.Q_CAP(CHIPS)':
 C_PATH='@scm_lib.scm(sch_1):page50_i236@pure_quanta.q_cap(chips)',
 P_PATH='@scm_lib.scm(sch_1):page50_i236@pure_quanta.q_cap(chips)',
 PATH='I236',
 DRAWING='@SCM_LIB.SCM(SCH_1):PAGE50',
 PHYS_PAGE='50',
 XY='(3000,3000)',
 ROT='0',
 VER='1',
 PACK_TYPE='C0402',
 CDS_LIB='pure_quanta',
 CDS_PART_NAME='Q_CAP_C0402-1UF,25V,10%,EMPTY,A',
 TOLERANCE='10%',
 MATERIAL='EMPTY',
 VOLTAGE='25V',
 VALUE='1UF',
 PRIM_FILE='W:/<user>/logical/q_cap/chips/chips.prt';

PART_NAME
 C29 'Q_CAP_0402-0.1UF,25V,10%,EMPTYA':;

SECTION_NUMBER 1
 '@SCM_LIB.SCM(SCH_1):PAGE50_I232@PURE_QUANTA.Q_CAP(CHIPS)':
 C_PATH='@scm_lib.scm(sch_1):page50_i232@pure_quanta.q_cap(chips)',
 P_PATH='@scm_lib.scm(sch_1):page50_i232@pure_quanta.q_cap(chips)',
 PATH='I232',
 DRAWING='@SCM_LIB.SCM(SCH_1):PAGE50',
 PHYS_PAGE='50',
 XY='(3700,3675)',
 ROT='2',
 VER='1',
 PACK_TYPE='0402',
 CDS_LIB='pure_quanta',
 CDS_PART_NAME='Q_CAP_0402-0.1UF,25V,10%,EMPTYA',
 TOLERANCE='10%',
 MATERIAL='EMPTY',
 VOLTAGE='25V',
 VALUE='0.1UF',
 PRIM_FILE='W:/<user>/logical/q_cap/chips/chips.prt';

PART_NAME
 C30 'Q_CAP_C0402-1UF,25V,10%,X6S,CHA':;

SECTION_NUMBER 1
 '@SCM_LIB.SCM(SCH_1):PAGE13_I29@PURE_QUANTA.Q_CAP(CHIPS)':
 C_PATH='@scm_lib.scm(sch_1):page13_i29@pure_quanta.q_cap(chips)',
 P_PATH='@scm_lib.scm(sch_1):page13_i29@pure_quanta.q_cap(chips)',
 PATH='I29',
 DRAWING='@SCM_LIB.SCM(SCH_1):PAGE13',
 PHYS_PAGE='13',
 XY='(-1950,-150)',
 ROT='0',
 VER='1',
 PACK_TYPE='C0402',
 LOCATION='C30',
 CDS_LIB='pure_quanta',
 CDS_PART_NAME='Q_CAP_C0402-1UF,25V,10%,X6S,CHA',
 TOLERANCE='10%',
 MATERIAL='X6S',
 VOLTAGE='25V',
 VALUE='1UF',
 PRIM_FILE='W:/<user>/logical/q_cap/chips/chips.prt';

PART_NAME
 C31 'Q_CAP_0402-0.1UF,25V,10%,X7R,CA':;

SECTION_NUMBER 1
 '@SCM_LIB.SCM(SCH_1):PAGE13_I30@PURE_QUANTA.Q_CAP(CHIPS)':
 C_PATH='@scm_lib.scm(sch_1):page13_i30@pure_quanta.q_cap(chips)',
 P_PATH='@scm_lib.scm(sch_1):page13_i30@pure_quanta.q_cap(chips)',
 PATH='I30',
 DRAWING='@SCM_LIB.SCM(SCH_1):PAGE13',
 PHYS_PAGE='13',
 XY='(-1750,-150)',
 ROT='0',
 VER='1',
 PACK_TYPE='0402',
 LOCATION='C31',
 CDS_LIB='pure_quanta',
 CDS_PART_NAME='Q_CAP_0402-0.1UF,25V,10%,X7R,CA',
 TOLERANCE='10%',
 MATERIAL='X7R',
 VOLTAGE='25V',
 VALUE='0.1UF',
 PRIM_FILE='W:/<user>/logical/q_cap/chips/chips.prt';

PART_NAME
 C32 'Q_CAP_C0402-1UF,25V,10%,X6S,CHA':;

SECTION_NUMBER 1
 '@SCM_LIB.SCM(SCH_1):PAGE13_I31@PURE_QUANTA.Q_CAP(CHIPS)':
 C_PATH='@scm_lib.scm(sch_1):page13_i31@pure_quanta.q_cap(chips)',
 P_PATH='@scm_lib.scm(sch_1):page13_i31@pure_quanta.q_cap(chips)',
 PATH='I31',
 DRAWING='@SCM_LIB.SCM(SCH_1):PAGE13',
 PHYS_PAGE='13',
 XY='(-1550,-150)',
 ROT='0',
 VER='1',
 PACK_TYPE='C0402',
 LOCATION='C32',
 CDS_LIB='pure_quanta',
 CDS_PART_NAME='Q_CAP_C0402-1UF,25V,10%,X6S,CHA',
 TOLERANCE='10%',
 MATERIAL='X6S',
 VOLTAGE='25V',
 VALUE='1UF',
 PRIM_FILE='W:/<user>/logical/q_cap/chips/chips.prt';

PART_NAME
 C33 'Q_CAP_0402-0.1UF,25V,10%,X7R,CA':;

SECTION_NUMBER 1
 '@SCM_LIB.SCM(SCH_1):PAGE13_I32@PURE_QUANTA.Q_CAP(CHIPS)':
 C_PATH='@scm_lib.scm(sch_1):page13_i32@pure_quanta.q_cap(chips)',
 P_PATH='@scm_lib.scm(sch_1):page13_i32@pure_quanta.q_cap(chips)',
 PATH='I32',
 DRAWING='@SCM_LIB.SCM(SCH_1):PAGE13',
 PHYS_PAGE='13',
 XY='(-1350,-150)',
 ROT='0',
 VER='1',
 PACK_TYPE='0402',
 LOCATION='C33',
 CDS_LIB='pure_quanta',
 CDS_PART_NAME='Q_CAP_0402-0.1UF,25V,10%,X7R,CA',
 TOLERANCE='10%',
 MATERIAL='X7R',
 VOLTAGE='25V',
 VALUE='0.1UF',
 PRIM_FILE='W:/<user>/logical/q_cap/chips/chips.prt';

PART_NAME
 C34 'Q_CAP_0402-0.1UF,25V,10%,X7R,CA':;

SECTION_NUMBER 1
 '@SCM_LIB.SCM(SCH_1):PAGE22_I42@PURE_QUANTA.Q_CAP(CHIPS)':
 C_PATH='@scm_lib.scm(sch_1):page22_i42@pure_quanta.q_cap(chips)',
 P_PATH='@scm_lib.scm(sch_1):page22_i42@pure_quanta.q_cap(chips)',
 PATH='I42',
 DRAWING='@SCM_LIB.SCM(SCH_1):PAGE22',
 PHYS_PAGE='22',
 XY='(-675,1650)',
 ROT='0',
 VER='1',
 PACK_TYPE='0402',
 LOCATION='C34',
 CDS_LIB='pure_quanta',
 CDS_PART_NAME='Q_CAP_0402-0.1UF,25V,10%,X7R,CA',
 TOLERANCE='10%',
 MATERIAL='X7R',
 VOLTAGE='25V',
 VALUE='0.1UF',
 PRIM_FILE='W:/<user>/logical/q_cap/chips/chips.prt';

PART_NAME
 C35 'Q_CAP_C0402-1UF,25V,10%,X6S,CHA':;

SECTION_NUMBER 1
 '@SCM_LIB.SCM(SCH_1):PAGE15_I14@PURE_QUANTA.Q_CAP(CHIPS)':
 C_PATH='@scm_lib.scm(sch_1):page15_i14@pure_quanta.q_cap(chips)',
 P_PATH='@scm_lib.scm(sch_1):page15_i14@pure_quanta.q_cap(chips)',
 PATH='I14',
 DRAWING='@SCM_LIB.SCM(SCH_1):PAGE15',
 PHYS_PAGE='15',
 XY='(3175,-725)',
 ROT='0',
 VER='1',
 PACK_TYPE='C0402',
 LOCATION='C35',
 CDS_LIB='pure_quanta',
 CDS_PART_NAME='Q_CAP_C0402-1UF,25V,10%,X6S,CHA',
 TOLERANCE='10%',
 MATERIAL='X6S',
 VOLTAGE='25V',
 VALUE='1UF',
 PRIM_FILE='W:/<user>/logical/q_cap/chips/chips.prt';

PART_NAME
 C36 'Q_CAP_0402-0.1UF,25V,10%,X7R,CA':;

SECTION_NUMBER 1
 '@SCM_LIB.SCM(SCH_1):PAGE15_I16@PURE_QUANTA.Q_CAP(CHIPS)':
 C_PATH='@scm_lib.scm(sch_1):page15_i16@pure_quanta.q_cap(chips)',
 P_PATH='@scm_lib.scm(sch_1):page15_i16@pure_quanta.q_cap(chips)',
 PATH='I16',
 DRAWING='@SCM_LIB.SCM(SCH_1):PAGE15',
 PHYS_PAGE='15',
 XY='(3375,-725)',
 ROT='0',
 VER='1',
 PACK_TYPE='0402',
 LOCATION='C36',
 CDS_LIB='pure_quanta',
 CDS_PART_NAME='Q_CAP_0402-0.1UF,25V,10%,X7R,CA',
 TOLERANCE='10%',
 MATERIAL='X7R',
 VOLTAGE='25V',
 VALUE='0.1UF',
 PRIM_FILE='W:/<user>/logical/q_cap/chips/chips.prt';

PART_NAME
 C37 'Q_CAP_0402-0.1UF,25V,10%,X7R,CA':;

SECTION_NUMBER 1
 '@SCM_LIB.SCM(SCH_1):PAGE15_I24@PURE_QUANTA.Q_CAP(CHIPS)':
 C_PATH='@scm_lib.scm(sch_1):page15_i24@pure_quanta.q_cap(chips)',
 P_PATH='@scm_lib.scm(sch_1):page15_i24@pure_quanta.q_cap(chips)',
 PATH='I24',
 DRAWING='@SCM_LIB.SCM(SCH_1):PAGE15',
 PHYS_PAGE='15',
 XY='(-175,800)',
 ROT='0',
 VER='1',
 PACK_TYPE='0402',
 LOCATION='C37',
 CDS_LIB='pure_quanta',
 CDS_PART_NAME='Q_CAP_0402-0.1UF,25V,10%,X7R,CA',
 TOLERANCE='10%',
 MATERIAL='X7R',
 VOLTAGE='25V',
 VALUE='0.1UF',
 PRIM_FILE='W:/<user>/logical/q_cap/chips/chips.prt';

PART_NAME
 C38 'Q_CAP_C0402-1UF,25V,10%,X6S,CHA':;

SECTION_NUMBER 1
 '@SCM_LIB.SCM(SCH_1):PAGE15_I36@PURE_QUANTA.Q_CAP(CHIPS)':
 C_PATH='@scm_lib.scm(sch_1):page15_i36@pure_quanta.q_cap(chips)',
 P_PATH='@scm_lib.scm(sch_1):page15_i36@pure_quanta.q_cap(chips)',
 PATH='I36',
 DRAWING='@SCM_LIB.SCM(SCH_1):PAGE15',
 PHYS_PAGE='15',
 XY='(5450,-525)',
 ROT='0',
 VER='1',
 PACK_TYPE='C0402',
 LOCATION='C38',
 CDS_LIB='pure_quanta',
 CDS_PART_NAME='Q_CAP_C0402-1UF,25V,10%,X6S,CHA',
 TOLERANCE='10%',
 MATERIAL='X6S',
 VOLTAGE='25V',
 VALUE='1UF',
 PRIM_FILE='W:/<user>/logical/q_cap/chips/chips.prt';

PART_NAME
 C39 'Q_CAP_0402-0.1UF,25V,10%,X7R,CA':;

SECTION_NUMBER 1
 '@SCM_LIB.SCM(SCH_1):PAGE15_I37@PURE_QUANTA.Q_CAP(CHIPS)':
 C_PATH='@scm_lib.scm(sch_1):page15_i37@pure_quanta.q_cap(chips)',
 P_PATH='@scm_lib.scm(sch_1):page15_i37@pure_quanta.q_cap(chips)',
 PATH='I37',
 DRAWING='@SCM_LIB.SCM(SCH_1):PAGE15',
 PHYS_PAGE='15',
 XY='(5650,-525)',
 ROT='0',
 VER='1',
 PACK_TYPE='0402',
 LOCATION='C39',
 CDS_LIB='pure_quanta',
 CDS_PART_NAME='Q_CAP_0402-0.1UF,25V,10%,X7R,CA',
 TOLERANCE='10%',
 MATERIAL='X7R',
 VOLTAGE='25V',
 VALUE='0.1UF',
 PRIM_FILE='W:/<user>/logical/q_cap/chips/chips.prt';

PART_NAME
 C40 'Q_CAP_C0603-4.7UF,25V,10%,X6S,A':;

SECTION_NUMBER 1
 '@SCM_LIB.SCM(SCH_1):PAGE15_I368@PURE_QUANTA.Q_CAP(CHIPS)':
 C_PATH='@scm_lib.scm(sch_1):page15_i368@pure_quanta.q_cap(chips)',
 P_PATH='@scm_lib.scm(sch_1):page15_i368@pure_quanta.q_cap(chips)',
 PATH='I368',
 DRAWING='@SCM_LIB.SCM(SCH_1):PAGE15',
 PHYS_PAGE='15',
 XY='(3800,650)',
 ROT='0',
 VER='1',
 PACK_TYPE='C0603',
 LOCATION='C40',
 CDS_LIB='pure_quanta',
 CDS_PART_NAME='Q_CAP_C0603-4.7UF,25V,10%,X6S,A',
 TOLERANCE='10%',
 MATERIAL='X6S',
 VOLTAGE='25V',
 VALUE='4.7UF',
 PRIM_FILE='W:/<user>/logical/q_cap/chips/chips.prt';

PART_NAME
 C41 'Q_CAP_0402-0.1UF,25V,10%,X7R,CA':;

SECTION_NUMBER 1
 '@SCM_LIB.SCM(SCH_1):PAGE15_I68@PURE_QUANTA.Q_CAP(CHIPS)':
 C_PATH='@scm_lib.scm(sch_1):page15_i68@pure_quanta.q_cap(chips)',
 P_PATH='@scm_lib.scm(sch_1):page15_i68@pure_quanta.q_cap(chips)',
 PATH='I68',
 DRAWING='@SCM_LIB.SCM(SCH_1):PAGE15',
 PHYS_PAGE='15',
 XY='(4000,650)',
 ROT='0',
 VER='1',
 PACK_TYPE='0402',
 LOCATION='C41',
 CDS_LIB='pure_quanta',
 CDS_PART_NAME='Q_CAP_0402-0.1UF,25V,10%,X7R,CA',
 TOLERANCE='10%',
 MATERIAL='X7R',
 VOLTAGE='25V',
 VALUE='0.1UF',
 PRIM_FILE='W:/<user>/logical/q_cap/chips/chips.prt';

PART_NAME
 C42 'Q_CAP_C0603-22UF,6.3V,20%,X6S,A':;

SECTION_NUMBER 1
 '@SCM_LIB.SCM(SCH_1):PAGE15_I117@PURE_QUANTA.Q_CAP(CHIPS)':
 C_PATH='@scm_lib.scm(sch_1):page15_i117@pure_quanta.q_cap(chips)',
 P_PATH='@scm_lib.scm(sch_1):page15_i117@pure_quanta.q_cap(chips)',
 PATH='I117',
 DRAWING='@SCM_LIB.SCM(SCH_1):PAGE15',
 PHYS_PAGE='15',
 XY='(4450,2375)',
 ROT='0',
 VER='1',
 PACK_TYPE='C0603',
 LOCATION='C42',
 CDS_LIB='pure_quanta',
 CDS_PART_NAME='Q_CAP_C0603-22UF,6.3V,20%,X6S,A',
 TOLERANCE='20%',
 MATERIAL='X6S',
 VOLTAGE='6.3V',
 VALUE='22UF',
 PRIM_FILE='W:/<user>/logical/q_cap/chips/chips.prt';

PART_NAME
 C43 'Q_CAP_C0402-1UF,25V,10%,X6S,CHA':;

SECTION_NUMBER 1
 '@SCM_LIB.SCM(SCH_1):PAGE15_I119@PURE_QUANTA.Q_CAP(CHIPS)':
 C_PATH='@scm_lib.scm(sch_1):page15_i119@pure_quanta.q_cap(chips)',
 P_PATH='@scm_lib.scm(sch_1):page15_i119@pure_quanta.q_cap(chips)',
 PATH='I119',
 DRAWING='@SCM_LIB.SCM(SCH_1):PAGE15',
 PHYS_PAGE='15',
 XY='(4675,2375)',
 ROT='0',
 VER='1',
 PACK_TYPE='C0402',
 LOCATION='C43',
 CDS_LIB='pure_quanta',
 CDS_PART_NAME='Q_CAP_C0402-1UF,25V,10%,X6S,CHA',
 TOLERANCE='10%',
 MATERIAL='X6S',
 VOLTAGE='25V',
 VALUE='1UF',
 PRIM_FILE='W:/<user>/logical/q_cap/chips/chips.prt';

PART_NAME
 C44 'Q_CAP_C0603-4.7UF,25V,10%,X6S,A':;

SECTION_NUMBER 1
 '@SCM_LIB.SCM(SCH_1):PAGE15_I369@PURE_QUANTA.Q_CAP(CHIPS)':
 C_PATH='@scm_lib.scm(sch_1):page15_i369@pure_quanta.q_cap(chips)',
 P_PATH='@scm_lib.scm(sch_1):page15_i369@pure_quanta.q_cap(chips)',
 PATH='I369',
 DRAWING='@SCM_LIB.SCM(SCH_1):PAGE15',
 PHYS_PAGE='15',
 XY='(5300,625)',
 ROT='0',
 VER='1',
 PACK_TYPE='C0603',
 LOCATION='C44',
 CDS_LIB='pure_quanta',
 CDS_PART_NAME='Q_CAP_C0603-4.7UF,25V,10%,X6S,A',
 TOLERANCE='10%',
 MATERIAL='X6S',
 VOLTAGE='25V',
 VALUE='4.7UF',
 PRIM_FILE='W:/<user>/logical/q_cap/chips/chips.prt';

PART_NAME
 C45 'Q_CAP_0402-0.1UF,25V,10%,X7R,CA':;

SECTION_NUMBER 1
 '@SCM_LIB.SCM(SCH_1):PAGE15_I89@PURE_QUANTA.Q_CAP(CHIPS)':
 C_PATH='@scm_lib.scm(sch_1):page15_i89@pure_quanta.q_cap(chips)',
 P_PATH='@scm_lib.scm(sch_1):page15_i89@pure_quanta.q_cap(chips)',
 PATH='I89',
 DRAWING='@SCM_LIB.SCM(SCH_1):PAGE15',
 PHYS_PAGE='15',
 XY='(5500,625)',
 ROT='0',
 VER='1',
 PACK_TYPE='0402',
 LOCATION='C45',
 CDS_LIB='pure_quanta',
 CDS_PART_NAME='Q_CAP_0402-0.1UF,25V,10%,X7R,CA',
 TOLERANCE='10%',
 MATERIAL='X7R',
 VOLTAGE='25V',
 VALUE='0.1UF',
 PRIM_FILE='W:/<user>/logical/q_cap/chips/chips.prt';

PART_NAME
 C46 'Q_CAP_C0402-1UF,25V,10%,X6S,CHA':;

SECTION_NUMBER 1
 '@SCM_LIB.SCM(SCH_1):PAGE17_I122@PURE_QUANTA.Q_CAP(CHIPS)':
 C_PATH='@scm_lib.scm(sch_1):page17_i122@pure_quanta.q_cap(chips)',
 P_PATH='@scm_lib.scm(sch_1):page17_i122@pure_quanta.q_cap(chips)',
 PATH='I122',
 DRAWING='@SCM_LIB.SCM(SCH_1):PAGE17',
 PHYS_PAGE='17',
 XY='(-1125,3875)',
 ROT='0',
 VER='1',
 PACK_TYPE='C0402',
 LOCATION='C46',
 CDS_LIB='pure_quanta',
 CDS_PART_NAME='Q_CAP_C0402-1UF,25V,10%,X6S,CHA',
 TOLERANCE='10%',
 MATERIAL='X6S',
 VOLTAGE='25V',
 VALUE='1UF',
 PRIM_FILE='W:/<user>/logical/q_cap/chips/chips.prt';

PART_NAME
 C47 'Q_CAP_C0402-1UF,25V,10%,X6S,CHA':;

SECTION_NUMBER 1
 '@SCM_LIB.SCM(SCH_1):PAGE17_I128@PURE_QUANTA.Q_CAP(CHIPS)':
 C_PATH='@scm_lib.scm(sch_1):page17_i128@pure_quanta.q_cap(chips)',
 P_PATH='@scm_lib.scm(sch_1):page17_i128@pure_quanta.q_cap(chips)',
 PATH='I128',
 DRAWING='@SCM_LIB.SCM(SCH_1):PAGE17',
 PHYS_PAGE='17',
 XY='(-1100,3000)',
 ROT='0',
 VER='1',
 PACK_TYPE='C0402',
 LOCATION='C47',
 CDS_LIB='pure_quanta',
 CDS_PART_NAME='Q_CAP_C0402-1UF,25V,10%,X6S,CHA',
 TOLERANCE='10%',
 MATERIAL='X6S',
 VOLTAGE='25V',
 VALUE='1UF',
 PRIM_FILE='W:/<user>/logical/q_cap/chips/chips.prt';

PART_NAME
 C48 'Q_CAP_C0402-1UF,25V,10%,X6S,CHA':;

SECTION_NUMBER 1
 '@SCM_LIB.SCM(SCH_1):PAGE17_I148@PURE_QUANTA.Q_CAP(CHIPS)':
 C_PATH='@scm_lib.scm(sch_1):page17_i148@pure_quanta.q_cap(chips)',
 P_PATH='@scm_lib.scm(sch_1):page17_i148@pure_quanta.q_cap(chips)',
 PATH='I148',
 DRAWING='@SCM_LIB.SCM(SCH_1):PAGE17',
 PHYS_PAGE='17',
 XY='(-1100,750)',
 ROT='0',
 VER='1',
 PACK_TYPE='C0402',
 LOCATION='C48',
 CDS_LIB='pure_quanta',
 CDS_PART_NAME='Q_CAP_C0402-1UF,25V,10%,X6S,CHA',
 TOLERANCE='10%',
 MATERIAL='X6S',
 VOLTAGE='25V',
 VALUE='1UF',
 PRIM_FILE='W:/<user>/logical/q_cap/chips/chips.prt';

PART_NAME
 C49 'Q_CAP_0402-0.1UF,25V,10%,X7R,CA':;

SECTION_NUMBER 1
 '@SCM_LIB.SCM(SCH_1):PAGE17_I118@PURE_QUANTA.Q_CAP(CHIPS)':
 C_PATH='@scm_lib.scm(sch_1):page17_i118@pure_quanta.q_cap(chips)',
 P_PATH='@scm_lib.scm(sch_1):page17_i118@pure_quanta.q_cap(chips)',
 PATH='I118',
 DRAWING='@SCM_LIB.SCM(SCH_1):PAGE17',
 PHYS_PAGE='17',
 XY='(-925,3875)',
 ROT='0',
 VER='1',
 PACK_TYPE='0402',
 LOCATION='C49',
 CDS_LIB='pure_quanta',
 CDS_PART_NAME='Q_CAP_0402-0.1UF,25V,10%,X7R,CA',
 TOLERANCE='10%',
 MATERIAL='X7R',
 VOLTAGE='25V',
 VALUE='0.1UF',
 PRIM_FILE='W:/<user>/logical/q_cap/chips/chips.prt';

PART_NAME
 C50 'Q_CAP_0402-0.1UF,25V,10%,X7R,CA':;

SECTION_NUMBER 1
 '@SCM_LIB.SCM(SCH_1):PAGE17_I126@PURE_QUANTA.Q_CAP(CHIPS)':
 C_PATH='@scm_lib.scm(sch_1):page17_i126@pure_quanta.q_cap(chips)',
 P_PATH='@scm_lib.scm(sch_1):page17_i126@pure_quanta.q_cap(chips)',
 PATH='I126',
 DRAWING='@SCM_LIB.SCM(SCH_1):PAGE17',
 PHYS_PAGE='17',
 XY='(-900,3000)',
 ROT='0',
 VER='1',
 PACK_TYPE='0402',
 LOCATION='C50',
 CDS_LIB='pure_quanta',
 CDS_PART_NAME='Q_CAP_0402-0.1UF,25V,10%,X7R,CA',
 TOLERANCE='10%',
 MATERIAL='X7R',
 VOLTAGE='25V',
 VALUE='0.1UF',
 PRIM_FILE='W:/<user>/logical/q_cap/chips/chips.prt';

PART_NAME
 C51 'Q_CAP_0402-0.1UF,25V,10%,X7R,CA':;

SECTION_NUMBER 1
 '@SCM_LIB.SCM(SCH_1):PAGE17_I145@PURE_QUANTA.Q_CAP(CHIPS)':
 C_PATH='@scm_lib.scm(sch_1):page17_i145@pure_quanta.q_cap(chips)',
 P_PATH='@scm_lib.scm(sch_1):page17_i145@pure_quanta.q_cap(chips)',
 PATH='I145',
 DRAWING='@SCM_LIB.SCM(SCH_1):PAGE17',
 PHYS_PAGE='17',
 XY='(-900,750)',
 ROT='0',
 VER='1',
 PACK_TYPE='0402',
 LOCATION='C51',
 CDS_LIB='pure_quanta',
 CDS_PART_NAME='Q_CAP_0402-0.1UF,25V,10%,X7R,CA',
 TOLERANCE='10%',
 MATERIAL='X7R',
 VOLTAGE='25V',
 VALUE='0.1UF',
 PRIM_FILE='W:/<user>/logical/q_cap/chips/chips.prt';

PART_NAME
 C52 'Q_CAP_C0402-1UF,25V,10%,X6S,CHA':;

SECTION_NUMBER 1
 '@SCM_LIB.SCM(SCH_1):PAGE16_I31@PURE_QUANTA.Q_CAP(CHIPS)':
 C_PATH='@scm_lib.scm(sch_1):page16_i31@pure_quanta.q_cap(chips)',
 P_PATH='@scm_lib.scm(sch_1):page16_i31@pure_quanta.q_cap(chips)',
 PATH='I31',
 DRAWING='@SCM_LIB.SCM(SCH_1):PAGE16',
 PHYS_PAGE='16',
 XY='(-2500,2700)',
 ROT='0',
 VER='1',
 PACK_TYPE='C0402',
 LOCATION='C52',
 CDS_LIB='pure_quanta',
 CDS_PART_NAME='Q_CAP_C0402-1UF,25V,10%,X6S,CHA',
 TOLERANCE='10%',
 MATERIAL='X6S',
 VOLTAGE='25V',
 VALUE='1UF',
 PRIM_FILE='W:/<user>/logical/q_cap/chips/chips.prt';

PART_NAME
 C53 'Q_CAP_C0402-1UF,25V,10%,X6S,CHA':;

SECTION_NUMBER 1
 '@SCM_LIB.SCM(SCH_1):PAGE17_I135@PURE_QUANTA.Q_CAP(CHIPS)':
 C_PATH='@scm_lib.scm(sch_1):page17_i135@pure_quanta.q_cap(chips)',
 P_PATH='@scm_lib.scm(sch_1):page17_i135@pure_quanta.q_cap(chips)',
 PATH='I135',
 DRAWING='@SCM_LIB.SCM(SCH_1):PAGE17',
 PHYS_PAGE='17',
 XY='(-250,1875)',
 ROT='0',
 VER='1',
 PACK_TYPE='C0402',
 LOCATION='C53',
 CDS_LIB='pure_quanta',
 CDS_PART_NAME='Q_CAP_C0402-1UF,25V,10%,X6S,CHA',
 TOLERANCE='10%',
 MATERIAL='X6S',
 VOLTAGE='25V',
 VALUE='1UF',
 PRIM_FILE='W:/<user>/logical/q_cap/chips/chips.prt';

PART_NAME
 C54 'Q_CAP_0402-0.1UF,25V,10%,X7R,CA':;

SECTION_NUMBER 1
 '@SCM_LIB.SCM(SCH_1):PAGE16_I32@PURE_QUANTA.Q_CAP(CHIPS)':
 C_PATH='@scm_lib.scm(sch_1):page16_i32@pure_quanta.q_cap(chips)',
 P_PATH='@scm_lib.scm(sch_1):page16_i32@pure_quanta.q_cap(chips)',
 PATH='I32',
 DRAWING='@SCM_LIB.SCM(SCH_1):PAGE16',
 PHYS_PAGE='16',
 XY='(-2300,2700)',
 ROT='0',
 VER='1',
 PACK_TYPE='0402',
 LOCATION='C54',
 CDS_LIB='pure_quanta',
 CDS_PART_NAME='Q_CAP_0402-0.1UF,25V,10%,X7R,CA',
 TOLERANCE='10%',
 MATERIAL='X7R',
 VOLTAGE='25V',
 VALUE='0.1UF',
 PRIM_FILE='W:/<user>/logical/q_cap/chips/chips.prt';

PART_NAME
 C55 'Q_CAP_C0603-22UF,6.3V,20%,X6S,A':;

SECTION_NUMBER 1
 '@SCM_LIB.SCM(SCH_1):PAGE16_I23@PURE_QUANTA.Q_CAP(CHIPS)':
 C_PATH='@scm_lib.scm(sch_1):page16_i23@pure_quanta.q_cap(chips)',
 P_PATH='@scm_lib.scm(sch_1):page16_i23@pure_quanta.q_cap(chips)',
 PATH='I23',
 DRAWING='@SCM_LIB.SCM(SCH_1):PAGE16',
 PHYS_PAGE='16',
 XY='(-2175,1425)',
 ROT='0',
 VER='1',
 PACK_TYPE='C0603',
 LOCATION='C55',
 CDS_LIB='pure_quanta',
 CDS_PART_NAME='Q_CAP_C0603-22UF,6.3V,20%,X6S,A',
 TOLERANCE='20%',
 MATERIAL='X6S',
 VOLTAGE='6.3V',
 VALUE='22UF',
 PRIM_FILE='W:/<user>/logical/q_cap/chips/chips.prt';

PART_NAME
 C56 'Q_CAP_C0402-1UF,25V,10%,X6S,CHA':;

SECTION_NUMBER 1
 '@SCM_LIB.SCM(SCH_1):PAGE16_I33@PURE_QUANTA.Q_CAP(CHIPS)':
 C_PATH='@scm_lib.scm(sch_1):page16_i33@pure_quanta.q_cap(chips)',
 P_PATH='@scm_lib.scm(sch_1):page16_i33@pure_quanta.q_cap(chips)',
 PATH='I33',
 DRAWING='@SCM_LIB.SCM(SCH_1):PAGE16',
 PHYS_PAGE='16',
 XY='(-2075,2700)',
 ROT='0',
 VER='1',
 PACK_TYPE='C0402',
 LOCATION='C56',
 CDS_LIB='pure_quanta',
 CDS_PART_NAME='Q_CAP_C0402-1UF,25V,10%,X6S,CHA',
 TOLERANCE='10%',
 MATERIAL='X6S',
 VOLTAGE='25V',
 VALUE='1UF',
 PRIM_FILE='W:/<user>/logical/q_cap/chips/chips.prt';

PART_NAME
 C57 'Q_CAP_0402-0.1UF,25V,10%,X7R,CA':;

SECTION_NUMBER 1
 '@SCM_LIB.SCM(SCH_1):PAGE17_I133@PURE_QUANTA.Q_CAP(CHIPS)':
 C_PATH='@scm_lib.scm(sch_1):page17_i133@pure_quanta.q_cap(chips)',
 P_PATH='@scm_lib.scm(sch_1):page17_i133@pure_quanta.q_cap(chips)',
 PATH='I133',
 DRAWING='@SCM_LIB.SCM(SCH_1):PAGE17',
 PHYS_PAGE='17',
 XY='(100,1875)',
 ROT='0',
 VER='1',
 PACK_TYPE='0402',
 LOCATION='C57',
 CDS_LIB='pure_quanta',
 CDS_PART_NAME='Q_CAP_0402-0.1UF,25V,10%,X7R,CA',
 TOLERANCE='10%',
 MATERIAL='X7R',
 VOLTAGE='25V',
 VALUE='0.1UF',
 PRIM_FILE='W:/<user>/logical/q_cap/chips/chips.prt';

PART_NAME
 C58 'Q_CAP_C0402-1UF,25V,10%,X6S,CHA':;

SECTION_NUMBER 1
 '@SCM_LIB.SCM(SCH_1):PAGE16_I52@PURE_QUANTA.Q_CAP(CHIPS)':
 C_PATH='@scm_lib.scm(sch_1):page16_i52@pure_quanta.q_cap(chips)',
 P_PATH='@scm_lib.scm(sch_1):page16_i52@pure_quanta.q_cap(chips)',
 PATH='I52',
 DRAWING='@SCM_LIB.SCM(SCH_1):PAGE16',
 PHYS_PAGE='16',
 XY='(-1975,1425)',
 ROT='0',
 VER='1',
 PACK_TYPE='C0402',
 LOCATION='C58',
 CDS_LIB='pure_quanta',
 CDS_PART_NAME='Q_CAP_C0402-1UF,25V,10%,X6S,CHA',
 TOLERANCE='10%',
 MATERIAL='X6S',
 VOLTAGE='25V',
 VALUE='1UF',
 PRIM_FILE='W:/<user>/logical/q_cap/chips/chips.prt';

PART_NAME
 C59 'Q_CAP_0402-0.1UF,25V,10%,X7R,CA':;

SECTION_NUMBER 1
 '@SCM_LIB.SCM(SCH_1):PAGE16_I79@PURE_QUANTA.Q_CAP(CHIPS)':
 C_PATH='@scm_lib.scm(sch_1):page16_i79@pure_quanta.q_cap(chips)',
 P_PATH='@scm_lib.scm(sch_1):page16_i79@pure_quanta.q_cap(chips)',
 PATH='I79',
 DRAWING='@SCM_LIB.SCM(SCH_1):PAGE16',
 PHYS_PAGE='16',
 XY='(-1875,2700)',
 ROT='0',
 VER='1',
 PACK_TYPE='0402',
 LOCATION='C59',
 CDS_LIB='pure_quanta',
 CDS_PART_NAME='Q_CAP_0402-0.1UF,25V,10%,X7R,CA',
 TOLERANCE='10%',
 MATERIAL='X7R',
 VOLTAGE='25V',
 VALUE='0.1UF',
 PRIM_FILE='W:/<user>/logical/q_cap/chips/chips.prt';

PART_NAME
 C60 'Q_CAP_C0402-1UF,25V,10%,X6S,CHA':;

SECTION_NUMBER 1
 '@SCM_LIB.SCM(SCH_1):PAGE17_I141@PURE_QUANTA.Q_CAP(CHIPS)':
 C_PATH='@scm_lib.scm(sch_1):page17_i141@pure_quanta.q_cap(chips)',
 P_PATH='@scm_lib.scm(sch_1):page17_i141@pure_quanta.q_cap(chips)',
 PATH='I141',
 DRAWING='@SCM_LIB.SCM(SCH_1):PAGE17',
 PHYS_PAGE='17',
 XY='(225,875)',
 ROT='0',
 VER='1',
 PACK_TYPE='C0402',
 LOCATION='C60',
 CDS_LIB='pure_quanta',
 CDS_PART_NAME='Q_CAP_C0402-1UF,25V,10%,X6S,CHA',
 TOLERANCE='10%',
 MATERIAL='X6S',
 VOLTAGE='25V',
 VALUE='1UF',
 PRIM_FILE='W:/<user>/logical/q_cap/chips/chips.prt';

PART_NAME
 C61 'Q_CAP_C0402-1UF,25V,10%,X6S,CHA':;

SECTION_NUMBER 1
 '@SCM_LIB.SCM(SCH_1):PAGE16_I55@PURE_QUANTA.Q_CAP(CHIPS)':
 C_PATH='@scm_lib.scm(sch_1):page16_i55@pure_quanta.q_cap(chips)',
 P_PATH='@scm_lib.scm(sch_1):page16_i55@pure_quanta.q_cap(chips)',
 PATH='I55',
 DRAWING='@SCM_LIB.SCM(SCH_1):PAGE16',
 PHYS_PAGE='16',
 XY='(-1825,2075)',
 ROT='0',
 VER='1',
 PACK_TYPE='C0402',
 LOCATION='C61',
 CDS_LIB='pure_quanta',
 CDS_PART_NAME='Q_CAP_C0402-1UF,25V,10%,X6S,CHA',
 TOLERANCE='10%',
 MATERIAL='X6S',
 VOLTAGE='25V',
 VALUE='1UF',
 PRIM_FILE='W:/<user>/logical/q_cap/chips/chips.prt';

PART_NAME
 C62 'Q_CAP_C0402-1UF,25V,10%,X6S,CHA':;

SECTION_NUMBER 1
 '@SCM_LIB.SCM(SCH_1):PAGE16_I53@PURE_QUANTA.Q_CAP(CHIPS)':
 C_PATH='@scm_lib.scm(sch_1):page16_i53@pure_quanta.q_cap(chips)',
 P_PATH='@scm_lib.scm(sch_1):page16_i53@pure_quanta.q_cap(chips)',
 PATH='I53',
 DRAWING='@SCM_LIB.SCM(SCH_1):PAGE16',
 PHYS_PAGE='16',
 XY='(-1775,1425)',
 ROT='0',
 VER='1',
 PACK_TYPE='C0402',
 LOCATION='C62',
 CDS_LIB='pure_quanta',
 CDS_PART_NAME='Q_CAP_C0402-1UF,25V,10%,X6S,CHA',
 TOLERANCE='10%',
 MATERIAL='X6S',
 VOLTAGE='25V',
 VALUE='1UF',
 PRIM_FILE='W:/<user>/logical/q_cap/chips/chips.prt';

PART_NAME
 C63 'Q_CAP_0402-2200PF,50V,10%,X7R,A':;

SECTION_NUMBER 1
 '@SCM_LIB.SCM(SCH_1):PAGE16_I46@PURE_QUANTA.Q_CAP(CHIPS)':
 C_PATH='@scm_lib.scm(sch_1):page16_i46@pure_quanta.q_cap(chips)',
 P_PATH='@scm_lib.scm(sch_1):page16_i46@pure_quanta.q_cap(chips)',
 PATH='I46',
 DRAWING='@SCM_LIB.SCM(SCH_1):PAGE16',
 PHYS_PAGE='16',
 XY='(-1725,800)',
 ROT='0',
 VER='1',
 PACK_TYPE='0402',
 LOCATION='C63',
 CDS_LIB='pure_quanta',
 CDS_PART_NAME='Q_CAP_0402-2200PF,50V,10%,X7R,A',
 TOLERANCE='10%',
 MATERIAL='X7R',
 VOLTAGE='50V',
 VALUE='2200PF',
 PRIM_FILE='W:/<user>/logical/q_cap/chips/chips.prt';

PART_NAME
 C64 'Q_CAP_C0402-1UF,25V,10%,X6S,CHA':;

SECTION_NUMBER 1
 '@SCM_LIB.SCM(SCH_1):PAGE16_I81@PURE_QUANTA.Q_CAP(CHIPS)':
 C_PATH='@scm_lib.scm(sch_1):page16_i81@pure_quanta.q_cap(chips)',
 P_PATH='@scm_lib.scm(sch_1):page16_i81@pure_quanta.q_cap(chips)',
 PATH='I81',
 DRAWING='@SCM_LIB.SCM(SCH_1):PAGE16',
 PHYS_PAGE='16',
 XY='(-1700,2700)',
 ROT='0',
 VER='1',
 PACK_TYPE='C0402',
 LOCATION='C64',
 CDS_LIB='pure_quanta',
 CDS_PART_NAME='Q_CAP_C0402-1UF,25V,10%,X6S,CHA',
 TOLERANCE='10%',
 MATERIAL='X6S',
 VOLTAGE='25V',
 VALUE='1UF',
 PRIM_FILE='W:/<user>/logical/q_cap/chips/chips.prt';

PART_NAME
 C65 'Q_CAP_0402-0.1UF,25V,10%,X7R,CA':;

SECTION_NUMBER 1
 '@SCM_LIB.SCM(SCH_1):PAGE17_I139@PURE_QUANTA.Q_CAP(CHIPS)':
 C_PATH='@scm_lib.scm(sch_1):page17_i139@pure_quanta.q_cap(chips)',
 P_PATH='@scm_lib.scm(sch_1):page17_i139@pure_quanta.q_cap(chips)',
 PATH='I139',
 DRAWING='@SCM_LIB.SCM(SCH_1):PAGE17',
 PHYS_PAGE='17',
 XY='(425,875)',
 ROT='0',
 VER='1',
 PACK_TYPE='0402',
 LOCATION='C65',
 CDS_LIB='pure_quanta',
 CDS_PART_NAME='Q_CAP_0402-0.1UF,25V,10%,X7R,CA',
 TOLERANCE='10%',
 MATERIAL='X7R',
 VOLTAGE='25V',
 VALUE='0.1UF',
 PRIM_FILE='W:/<user>/logical/q_cap/chips/chips.prt';

PART_NAME
 C66 'Q_CAP_0402-0.1UF,25V,10%,X7R,CA':;

SECTION_NUMBER 1
 '@SCM_LIB.SCM(SCH_1):PAGE16_I54@PURE_QUANTA.Q_CAP(CHIPS)':
 C_PATH='@scm_lib.scm(sch_1):page16_i54@pure_quanta.q_cap(chips)',
 P_PATH='@scm_lib.scm(sch_1):page16_i54@pure_quanta.q_cap(chips)',
 PATH='I54',
 DRAWING='@SCM_LIB.SCM(SCH_1):PAGE16',
 PHYS_PAGE='16',
 XY='(-1575,1425)',
 ROT='0',
 VER='1',
 PACK_TYPE='0402',
 LOCATION='C66',
 CDS_LIB='pure_quanta',
 CDS_PART_NAME='Q_CAP_0402-0.1UF,25V,10%,X7R,CA',
 TOLERANCE='10%',
 MATERIAL='X7R',
 VOLTAGE='25V',
 VALUE='0.1UF',
 PRIM_FILE='W:/<user>/logical/q_cap/chips/chips.prt';

PART_NAME
 C67 'Q_CAP_C0402-1UF,25V,10%,X6S,CHA':;

SECTION_NUMBER 1
 '@SCM_LIB.SCM(SCH_1):PAGE16_I48@PURE_QUANTA.Q_CAP(CHIPS)':
 C_PATH='@scm_lib.scm(sch_1):page16_i48@pure_quanta.q_cap(chips)',
 P_PATH='@scm_lib.scm(sch_1):page16_i48@pure_quanta.q_cap(chips)',
 PATH='I48',
 DRAWING='@SCM_LIB.SCM(SCH_1):PAGE16',
 PHYS_PAGE='16',
 XY='(-1525,800)',
 ROT='0',
 VER='1',
 PACK_TYPE='C0402',
 LOCATION='C67',
 CDS_LIB='pure_quanta',
 CDS_PART_NAME='Q_CAP_C0402-1UF,25V,10%,X6S,CHA',
 TOLERANCE='10%',
 MATERIAL='X6S',
 VOLTAGE='25V',
 VALUE='1UF',
 PRIM_FILE='W:/<user>/logical/q_cap/chips/chips.prt';

PART_NAME
 C68 'Q_CAP_0402-0.1UF,25V,10%,X7R,CA':;

SECTION_NUMBER 1
 '@SCM_LIB.SCM(SCH_1):PAGE16_I82@PURE_QUANTA.Q_CAP(CHIPS)':
 C_PATH='@scm_lib.scm(sch_1):page16_i82@pure_quanta.q_cap(chips)',
 P_PATH='@scm_lib.scm(sch_1):page16_i82@pure_quanta.q_cap(chips)',
 PATH='I82',
 DRAWING='@SCM_LIB.SCM(SCH_1):PAGE16',
 PHYS_PAGE='16',
 XY='(-1500,2700)',
 ROT='0',
 VER='1',
 PACK_TYPE='0402',
 LOCATION='C68',
 CDS_LIB='pure_quanta',
 CDS_PART_NAME='Q_CAP_0402-0.1UF,25V,10%,X7R,CA',
 TOLERANCE='10%',
 MATERIAL='X7R',
 VOLTAGE='25V',
 VALUE='0.1UF',
 PRIM_FILE='W:/<user>/logical/q_cap/chips/chips.prt';

PART_NAME
 C69 'Q_CAP_0402-0.1UF,25V,10%,X7R,CA':;

SECTION_NUMBER 1
 '@SCM_LIB.SCM(SCH_1):PAGE16_I59@PURE_QUANTA.Q_CAP(CHIPS)':
 C_PATH='@scm_lib.scm(sch_1):page16_i59@pure_quanta.q_cap(chips)',
 P_PATH='@scm_lib.scm(sch_1):page16_i59@pure_quanta.q_cap(chips)',
 PATH='I59',
 DRAWING='@SCM_LIB.SCM(SCH_1):PAGE16',
 PHYS_PAGE='16',
 XY='(-1400,2075)',
 ROT='0',
 VER='1',
 PACK_TYPE='0402',
 LOCATION='C69',
 CDS_LIB='pure_quanta',
 CDS_PART_NAME='Q_CAP_0402-0.1UF,25V,10%,X7R,CA',
 TOLERANCE='10%',
 MATERIAL='X7R',
 VOLTAGE='25V',
 VALUE='0.1UF',
 PRIM_FILE='W:/<user>/logical/q_cap/chips/chips.prt';

PART_NAME
 C70 'Q_CAP_0402-0.1UF,25V,10%,X7R,CA':;

SECTION_NUMBER 1
 '@SCM_LIB.SCM(SCH_1):PAGE16_I57@PURE_QUANTA.Q_CAP(CHIPS)':
 C_PATH='@scm_lib.scm(sch_1):page16_i57@pure_quanta.q_cap(chips)',
 P_PATH='@scm_lib.scm(sch_1):page16_i57@pure_quanta.q_cap(chips)',
 PATH='I57',
 DRAWING='@SCM_LIB.SCM(SCH_1):PAGE16',
 PHYS_PAGE='16',
 XY='(-1375,1425)',
 ROT='0',
 VER='1',
 PACK_TYPE='0402',
 LOCATION='C70',
 CDS_LIB='pure_quanta',
 CDS_PART_NAME='Q_CAP_0402-0.1UF,25V,10%,X7R,CA',
 TOLERANCE='10%',
 MATERIAL='X7R',
 VOLTAGE='25V',
 VALUE='0.1UF',
 PRIM_FILE='W:/<user>/logical/q_cap/chips/chips.prt';

PART_NAME
 C71 'Q_CAP_0402-0.1UF,25V,10%,X7R,CA':;

SECTION_NUMBER 1
 '@SCM_LIB.SCM(SCH_1):PAGE16_I49@PURE_QUANTA.Q_CAP(CHIPS)':
 C_PATH='@scm_lib.scm(sch_1):page16_i49@pure_quanta.q_cap(chips)',
 P_PATH='@scm_lib.scm(sch_1):page16_i49@pure_quanta.q_cap(chips)',
 PATH='I49',
 DRAWING='@SCM_LIB.SCM(SCH_1):PAGE16',
 PHYS_PAGE='16',
 XY='(-1325,800)',
 ROT='0',
 VER='1',
 PACK_TYPE='0402',
 LOCATION='C71',
 CDS_LIB='pure_quanta',
 CDS_PART_NAME='Q_CAP_0402-0.1UF,25V,10%,X7R,CA',
 TOLERANCE='10%',
 MATERIAL='X7R',
 VOLTAGE='25V',
 VALUE='0.1UF',
 PRIM_FILE='W:/<user>/logical/q_cap/chips/chips.prt';

PART_NAME
 C72 'Q_CAP_0402-0.1UF,25V,10%,X7R,CA':;

SECTION_NUMBER 1
 '@SCM_LIB.SCM(SCH_1):PAGE16_I58@PURE_QUANTA.Q_CAP(CHIPS)':
 C_PATH='@scm_lib.scm(sch_1):page16_i58@pure_quanta.q_cap(chips)',
 P_PATH='@scm_lib.scm(sch_1):page16_i58@pure_quanta.q_cap(chips)',
 PATH='I58',
 DRAWING='@SCM_LIB.SCM(SCH_1):PAGE16',
 PHYS_PAGE='16',
 XY='(-1175,1425)',
 ROT='0',
 VER='1',
 PACK_TYPE='0402',
 LOCATION='C72',
 CDS_LIB='pure_quanta',
 CDS_PART_NAME='Q_CAP_0402-0.1UF,25V,10%,X7R,CA',
 TOLERANCE='10%',
 MATERIAL='X7R',
 VOLTAGE='25V',
 VALUE='0.1UF',
 PRIM_FILE='W:/<user>/logical/q_cap/chips/chips.prt';

PART_NAME
 C73 'Q_CAP_0402-0.1UF,25V,10%,X7R,CA':;

SECTION_NUMBER 1
 '@SCM_LIB.SCM(SCH_1):PAGE16_I51@PURE_QUANTA.Q_CAP(CHIPS)':
 C_PATH='@scm_lib.scm(sch_1):page16_i51@pure_quanta.q_cap(chips)',
 P_PATH='@scm_lib.scm(sch_1):page16_i51@pure_quanta.q_cap(chips)',
 PATH='I51',
 DRAWING='@SCM_LIB.SCM(SCH_1):PAGE16',
 PHYS_PAGE='16',
 XY='(-1125,800)',
 ROT='0',
 VER='1',
 PACK_TYPE='0402',
 LOCATION='C73',
 CDS_LIB='pure_quanta',
 CDS_PART_NAME='Q_CAP_0402-0.1UF,25V,10%,X7R,CA',
 TOLERANCE='10%',
 MATERIAL='X7R',
 VOLTAGE='25V',
 VALUE='0.1UF',
 PRIM_FILE='W:/<user>/logical/q_cap/chips/chips.prt';

PART_NAME
 C74 'Q_CAP_0402-0.1UF,25V,10%,X7R,CA':;

SECTION_NUMBER 1
 '@SCM_LIB.SCM(SCH_1):PAGE16_I66@PURE_QUANTA.Q_CAP(CHIPS)':
 C_PATH='@scm_lib.scm(sch_1):page16_i66@pure_quanta.q_cap(chips)',
 P_PATH='@scm_lib.scm(sch_1):page16_i66@pure_quanta.q_cap(chips)',
 PATH='I66',
 DRAWING='@SCM_LIB.SCM(SCH_1):PAGE16',
 PHYS_PAGE='16',
 XY='(-975,1425)',
 ROT='0',
 VER='1',
 PACK_TYPE='0402',
 LOCATION='C74',
 CDS_LIB='pure_quanta',
 CDS_PART_NAME='Q_CAP_0402-0.1UF,25V,10%,X7R,CA',
 TOLERANCE='10%',
 MATERIAL='X7R',
 VOLTAGE='25V',
 VALUE='0.1UF',
 PRIM_FILE='W:/<user>/logical/q_cap/chips/chips.prt';

PART_NAME
 C75 'Q_CAP_C0402-1UF,25V,10%,X6S,CHA':;

SECTION_NUMBER 1
 '@SCM_LIB.SCM(SCH_1):PAGE16_I93@PURE_QUANTA.Q_CAP(CHIPS)':
 C_PATH='@scm_lib.scm(sch_1):page16_i93@pure_quanta.q_cap(chips)',
 P_PATH='@scm_lib.scm(sch_1):page16_i93@pure_quanta.q_cap(chips)',
 PATH='I93',
 DRAWING='@SCM_LIB.SCM(SCH_1):PAGE16',
 PHYS_PAGE='16',
 XY='(-900,4400)',
 ROT='0',
 VER='1',
 PACK_TYPE='C0402',
 LOCATION='C75',
 CDS_LIB='pure_quanta',
 CDS_PART_NAME='Q_CAP_C0402-1UF,25V,10%,X6S,CHA',
 TOLERANCE='10%',
 MATERIAL='X6S',
 VOLTAGE='25V',
 VALUE='1UF',
 PRIM_FILE='W:/<user>/logical/q_cap/chips/chips.prt';

PART_NAME
 C76 'Q_CAP_0402-0.1UF,25V,10%,X7R,CA':;

SECTION_NUMBER 1
 '@SCM_LIB.SCM(SCH_1):PAGE16_I183@PURE_QUANTA.Q_CAP(CHIPS)':
 C_PATH='@scm_lib.scm(sch_1):page16_i183@pure_quanta.q_cap(chips)',
 P_PATH='@scm_lib.scm(sch_1):page16_i183@pure_quanta.q_cap(chips)',
 PATH='I183',
 DRAWING='@SCM_LIB.SCM(SCH_1):PAGE16',
 PHYS_PAGE='16',
 XY='(-775,1425)',
 ROT='0',
 VER='1',
 PACK_TYPE='0402',
 LOCATION='C76',
 CDS_LIB='pure_quanta',
 CDS_PART_NAME='Q_CAP_0402-0.1UF,25V,10%,X7R,CA',
 TOLERANCE='10%',
 MATERIAL='X7R',
 VOLTAGE='25V',
 VALUE='0.1UF',
 PRIM_FILE='W:/<user>/logical/q_cap/chips/chips.prt';

PART_NAME
 C77 'Q_CAP_0402-0.1UF,25V,10%,X7R,CA':;

SECTION_NUMBER 1
 '@SCM_LIB.SCM(SCH_1):PAGE16_I100@PURE_QUANTA.Q_CAP(CHIPS)':
 C_PATH='@scm_lib.scm(sch_1):page16_i100@pure_quanta.q_cap(chips)',
 P_PATH='@scm_lib.scm(sch_1):page16_i100@pure_quanta.q_cap(chips)',
 PATH='I100',
 DRAWING='@SCM_LIB.SCM(SCH_1):PAGE16',
 PHYS_PAGE='16',
 XY='(-425,4425)',
 ROT='0',
 VER='1',
 PACK_TYPE='0402',
 LOCATION='C77',
 CDS_LIB='pure_quanta',
 CDS_PART_NAME='Q_CAP_0402-0.1UF,25V,10%,X7R,CA',
 TOLERANCE='10%',
 MATERIAL='X7R',
 VOLTAGE='25V',
 VALUE='0.1UF',
 PRIM_FILE='W:/<user>/logical/q_cap/chips/chips.prt';

PART_NAME
 C78 'Q_CAP_C0402-1UF,25V,10%,X6S,CHA':;

SECTION_NUMBER 1
 '@SCM_LIB.SCM(SCH_1):PAGE17_I160@PURE_QUANTA.Q_CAP(CHIPS)':
 C_PATH='@scm_lib.scm(sch_1):page17_i160@pure_quanta.q_cap(chips)',
 P_PATH='@scm_lib.scm(sch_1):page17_i160@pure_quanta.q_cap(chips)',
 PATH='I160',
 DRAWING='@SCM_LIB.SCM(SCH_1):PAGE17',
 PHYS_PAGE='17',
 XY='(-1175,-300)',
 ROT='0',
 VER='1',
 PACK_TYPE='C0402',
 LOCATION='C78',
 CDS_LIB='pure_quanta',
 CDS_PART_NAME='Q_CAP_C0402-1UF,25V,10%,X6S,CHA',
 TOLERANCE='10%',
 MATERIAL='X6S',
 VOLTAGE='25V',
 VALUE='1UF',
 PRIM_FILE='W:/<user>/logical/q_cap/chips/chips.prt';

PART_NAME
 C79 'Q_CAP_0402-0.1UF,25V,10%,X7R,CA':;

SECTION_NUMBER 1
 '@SCM_LIB.SCM(SCH_1):PAGE17_I157@PURE_QUANTA.Q_CAP(CHIPS)':
 C_PATH='@scm_lib.scm(sch_1):page17_i157@pure_quanta.q_cap(chips)',
 P_PATH='@scm_lib.scm(sch_1):page17_i157@pure_quanta.q_cap(chips)',
 PATH='I157',
 DRAWING='@SCM_LIB.SCM(SCH_1):PAGE17',
 PHYS_PAGE='17',
 XY='(-975,-300)',
 ROT='0',
 VER='1',
 PACK_TYPE='0402',
 LOCATION='C79',
 CDS_LIB='pure_quanta',
 CDS_PART_NAME='Q_CAP_0402-0.1UF,25V,10%,X7R,CA',
 TOLERANCE='10%',
 MATERIAL='X7R',
 VOLTAGE='25V',
 VALUE='0.1UF',
 PRIM_FILE='W:/<user>/logical/q_cap/chips/chips.prt';

PART_NAME
 C80 'Q_CAP_C0402-1UF,25V,10%,X6S,CHA':;

SECTION_NUMBER 1
 '@SCM_LIB.SCM(SCH_1):PAGE17_I153@PURE_QUANTA.Q_CAP(CHIPS)':
 C_PATH='@scm_lib.scm(sch_1):page17_i153@pure_quanta.q_cap(chips)',
 P_PATH='@scm_lib.scm(sch_1):page17_i153@pure_quanta.q_cap(chips)',
 PATH='I153',
 DRAWING='@SCM_LIB.SCM(SCH_1):PAGE17',
 PHYS_PAGE='17',
 XY='(150,-250)',
 ROT='0',
 VER='1',
 PACK_TYPE='C0402',
 LOCATION='C80',
 CDS_LIB='pure_quanta',
 CDS_PART_NAME='Q_CAP_C0402-1UF,25V,10%,X6S,CHA',
 TOLERANCE='10%',
 MATERIAL='X6S',
 VOLTAGE='25V',
 VALUE='1UF',
 PRIM_FILE='W:/<user>/logical/q_cap/chips/chips.prt';

PART_NAME
 C81 'Q_CAP_0402-0.1UF,25V,10%,X7R,CA':;

SECTION_NUMBER 1
 '@SCM_LIB.SCM(SCH_1):PAGE17_I151@PURE_QUANTA.Q_CAP(CHIPS)':
 C_PATH='@scm_lib.scm(sch_1):page17_i151@pure_quanta.q_cap(chips)',
 P_PATH='@scm_lib.scm(sch_1):page17_i151@pure_quanta.q_cap(chips)',
 PATH='I151',
 DRAWING='@SCM_LIB.SCM(SCH_1):PAGE17',
 PHYS_PAGE='17',
 XY='(350,-250)',
 ROT='0',
 VER='1',
 PACK_TYPE='0402',
 LOCATION='C81',
 CDS_LIB='pure_quanta',
 CDS_PART_NAME='Q_CAP_0402-0.1UF,25V,10%,X7R,CA',
 TOLERANCE='10%',
 MATERIAL='X7R',
 VOLTAGE='25V',
 VALUE='0.1UF',
 PRIM_FILE='W:/<user>/logical/q_cap/chips/chips.prt';

PART_NAME
 C82 'Q_CAP_0402-0.1UF,25V,10%,X7R,CA':;

SECTION_NUMBER 1
 '@SCM_LIB.SCM(SCH_1):PAGE16_I180@PURE_QUANTA.Q_CAP(CHIPS)':
 C_PATH='@scm_lib.scm(sch_1):page16_i180@pure_quanta.q_cap(chips)',
 P_PATH='@scm_lib.scm(sch_1):page16_i180@pure_quanta.q_cap(chips)',
 PATH='I180',
 DRAWING='@SCM_LIB.SCM(SCH_1):PAGE16',
 PHYS_PAGE='16',
 XY='(2600,3825)',
 ROT='0',
 VER='1',
 PACK_TYPE='0402',
 LOCATION='C82',
 CDS_LIB='pure_quanta',
 CDS_PART_NAME='Q_CAP_0402-0.1UF,25V,10%,X7R,CA',
 TOLERANCE='10%',
 MATERIAL='X7R',
 VOLTAGE='25V',
 VALUE='0.1UF',
 PRIM_FILE='W:/<user>/logical/q_cap/chips/chips.prt';

PART_NAME
 C83 'Q_CAP_0402-0.1UF,25V,10%,X7R,CA':;

SECTION_NUMBER 1
 '@SCM_LIB.SCM(SCH_1):PAGE16_I106@PURE_QUANTA.Q_CAP(CHIPS)':
 C_PATH='@scm_lib.scm(sch_1):page16_i106@pure_quanta.q_cap(chips)',
 P_PATH='@scm_lib.scm(sch_1):page16_i106@pure_quanta.q_cap(chips)',
 PATH='I106',
 DRAWING='@SCM_LIB.SCM(SCH_1):PAGE16',
 PHYS_PAGE='16',
 XY='(2625,-50)',
 ROT='0',
 VER='1',
 PACK_TYPE='0402',
 LOCATION='C83',
 CDS_LIB='pure_quanta',
 CDS_PART_NAME='Q_CAP_0402-0.1UF,25V,10%,X7R,CA',
 TOLERANCE='10%',
 MATERIAL='X7R',
 VOLTAGE='25V',
 VALUE='0.1UF',
 PRIM_FILE='W:/<user>/logical/q_cap/chips/chips.prt';

PART_NAME
 C84 'Q_CAP_0402-0.1UF,25V,10%,X7R,CA':;

SECTION_NUMBER 1
 '@SCM_LIB.SCM(SCH_1):PAGE16_I179@PURE_QUANTA.Q_CAP(CHIPS)':
 C_PATH='@scm_lib.scm(sch_1):page16_i179@pure_quanta.q_cap(chips)',
 P_PATH='@scm_lib.scm(sch_1):page16_i179@pure_quanta.q_cap(chips)',
 PATH='I179',
 DRAWING='@SCM_LIB.SCM(SCH_1):PAGE16',
 PHYS_PAGE='16',
 XY='(2775,3825)',
 ROT='0',
 VER='1',
 PACK_TYPE='0402',
 LOCATION='C84',
 CDS_LIB='pure_quanta',
 CDS_PART_NAME='Q_CAP_0402-0.1UF,25V,10%,X7R,CA',
 TOLERANCE='10%',
 MATERIAL='X7R',
 VOLTAGE='25V',
 VALUE='0.1UF',
 PRIM_FILE='W:/<user>/logical/q_cap/chips/chips.prt';

PART_NAME
 C85 'Q_CAP_0402-0.1UF,25V,10%,X7R,CA':;

SECTION_NUMBER 1
 '@SCM_LIB.SCM(SCH_1):PAGE16_I120@PURE_QUANTA.Q_CAP(CHIPS)':
 C_PATH='@scm_lib.scm(sch_1):page16_i120@pure_quanta.q_cap(chips)',
 P_PATH='@scm_lib.scm(sch_1):page16_i120@pure_quanta.q_cap(chips)',
 PATH='I120',
 DRAWING='@SCM_LIB.SCM(SCH_1):PAGE16',
 PHYS_PAGE='16',
 XY='(2775,1275)',
 ROT='0',
 VER='1',
 PACK_TYPE='0402',
 LOCATION='C85',
 CDS_LIB='pure_quanta',
 CDS_PART_NAME='Q_CAP_0402-0.1UF,25V,10%,X7R,CA',
 TOLERANCE='10%',
 MATERIAL='X7R',
 VOLTAGE='25V',
 VALUE='0.1UF',
 PRIM_FILE='W:/<user>/logical/q_cap/chips/chips.prt';

PART_NAME
 C86 'Q_CAP_0402-0.1UF,25V,10%,X7R,CA':;

SECTION_NUMBER 1
 '@SCM_LIB.SCM(SCH_1):PAGE16_I149@PURE_QUANTA.Q_CAP(CHIPS)':
 C_PATH='@scm_lib.scm(sch_1):page16_i149@pure_quanta.q_cap(chips)',
 P_PATH='@scm_lib.scm(sch_1):page16_i149@pure_quanta.q_cap(chips)',
 PATH='I149',
 DRAWING='@SCM_LIB.SCM(SCH_1):PAGE16',
 PHYS_PAGE='16',
 XY='(2825,3200)',
 ROT='0',
 VER='1',
 PACK_TYPE='0402',
 LOCATION='C86',
 CDS_LIB='pure_quanta',
 CDS_PART_NAME='Q_CAP_0402-0.1UF,25V,10%,X7R,CA',
 TOLERANCE='10%',
 MATERIAL='X7R',
 VOLTAGE='25V',
 VALUE='0.1UF',
 PRIM_FILE='W:/<user>/logical/q_cap/chips/chips.prt';

PART_NAME
 C87 'Q_CAP_0402-0.1UF,25V,10%,X7R,CA':;

SECTION_NUMBER 1
 '@SCM_LIB.SCM(SCH_1):PAGE16_I147@PURE_QUANTA.Q_CAP(CHIPS)':
 C_PATH='@scm_lib.scm(sch_1):page16_i147@pure_quanta.q_cap(chips)',
 P_PATH='@scm_lib.scm(sch_1):page16_i147@pure_quanta.q_cap(chips)',
 PATH='I147',
 DRAWING='@SCM_LIB.SCM(SCH_1):PAGE16',
 PHYS_PAGE='16',
 XY='(2825,2500)',
 ROT='0',
 VER='1',
 PACK_TYPE='0402',
 LOCATION='C87',
 CDS_LIB='pure_quanta',
 CDS_PART_NAME='Q_CAP_0402-0.1UF,25V,10%,X7R,CA',
 TOLERANCE='10%',
 MATERIAL='X7R',
 VOLTAGE='25V',
 VALUE='0.1UF',
 PRIM_FILE='W:/<user>/logical/q_cap/chips/chips.prt';

PART_NAME
 C88 'Q_CAP_0402-0.1UF,25V,10%,X7R,CA':;

SECTION_NUMBER 1
 '@SCM_LIB.SCM(SCH_1):PAGE16_I123@PURE_QUANTA.Q_CAP(CHIPS)':
 C_PATH='@scm_lib.scm(sch_1):page16_i123@pure_quanta.q_cap(chips)',
 P_PATH='@scm_lib.scm(sch_1):page16_i123@pure_quanta.q_cap(chips)',
 PATH='I123',
 DRAWING='@SCM_LIB.SCM(SCH_1):PAGE16',
 PHYS_PAGE='16',
 XY='(2825,1875)',
 ROT='0',
 VER='1',
 PACK_TYPE='0402',
 LOCATION='C88',
 CDS_LIB='pure_quanta',
 CDS_PART_NAME='Q_CAP_0402-0.1UF,25V,10%,X7R,CA',
 TOLERANCE='10%',
 MATERIAL='X7R',
 VOLTAGE='25V',
 VALUE='0.1UF',
 PRIM_FILE='W:/<user>/logical/q_cap/chips/chips.prt';

PART_NAME
 C89 'Q_CAP_0402-0.1UF,25V,10%,X7R,CA':;

SECTION_NUMBER 1
 '@SCM_LIB.SCM(SCH_1):PAGE16_I118@PURE_QUANTA.Q_CAP(CHIPS)':
 C_PATH='@scm_lib.scm(sch_1):page16_i118@pure_quanta.q_cap(chips)',
 P_PATH='@scm_lib.scm(sch_1):page16_i118@pure_quanta.q_cap(chips)',
 PATH='I118',
 DRAWING='@SCM_LIB.SCM(SCH_1):PAGE16',
 PHYS_PAGE='16',
 XY='(2850,725)',
 ROT='0',
 VER='1',
 PACK_TYPE='0402',
 CDS_LIB='pure_quanta',
 CDS_PART_NAME='Q_CAP_0402-0.1UF,25V,10%,X7R,CA',
 TOLERANCE='10%',
 MATERIAL='X7R',
 VOLTAGE='25V',
 VALUE='0.1UF',
 PRIM_FILE='W:/<user>/logical/q_cap/chips/chips.prt';

PART_NAME
 C90 'Q_CAP_C0402-1UF,25V,10%,X6S,CHA':;

SECTION_NUMBER 1
 '@SCM_LIB.SCM(SCH_1):PAGE17_I173@PURE_QUANTA.Q_CAP(CHIPS)':
 C_PATH='@scm_lib.scm(sch_1):page17_i173@pure_quanta.q_cap(chips)',
 P_PATH='@scm_lib.scm(sch_1):page17_i173@pure_quanta.q_cap(chips)',
 PATH='I173',
 DRAWING='@SCM_LIB.SCM(SCH_1):PAGE17',
 PHYS_PAGE='17',
 XY='(2050,1950)',
 ROT='0',
 VER='1',
 PACK_TYPE='C0402',
 LOCATION='C90',
 CDS_LIB='pure_quanta',
 CDS_PART_NAME='Q_CAP_C0402-1UF,25V,10%,X6S,CHA',
 TOLERANCE='10%',
 MATERIAL='X6S',
 VOLTAGE='25V',
 VALUE='1UF',
 PRIM_FILE='W:/<user>/logical/q_cap/chips/chips.prt';

PART_NAME
 C91 'Q_CAP_0402-0.1UF,25V,10%,X7R,CA':;

SECTION_NUMBER 1
 '@SCM_LIB.SCM(SCH_1):PAGE16_I151@PURE_QUANTA.Q_CAP(CHIPS)':
 C_PATH='@scm_lib.scm(sch_1):page16_i151@pure_quanta.q_cap(chips)',
 P_PATH='@scm_lib.scm(sch_1):page16_i151@pure_quanta.q_cap(chips)',
 PATH='I151',
 DRAWING='@SCM_LIB.SCM(SCH_1):PAGE16',
 PHYS_PAGE='16',
 XY='(2950,3825)',
 ROT='0',
 VER='1',
 PACK_TYPE='0402',
 LOCATION='C91',
 CDS_LIB='pure_quanta',
 CDS_PART_NAME='Q_CAP_0402-0.1UF,25V,10%,X7R,CA',
 TOLERANCE='10%',
 MATERIAL='X7R',
 VOLTAGE='25V',
 VALUE='0.1UF',
 PRIM_FILE='W:/<user>/logical/q_cap/chips/chips.prt';

PART_NAME
 C92 'Q_CAP_0402-0.1UF,25V,10%,X7R,CA':;

SECTION_NUMBER 1
 '@SCM_LIB.SCM(SCH_1):PAGE16_I150@PURE_QUANTA.Q_CAP(CHIPS)':
 C_PATH='@scm_lib.scm(sch_1):page16_i150@pure_quanta.q_cap(chips)',
 P_PATH='@scm_lib.scm(sch_1):page16_i150@pure_quanta.q_cap(chips)',
 PATH='I150',
 DRAWING='@SCM_LIB.SCM(SCH_1):PAGE16',
 PHYS_PAGE='16',
 XY='(3025,3200)',
 ROT='0',
 VER='1',
 PACK_TYPE='0402',
 LOCATION='C92',
 CDS_LIB='pure_quanta',
 CDS_PART_NAME='Q_CAP_0402-0.1UF,25V,10%,X7R,CA',
 TOLERANCE='10%',
 MATERIAL='X7R',
 VOLTAGE='25V',
 VALUE='0.1UF',
 PRIM_FILE='W:/<user>/logical/q_cap/chips/chips.prt';

PART_NAME
 C93 'Q_CAP_0402-0.1UF,25V,10%,X7R,CA':;

SECTION_NUMBER 1
 '@SCM_LIB.SCM(SCH_1):PAGE16_I148@PURE_QUANTA.Q_CAP(CHIPS)':
 C_PATH='@scm_lib.scm(sch_1):page16_i148@pure_quanta.q_cap(chips)',
 P_PATH='@scm_lib.scm(sch_1):page16_i148@pure_quanta.q_cap(chips)',
 PATH='I148',
 DRAWING='@SCM_LIB.SCM(SCH_1):PAGE16',
 PHYS_PAGE='16',
 XY='(3025,2500)',
 ROT='0',
 VER='1',
 PACK_TYPE='0402',
 LOCATION='C93',
 CDS_LIB='pure_quanta',
 CDS_PART_NAME='Q_CAP_0402-0.1UF,25V,10%,X7R,CA',
 TOLERANCE='10%',
 MATERIAL='X7R',
 VOLTAGE='25V',
 VALUE='0.1UF',
 PRIM_FILE='W:/<user>/logical/q_cap/chips/chips.prt';

PART_NAME
 C94 'Q_CAP_0402-0.1UF,25V,10%,X7R,CA':;

SECTION_NUMBER 1
 '@SCM_LIB.SCM(SCH_1):PAGE16_I124@PURE_QUANTA.Q_CAP(CHIPS)':
 C_PATH='@scm_lib.scm(sch_1):page16_i124@pure_quanta.q_cap(chips)',
 P_PATH='@scm_lib.scm(sch_1):page16_i124@pure_quanta.q_cap(chips)',
 PATH='I124',
 DRAWING='@SCM_LIB.SCM(SCH_1):PAGE16',
 PHYS_PAGE='16',
 XY='(3025,1875)',
 ROT='0',
 VER='1',
 PACK_TYPE='0402',
 LOCATION='C94',
 CDS_LIB='pure_quanta',
 CDS_PART_NAME='Q_CAP_0402-0.1UF,25V,10%,X7R,CA',
 TOLERANCE='10%',
 MATERIAL='X7R',
 VOLTAGE='25V',
 VALUE='0.1UF',
 PRIM_FILE='W:/<user>/logical/q_cap/chips/chips.prt';

PART_NAME
 C95 'Q_CAP_0402-0.1UF,25V,10%,X7R,CA':;

SECTION_NUMBER 1
 '@SCM_LIB.SCM(SCH_1):PAGE16_I119@PURE_QUANTA.Q_CAP(CHIPS)':
 C_PATH='@scm_lib.scm(sch_1):page16_i119@pure_quanta.q_cap(chips)',
 P_PATH='@scm_lib.scm(sch_1):page16_i119@pure_quanta.q_cap(chips)',
 PATH='I119',
 DRAWING='@SCM_LIB.SCM(SCH_1):PAGE16',
 PHYS_PAGE='16',
 XY='(3050,725)',
 ROT='0',
 VER='1',
 PACK_TYPE='0402',
 LOCATION='C95',
 CDS_LIB='pure_quanta',
 CDS_PART_NAME='Q_CAP_0402-0.1UF,25V,10%,X7R,CA',
 TOLERANCE='10%',
 MATERIAL='X7R',
 VOLTAGE='25V',
 VALUE='0.1UF',
 PRIM_FILE='W:/<user>/logical/q_cap/chips/chips.prt';

PART_NAME
 C96 'Q_CAP_0402-0.1UF,25V,10%,X7R,CA':;

SECTION_NUMBER 1
 '@SCM_LIB.SCM(SCH_1):PAGE17_I178@PURE_QUANTA.Q_CAP(CHIPS)':
 C_PATH='@scm_lib.scm(sch_1):page17_i178@pure_quanta.q_cap(chips)',
 P_PATH='@scm_lib.scm(sch_1):page17_i178@pure_quanta.q_cap(chips)',
 PATH='I178',
 DRAWING='@SCM_LIB.SCM(SCH_1):PAGE17',
 PHYS_PAGE='17',
 XY='(2050,250)',
 ROT='0',
 VER='1',
 PACK_TYPE='0402',
 LOCATION='C96',
 CDS_LIB='pure_quanta',
 CDS_PART_NAME='Q_CAP_0402-0.1UF,25V,10%,X7R,CA',
 TOLERANCE='10%',
 MATERIAL='X7R',
 VOLTAGE='25V',
 VALUE='0.1UF',
 PRIM_FILE='W:/<user>/logical/q_cap/chips/chips.prt';

PART_NAME
 C97 'Q_CAP_0402-0.1UF,25V,10%,X7R,CA':;

SECTION_NUMBER 1
 '@SCM_LIB.SCM(SCH_1):PAGE17_I169@PURE_QUANTA.Q_CAP(CHIPS)':
 C_PATH='@scm_lib.scm(sch_1):page17_i169@pure_quanta.q_cap(chips)',
 P_PATH='@scm_lib.scm(sch_1):page17_i169@pure_quanta.q_cap(chips)',
 PATH='I169',
 DRAWING='@SCM_LIB.SCM(SCH_1):PAGE17',
 PHYS_PAGE='17',
 XY='(2250,1950)',
 ROT='0',
 VER='1',
 PACK_TYPE='0402',
 LOCATION='C97',
 CDS_LIB='pure_quanta',
 CDS_PART_NAME='Q_CAP_0402-0.1UF,25V,10%,X7R,CA',
 TOLERANCE='10%',
 MATERIAL='X7R',
 VOLTAGE='25V',
 VALUE='0.1UF',
 PRIM_FILE='W:/<user>/logical/q_cap/chips/chips.prt';

PART_NAME
 C98 'Q_CAP_0402-0.1UF,25V,10%,X7R,CA':;

SECTION_NUMBER 1
 '@SCM_LIB.SCM(SCH_1):PAGE16_I163@PURE_QUANTA.Q_CAP(CHIPS)':
 C_PATH='@scm_lib.scm(sch_1):page16_i163@pure_quanta.q_cap(chips)',
 P_PATH='@scm_lib.scm(sch_1):page16_i163@pure_quanta.q_cap(chips)',
 PATH='I163',
 DRAWING='@SCM_LIB.SCM(SCH_1):PAGE16',
 PHYS_PAGE='16',
 XY='(3150,3825)',
 ROT='0',
 VER='1',
 PACK_TYPE='0402',
 LOCATION='C98',
 CDS_LIB='pure_quanta',
 CDS_PART_NAME='Q_CAP_0402-0.1UF,25V,10%,X7R,CA',
 TOLERANCE='10%',
 MATERIAL='X7R',
 VOLTAGE='25V',
 VALUE='0.1UF',
 PRIM_FILE='W:/<user>/logical/q_cap/chips/chips.prt';

PART_NAME
 C99 'Q_CAP_0402-0.1UF,25V,10%,X7R,CA':;

SECTION_NUMBER 1
 '@SCM_LIB.SCM(SCH_1):PAGE16_I154@PURE_QUANTA.Q_CAP(CHIPS)':
 C_PATH='@scm_lib.scm(sch_1):page16_i154@pure_quanta.q_cap(chips)',
 P_PATH='@scm_lib.scm(sch_1):page16_i154@pure_quanta.q_cap(chips)',
 PATH='I154',
 DRAWING='@SCM_LIB.SCM(SCH_1):PAGE16',
 PHYS_PAGE='16',
 XY='(3225,3200)',
 ROT='0',
 VER='1',
 PACK_TYPE='0402',
 LOCATION='C99',
 CDS_LIB='pure_quanta',
 CDS_PART_NAME='Q_CAP_0402-0.1UF,25V,10%,X7R,CA',
 TOLERANCE='10%',
 MATERIAL='X7R',
 VOLTAGE='25V',
 VALUE='0.1UF',
 PRIM_FILE='W:/<user>/logical/q_cap/chips/chips.prt';

PART_NAME
 C100 'Q_CAP_0402-0.1UF,25V,10%,X7R,CA':;

SECTION_NUMBER 1
 '@SCM_LIB.SCM(SCH_1):PAGE16_I152@PURE_QUANTA.Q_CAP(CHIPS)':
 C_PATH='@scm_lib.scm(sch_1):page16_i152@pure_quanta.q_cap(chips)',
 P_PATH='@scm_lib.scm(sch_1):page16_i152@pure_quanta.q_cap(chips)',
 PATH='I152',
 DRAWING='@SCM_LIB.SCM(SCH_1):PAGE16',
 PHYS_PAGE='16',
 XY='(3225,2500)',
 ROT='0',
 VER='1',
 PACK_TYPE='0402',
 LOCATION='C100',
 CDS_LIB='pure_quanta',
 CDS_PART_NAME='Q_CAP_0402-0.1UF,25V,10%,X7R,CA',
 TOLERANCE='10%',
 MATERIAL='X7R',
 VOLTAGE='25V',
 VALUE='0.1UF',
 PRIM_FILE='W:/<user>/logical/q_cap/chips/chips.prt';

PART_NAME
 C101 'Q_CAP_0402-0.1UF,25V,10%,X7R,CA':;

SECTION_NUMBER 1
 '@SCM_LIB.SCM(SCH_1):PAGE16_I132@PURE_QUANTA.Q_CAP(CHIPS)':
 C_PATH='@scm_lib.scm(sch_1):page16_i132@pure_quanta.q_cap(chips)',
 P_PATH='@scm_lib.scm(sch_1):page16_i132@pure_quanta.q_cap(chips)',
 PATH='I132',
 DRAWING='@SCM_LIB.SCM(SCH_1):PAGE16',
 PHYS_PAGE='16',
 XY='(3225,1875)',
 ROT='0',
 VER='1',
 PACK_TYPE='0402',
 LOCATION='C101',
 CDS_LIB='pure_quanta',
 CDS_PART_NAME='Q_CAP_0402-0.1UF,25V,10%,X7R,CA',
 TOLERANCE='10%',
 MATERIAL='X7R',
 VOLTAGE='25V',
 VALUE='0.1UF',
 PRIM_FILE='W:/<user>/logical/q_cap/chips/chips.prt';

PART_NAME
 C102 'Q_CAP_0402-0.1UF,25V,10%,X7R,CA':;

SECTION_NUMBER 1
 '@SCM_LIB.SCM(SCH_1):PAGE16_I126@PURE_QUANTA.Q_CAP(CHIPS)':
 C_PATH='@scm_lib.scm(sch_1):page16_i126@pure_quanta.q_cap(chips)',
 P_PATH='@scm_lib.scm(sch_1):page16_i126@pure_quanta.q_cap(chips)',
 PATH='I126',
 DRAWING='@SCM_LIB.SCM(SCH_1):PAGE16',
 PHYS_PAGE='16',
 XY='(3250,725)',
 ROT='0',
 VER='1',
 PACK_TYPE='0402',
 LOCATION='C102',
 CDS_LIB='pure_quanta',
 CDS_PART_NAME='Q_CAP_0402-0.1UF,25V,10%,X7R,CA',
 TOLERANCE='10%',
 MATERIAL='X7R',
 VOLTAGE='25V',
 VALUE='0.1UF',
 PRIM_FILE='W:/<user>/logical/q_cap/chips/chips.prt';

PART_NAME
 C103 'Q_CAP_0402-0.1UF,25V,10%,X7R,CA':;

SECTION_NUMBER 1
 '@SCM_LIB.SCM(SCH_1):PAGE16_I164@PURE_QUANTA.Q_CAP(CHIPS)':
 C_PATH='@scm_lib.scm(sch_1):page16_i164@pure_quanta.q_cap(chips)',
 P_PATH='@scm_lib.scm(sch_1):page16_i164@pure_quanta.q_cap(chips)',
 PATH='I164',
 DRAWING='@SCM_LIB.SCM(SCH_1):PAGE16',
 PHYS_PAGE='16',
 XY='(3325,3825)',
 ROT='0',
 VER='1',
 PACK_TYPE='0402',
 LOCATION='C103',
 CDS_LIB='pure_quanta',
 CDS_PART_NAME='Q_CAP_0402-0.1UF,25V,10%,X7R,CA',
 TOLERANCE='10%',
 MATERIAL='X7R',
 VOLTAGE='25V',
 VALUE='0.1UF',
 PRIM_FILE='W:/<user>/logical/q_cap/chips/chips.prt';

PART_NAME
 C104 'Q_CAP_C0402-1UF,25V,10%,X6S,CHA':;

SECTION_NUMBER 1
 '@SCM_LIB.SCM(SCH_1):PAGE16_I155@PURE_QUANTA.Q_CAP(CHIPS)':
 C_PATH='@scm_lib.scm(sch_1):page16_i155@pure_quanta.q_cap(chips)',
 P_PATH='@scm_lib.scm(sch_1):page16_i155@pure_quanta.q_cap(chips)',
 PATH='I155',
 DRAWING='@SCM_LIB.SCM(SCH_1):PAGE16',
 PHYS_PAGE='16',
 XY='(3400,3200)',
 ROT='0',
 VER='1',
 PACK_TYPE='C0402',
 LOCATION='C104',
 CDS_LIB='pure_quanta',
 CDS_PART_NAME='Q_CAP_C0402-1UF,25V,10%,X6S,CHA',
 TOLERANCE='10%',
 MATERIAL='X6S',
 VOLTAGE='25V',
 VALUE='1UF',
 PRIM_FILE='W:/<user>/logical/q_cap/chips/chips.prt';

PART_NAME
 C105 'Q_CAP_0402-0.1UF,25V,10%,X7R,CA':;

SECTION_NUMBER 1
 '@SCM_LIB.SCM(SCH_1):PAGE16_I153@PURE_QUANTA.Q_CAP(CHIPS)':
 C_PATH='@scm_lib.scm(sch_1):page16_i153@pure_quanta.q_cap(chips)',
 P_PATH='@scm_lib.scm(sch_1):page16_i153@pure_quanta.q_cap(chips)',
 PATH='I153',
 DRAWING='@SCM_LIB.SCM(SCH_1):PAGE16',
 PHYS_PAGE='16',
 XY='(3400,2500)',
 ROT='0',
 VER='1',
 PACK_TYPE='0402',
 LOCATION='C105',
 CDS_LIB='pure_quanta',
 CDS_PART_NAME='Q_CAP_0402-0.1UF,25V,10%,X7R,CA',
 TOLERANCE='10%',
 MATERIAL='X7R',
 VOLTAGE='25V',
 VALUE='0.1UF',
 PRIM_FILE='W:/<user>/logical/q_cap/chips/chips.prt';

PART_NAME
 C106 'Q_CAP_C0402-1UF,25V,10%,X6S,CHA':;

SECTION_NUMBER 1
 '@SCM_LIB.SCM(SCH_1):PAGE16_I127@PURE_QUANTA.Q_CAP(CHIPS)':
 C_PATH='@scm_lib.scm(sch_1):page16_i127@pure_quanta.q_cap(chips)',
 P_PATH='@scm_lib.scm(sch_1):page16_i127@pure_quanta.q_cap(chips)',
 PATH='I127',
 DRAWING='@SCM_LIB.SCM(SCH_1):PAGE16',
 PHYS_PAGE='16',
 XY='(3425,725)',
 ROT='0',
 VER='1',
 PACK_TYPE='C0402',
 LOCATION='C106',
 CDS_LIB='pure_quanta',
 CDS_PART_NAME='Q_CAP_C0402-1UF,25V,10%,X6S,CHA',
 TOLERANCE='10%',
 MATERIAL='X6S',
 VOLTAGE='25V',
 VALUE='1UF',
 PRIM_FILE='W:/<user>/logical/q_cap/chips/chips.prt';

PART_NAME
 C107 'Q_CAP_0402-0.1UF,25V,10%,X7R,CA':;

SECTION_NUMBER 1
 '@SCM_LIB.SCM(SCH_1):PAGE16_I165@PURE_QUANTA.Q_CAP(CHIPS)':
 C_PATH='@scm_lib.scm(sch_1):page16_i165@pure_quanta.q_cap(chips)',
 P_PATH='@scm_lib.scm(sch_1):page16_i165@pure_quanta.q_cap(chips)',
 PATH='I165',
 DRAWING='@SCM_LIB.SCM(SCH_1):PAGE16',
 PHYS_PAGE='16',
 XY='(3525,3825)',
 ROT='0',
 VER='1',
 PACK_TYPE='0402',
 LOCATION='C107',
 CDS_LIB='pure_quanta',
 CDS_PART_NAME='Q_CAP_0402-0.1UF,25V,10%,X7R,CA',
 TOLERANCE='10%',
 MATERIAL='X7R',
 VOLTAGE='25V',
 VALUE='0.1UF',
 PRIM_FILE='W:/<user>/logical/q_cap/chips/chips.prt';

PART_NAME
 C108 'Q_CAP_C0402-1UF,25V,10%,X6S,CHA':;

SECTION_NUMBER 1
 '@SCM_LIB.SCM(SCH_1):PAGE16_I157@PURE_QUANTA.Q_CAP(CHIPS)':
 C_PATH='@scm_lib.scm(sch_1):page16_i157@pure_quanta.q_cap(chips)',
 P_PATH='@scm_lib.scm(sch_1):page16_i157@pure_quanta.q_cap(chips)',
 PATH='I157',
 DRAWING='@SCM_LIB.SCM(SCH_1):PAGE16',
 PHYS_PAGE='16',
 XY='(3575,3200)',
 ROT='0',
 VER='1',
 PACK_TYPE='C0402',
 LOCATION='C108',
 CDS_LIB='pure_quanta',
 CDS_PART_NAME='Q_CAP_C0402-1UF,25V,10%,X6S,CHA',
 TOLERANCE='10%',
 MATERIAL='X6S',
 VOLTAGE='25V',
 VALUE='1UF',
 PRIM_FILE='W:/<user>/logical/q_cap/chips/chips.prt';

PART_NAME
 C109 'Q_CAP_0402-0.1UF,25V,10%,X7R,CA':;

SECTION_NUMBER 1
 '@SCM_LIB.SCM(SCH_1):PAGE16_I156@PURE_QUANTA.Q_CAP(CHIPS)':
 C_PATH='@scm_lib.scm(sch_1):page16_i156@pure_quanta.q_cap(chips)',
 P_PATH='@scm_lib.scm(sch_1):page16_i156@pure_quanta.q_cap(chips)',
 PATH='I156',
 DRAWING='@SCM_LIB.SCM(SCH_1):PAGE16',
 PHYS_PAGE='16',
 XY='(3575,2500)',
 ROT='0',
 VER='1',
 PACK_TYPE='0402',
 LOCATION='C109',
 CDS_LIB='pure_quanta',
 CDS_PART_NAME='Q_CAP_0402-0.1UF,25V,10%,X7R,CA',
 TOLERANCE='10%',
 MATERIAL='X7R',
 VOLTAGE='25V',
 VALUE='0.1UF',
 PRIM_FILE='W:/<user>/logical/q_cap/chips/chips.prt';

PART_NAME
 C110 'Q_CAP_C0402-1UF,25V,10%,X6S,CHA':;

SECTION_NUMBER 1
 '@SCM_LIB.SCM(SCH_1):PAGE16_I133@PURE_QUANTA.Q_CAP(CHIPS)':
 C_PATH='@scm_lib.scm(sch_1):page16_i133@pure_quanta.q_cap(chips)',
 P_PATH='@scm_lib.scm(sch_1):page16_i133@pure_quanta.q_cap(chips)',
 PATH='I133',
 DRAWING='@SCM_LIB.SCM(SCH_1):PAGE16',
 PHYS_PAGE='16',
 XY='(3575,1875)',
 ROT='0',
 VER='1',
 PACK_TYPE='C0402',
 LOCATION='C110',
 CDS_LIB='pure_quanta',
 CDS_PART_NAME='Q_CAP_C0402-1UF,25V,10%,X6S,CHA',
 TOLERANCE='10%',
 MATERIAL='X6S',
 VOLTAGE='25V',
 VALUE='1UF',
 PRIM_FILE='W:/<user>/logical/q_cap/chips/chips.prt';

PART_NAME
 C111 'Q_CAP_C0402-1UF,25V,10%,X6S,CHA':;

SECTION_NUMBER 1
 '@SCM_LIB.SCM(SCH_1):PAGE16_I128@PURE_QUANTA.Q_CAP(CHIPS)':
 C_PATH='@scm_lib.scm(sch_1):page16_i128@pure_quanta.q_cap(chips)',
 P_PATH='@scm_lib.scm(sch_1):page16_i128@pure_quanta.q_cap(chips)',
 PATH='I128',
 DRAWING='@SCM_LIB.SCM(SCH_1):PAGE16',
 PHYS_PAGE='16',
 XY='(3600,725)',
 ROT='0',
 VER='1',
 PACK_TYPE='C0402',
 LOCATION='C111',
 CDS_LIB='pure_quanta',
 CDS_PART_NAME='Q_CAP_C0402-1UF,25V,10%,X6S,CHA',
 TOLERANCE='10%',
 MATERIAL='X6S',
 VOLTAGE='25V',
 VALUE='1UF',
 PRIM_FILE='W:/<user>/logical/q_cap/chips/chips.prt';

PART_NAME
 C112 'Q_CAP_0402-0.1UF,25V,10%,X7R,CA':;

SECTION_NUMBER 1
 '@SCM_LIB.SCM(SCH_1):PAGE16_I166@PURE_QUANTA.Q_CAP(CHIPS)':
 C_PATH='@scm_lib.scm(sch_1):page16_i166@pure_quanta.q_cap(chips)',
 P_PATH='@scm_lib.scm(sch_1):page16_i166@pure_quanta.q_cap(chips)',
 PATH='I166',
 DRAWING='@SCM_LIB.SCM(SCH_1):PAGE16',
 PHYS_PAGE='16',
 XY='(3725,3825)',
 ROT='0',
 VER='1',
 PACK_TYPE='0402',
 LOCATION='C112',
 CDS_LIB='pure_quanta',
 CDS_PART_NAME='Q_CAP_0402-0.1UF,25V,10%,X7R,CA',
 TOLERANCE='10%',
 MATERIAL='X7R',
 VOLTAGE='25V',
 VALUE='0.1UF',
 PRIM_FILE='W:/<user>/logical/q_cap/chips/chips.prt';

PART_NAME
 C113 'Q_CAP_C0603-22UF,6.3V,20%,X6S,A':;

SECTION_NUMBER 1
 '@SCM_LIB.SCM(SCH_1):PAGE16_I189@PURE_QUANTA.Q_CAP(CHIPS)':
 C_PATH='@scm_lib.scm(sch_1):page16_i189@pure_quanta.q_cap(chips)',
 P_PATH='@scm_lib.scm(sch_1):page16_i189@pure_quanta.q_cap(chips)',
 PATH='I189',
 DRAWING='@SCM_LIB.SCM(SCH_1):PAGE16',
 PHYS_PAGE='16',
 XY='(3750,3200)',
 ROT='0',
 VER='1',
 PACK_TYPE='C0603',
 LOCATION='C113',
 CDS_LIB='pure_quanta',
 CDS_PART_NAME='Q_CAP_C0603-22UF,6.3V,20%,X6S,A',
 TOLERANCE='20%',
 MATERIAL='X6S',
 VOLTAGE='6.3V',
 VALUE='22UF',
 PRIM_FILE='W:/<user>/logical/q_cap/chips/chips.prt';

PART_NAME
 C114 'Q_CAP_C0402-1UF,25V,10%,X6S,CHA':;

SECTION_NUMBER 1
 '@SCM_LIB.SCM(SCH_1):PAGE16_I158@PURE_QUANTA.Q_CAP(CHIPS)':
 C_PATH='@scm_lib.scm(sch_1):page16_i158@pure_quanta.q_cap(chips)',
 P_PATH='@scm_lib.scm(sch_1):page16_i158@pure_quanta.q_cap(chips)',
 PATH='I158',
 DRAWING='@SCM_LIB.SCM(SCH_1):PAGE16',
 PHYS_PAGE='16',
 XY='(3750,2500)',
 ROT='0',
 VER='1',
 PACK_TYPE='C0402',
 LOCATION='C114',
 CDS_LIB='pure_quanta',
 CDS_PART_NAME='Q_CAP_C0402-1UF,25V,10%,X6S,CHA',
 TOLERANCE='10%',
 MATERIAL='X6S',
 VOLTAGE='25V',
 VALUE='1UF',
 PRIM_FILE='W:/<user>/logical/q_cap/chips/chips.prt';

PART_NAME
 C115 'Q_CAP_C0402-1UF,25V,10%,X6S,CHA':;

SECTION_NUMBER 1
 '@SCM_LIB.SCM(SCH_1):PAGE16_I135@PURE_QUANTA.Q_CAP(CHIPS)':
 C_PATH='@scm_lib.scm(sch_1):page16_i135@pure_quanta.q_cap(chips)',
 P_PATH='@scm_lib.scm(sch_1):page16_i135@pure_quanta.q_cap(chips)',
 PATH='I135',
 DRAWING='@SCM_LIB.SCM(SCH_1):PAGE16',
 PHYS_PAGE='16',
 XY='(3750,1875)',
 ROT='0',
 VER='1',
 PACK_TYPE='C0402',
 LOCATION='C115',
 CDS_LIB='pure_quanta',
 CDS_PART_NAME='Q_CAP_C0402-1UF,25V,10%,X6S,CHA',
 TOLERANCE='10%',
 MATERIAL='X6S',
 VOLTAGE='25V',
 VALUE='1UF',
 PRIM_FILE='W:/<user>/logical/q_cap/chips/chips.prt';

PART_NAME
 C116 'Q_CAP_C0402-1UF,25V,10%,X6S,CHA':;

SECTION_NUMBER 1
 '@SCM_LIB.SCM(SCH_1):PAGE16_I129@PURE_QUANTA.Q_CAP(CHIPS)':
 C_PATH='@scm_lib.scm(sch_1):page16_i129@pure_quanta.q_cap(chips)',
 P_PATH='@scm_lib.scm(sch_1):page16_i129@pure_quanta.q_cap(chips)',
 PATH='I129',
 DRAWING='@SCM_LIB.SCM(SCH_1):PAGE16',
 PHYS_PAGE='16',
 XY='(3775,725)',
 ROT='0',
 VER='1',
 PACK_TYPE='C0402',
 LOCATION='C116',
 CDS_LIB='pure_quanta',
 CDS_PART_NAME='Q_CAP_C0402-1UF,25V,10%,X6S,CHA',
 TOLERANCE='10%',
 MATERIAL='X6S',
 VOLTAGE='25V',
 VALUE='1UF',
 PRIM_FILE='W:/<user>/logical/q_cap/chips/chips.prt';

PART_NAME
 C117 'Q_CAP_C0402-1UF,25V,10%,X6S,CHA':;

SECTION_NUMBER 1
 '@SCM_LIB.SCM(SCH_1):PAGE16_I167@PURE_QUANTA.Q_CAP(CHIPS)':
 C_PATH='@scm_lib.scm(sch_1):page16_i167@pure_quanta.q_cap(chips)',
 P_PATH='@scm_lib.scm(sch_1):page16_i167@pure_quanta.q_cap(chips)',
 PATH='I167',
 DRAWING='@SCM_LIB.SCM(SCH_1):PAGE16',
 PHYS_PAGE='16',
 XY='(3900,3825)',
 ROT='0',
 VER='1',
 PACK_TYPE='C0402',
 LOCATION='C117',
 CDS_LIB='pure_quanta',
 CDS_PART_NAME='Q_CAP_C0402-1UF,25V,10%,X6S,CHA',
 TOLERANCE='10%',
 MATERIAL='X6S',
 VOLTAGE='25V',
 VALUE='1UF',
 PRIM_FILE='W:/<user>/logical/q_cap/chips/chips.prt';

PART_NAME
 C118 'Q_CAP_C0603-22UF,6.3V,20%,X6S,A':;

SECTION_NUMBER 1
 '@SCM_LIB.SCM(SCH_1):PAGE16_I162@PURE_QUANTA.Q_CAP(CHIPS)':
 C_PATH='@scm_lib.scm(sch_1):page16_i162@pure_quanta.q_cap(chips)',
 P_PATH='@scm_lib.scm(sch_1):page16_i162@pure_quanta.q_cap(chips)',
 PATH='I162',
 DRAWING='@SCM_LIB.SCM(SCH_1):PAGE16',
 PHYS_PAGE='16',
 XY='(3950,3200)',
 ROT='0',
 VER='1',
 PACK_TYPE='C0603',
 LOCATION='C118',
 CDS_LIB='pure_quanta',
 CDS_PART_NAME='Q_CAP_C0603-22UF,6.3V,20%,X6S,A',
 TOLERANCE='20%',
 MATERIAL='X6S',
 VOLTAGE='6.3V',
 VALUE='22UF',
 PRIM_FILE='W:/<user>/logical/q_cap/chips/chips.prt';

PART_NAME
 C119 'Q_CAP_C0402-1UF,25V,10%,X6S,CHA':;

SECTION_NUMBER 1
 '@SCM_LIB.SCM(SCH_1):PAGE16_I159@PURE_QUANTA.Q_CAP(CHIPS)':
 C_PATH='@scm_lib.scm(sch_1):page16_i159@pure_quanta.q_cap(chips)',
 P_PATH='@scm_lib.scm(sch_1):page16_i159@pure_quanta.q_cap(chips)',
 PATH='I159',
 DRAWING='@SCM_LIB.SCM(SCH_1):PAGE16',
 PHYS_PAGE='16',
 XY='(3950,2500)',
 ROT='0',
 VER='1',
 PACK_TYPE='C0402',
 LOCATION='C119',
 CDS_LIB='pure_quanta',
 CDS_PART_NAME='Q_CAP_C0402-1UF,25V,10%,X6S,CHA',
 TOLERANCE='10%',
 MATERIAL='X6S',
 VOLTAGE='25V',
 VALUE='1UF',
 PRIM_FILE='W:/<user>/logical/q_cap/chips/chips.prt';

PART_NAME
 C120 'Q_CAP_C0603-22UF,6.3V,20%,X6S,A':;

SECTION_NUMBER 1
 '@SCM_LIB.SCM(SCH_1):PAGE16_I190@PURE_QUANTA.Q_CAP(CHIPS)':
 C_PATH='@scm_lib.scm(sch_1):page16_i190@pure_quanta.q_cap(chips)',
 P_PATH='@scm_lib.scm(sch_1):page16_i190@pure_quanta.q_cap(chips)',
 PATH='I190',
 DRAWING='@SCM_LIB.SCM(SCH_1):PAGE16',
 PHYS_PAGE='16',
 XY='(3950,1875)',
 ROT='0',
 VER='1',
 PACK_TYPE='C0603',
 LOCATION='C120',
 CDS_LIB='pure_quanta',
 CDS_PART_NAME='Q_CAP_C0603-22UF,6.3V,20%,X6S,A',
 TOLERANCE='20%',
 MATERIAL='X6S',
 VOLTAGE='6.3V',
 VALUE='22UF',
 PRIM_FILE='W:/<user>/logical/q_cap/chips/chips.prt';

PART_NAME
 C121 'Q_CAP_C0603-22UF,6.3V,20%,X6S,A':;

SECTION_NUMBER 1
 '@SCM_LIB.SCM(SCH_1):PAGE16_I131@PURE_QUANTA.Q_CAP(CHIPS)':
 C_PATH='@scm_lib.scm(sch_1):page16_i131@pure_quanta.q_cap(chips)',
 P_PATH='@scm_lib.scm(sch_1):page16_i131@pure_quanta.q_cap(chips)',
 PATH='I131',
 DRAWING='@SCM_LIB.SCM(SCH_1):PAGE16',
 PHYS_PAGE='16',
 XY='(3975,725)',
 ROT='0',
 VER='1',
 PACK_TYPE='C0603',
 LOCATION='C121',
 CDS_LIB='pure_quanta',
 CDS_PART_NAME='Q_CAP_C0603-22UF,6.3V,20%,X6S,A',
 TOLERANCE='20%',
 MATERIAL='X6S',
 VOLTAGE='6.3V',
 VALUE='22UF',
 PRIM_FILE='W:/<user>/logical/q_cap/chips/chips.prt';

PART_NAME
 C122 'Q_CAP_C0402-1UF,25V,10%,X6S,CHA':;

SECTION_NUMBER 1
 '@SCM_LIB.SCM(SCH_1):PAGE16_I168@PURE_QUANTA.Q_CAP(CHIPS)':
 C_PATH='@scm_lib.scm(sch_1):page16_i168@pure_quanta.q_cap(chips)',
 P_PATH='@scm_lib.scm(sch_1):page16_i168@pure_quanta.q_cap(chips)',
 PATH='I168',
 DRAWING='@SCM_LIB.SCM(SCH_1):PAGE16',
 PHYS_PAGE='16',
 XY='(4075,3825)',
 ROT='0',
 VER='1',
 PACK_TYPE='C0402',
 LOCATION='C122',
 CDS_LIB='pure_quanta',
 CDS_PART_NAME='Q_CAP_C0402-1UF,25V,10%,X6S,CHA',
 TOLERANCE='10%',
 MATERIAL='X6S',
 VOLTAGE='25V',
 VALUE='1UF',
 PRIM_FILE='W:/<user>/logical/q_cap/chips/chips.prt';

PART_NAME
 C123 'Q_CAP_C0603-22UF,6.3V,20%,X6S,A':;

SECTION_NUMBER 1
 '@SCM_LIB.SCM(SCH_1):PAGE16_I171@PURE_QUANTA.Q_CAP(CHIPS)':
 C_PATH='@scm_lib.scm(sch_1):page16_i171@pure_quanta.q_cap(chips)',
 P_PATH='@scm_lib.scm(sch_1):page16_i171@pure_quanta.q_cap(chips)',
 PATH='I171',
 DRAWING='@SCM_LIB.SCM(SCH_1):PAGE16',
 PHYS_PAGE='16',
 XY='(4150,3200)',
 ROT='0',
 VER='1',
 PACK_TYPE='C0603',
 LOCATION='C123',
 CDS_LIB='pure_quanta',
 CDS_PART_NAME='Q_CAP_C0603-22UF,6.3V,20%,X6S,A',
 TOLERANCE='20%',
 MATERIAL='X6S',
 VOLTAGE='6.3V',
 VALUE='22UF',
 PRIM_FILE='W:/<user>/logical/q_cap/chips/chips.prt';

PART_NAME
 C124 'Q_CAP_C0603-22UF,6.3V,20%,X6S,A':;

SECTION_NUMBER 1
 '@SCM_LIB.SCM(SCH_1):PAGE16_I169@PURE_QUANTA.Q_CAP(CHIPS)':
 C_PATH='@scm_lib.scm(sch_1):page16_i169@pure_quanta.q_cap(chips)',
 P_PATH='@scm_lib.scm(sch_1):page16_i169@pure_quanta.q_cap(chips)',
 PATH='I169',
 DRAWING='@SCM_LIB.SCM(SCH_1):PAGE16',
 PHYS_PAGE='16',
 XY='(4150,2500)',
 ROT='0',
 VER='1',
 PACK_TYPE='C0603',
 LOCATION='C124',
 CDS_LIB='pure_quanta',
 CDS_PART_NAME='Q_CAP_C0603-22UF,6.3V,20%,X6S,A',
 TOLERANCE='20%',
 MATERIAL='X6S',
 VOLTAGE='6.3V',
 VALUE='22UF',
 PRIM_FILE='W:/<user>/logical/q_cap/chips/chips.prt';

PART_NAME
 C125 'Q_CAP_C0603-22UF,6.3V,20%,X6S,A':;

SECTION_NUMBER 1
 '@SCM_LIB.SCM(SCH_1):PAGE16_I191@PURE_QUANTA.Q_CAP(CHIPS)':
 C_PATH='@scm_lib.scm(sch_1):page16_i191@pure_quanta.q_cap(chips)',
 P_PATH='@scm_lib.scm(sch_1):page16_i191@pure_quanta.q_cap(chips)',
 PATH='I191',
 DRAWING='@SCM_LIB.SCM(SCH_1):PAGE16',
 PHYS_PAGE='16',
 XY='(4150,1875)',
 ROT='0',
 VER='1',
 PACK_TYPE='C0603',
 LOCATION='C125',
 CDS_LIB='pure_quanta',
 CDS_PART_NAME='Q_CAP_C0603-22UF,6.3V,20%,X6S,A',
 TOLERANCE='20%',
 MATERIAL='X6S',
 VOLTAGE='6.3V',
 VALUE='22UF',
 PRIM_FILE='W:/<user>/logical/q_cap/chips/chips.prt';

PART_NAME
 C126 'Q_CAP_C0603-22UF,6.3V,20%,X6S,A':;

SECTION_NUMBER 1
 '@SCM_LIB.SCM(SCH_1):PAGE16_I143@PURE_QUANTA.Q_CAP(CHIPS)':
 C_PATH='@scm_lib.scm(sch_1):page16_i143@pure_quanta.q_cap(chips)',
 P_PATH='@scm_lib.scm(sch_1):page16_i143@pure_quanta.q_cap(chips)',
 PATH='I143',
 DRAWING='@SCM_LIB.SCM(SCH_1):PAGE16',
 PHYS_PAGE='16',
 XY='(4175,725)',
 ROT='0',
 VER='1',
 PACK_TYPE='C0603',
 LOCATION='C126',
 CDS_LIB='pure_quanta',
 CDS_PART_NAME='Q_CAP_C0603-22UF,6.3V,20%,X6S,A',
 TOLERANCE='20%',
 MATERIAL='X6S',
 VOLTAGE='6.3V',
 VALUE='22UF',
 PRIM_FILE='W:/<user>/logical/q_cap/chips/chips.prt';

PART_NAME
 C127 'Q_CAP_C0402-1UF,25V,10%,X6S,CHA':;

SECTION_NUMBER 1
 '@SCM_LIB.SCM(SCH_1):PAGE16_I173@PURE_QUANTA.Q_CAP(CHIPS)':
 C_PATH='@scm_lib.scm(sch_1):page16_i173@pure_quanta.q_cap(chips)',
 P_PATH='@scm_lib.scm(sch_1):page16_i173@pure_quanta.q_cap(chips)',
 PATH='I173',
 DRAWING='@SCM_LIB.SCM(SCH_1):PAGE16',
 PHYS_PAGE='16',
 XY='(4250,3825)',
 ROT='0',
 VER='1',
 PACK_TYPE='C0402',
 LOCATION='C127',
 CDS_LIB='pure_quanta',
 CDS_PART_NAME='Q_CAP_C0402-1UF,25V,10%,X6S,CHA',
 TOLERANCE='10%',
 MATERIAL='X6S',
 VOLTAGE='25V',
 VALUE='1UF',
 PRIM_FILE='W:/<user>/logical/q_cap/chips/chips.prt';

PART_NAME
 C128 'Q_CAP_C0402-1UF,25V,10%,X6S,CHA':;

SECTION_NUMBER 1
 '@SCM_LIB.SCM(SCH_1):PAGE17_I165@PURE_QUANTA.Q_CAP(CHIPS)':
 C_PATH='@scm_lib.scm(sch_1):page17_i165@pure_quanta.q_cap(chips)',
 P_PATH='@scm_lib.scm(sch_1):page17_i165@pure_quanta.q_cap(chips)',
 PATH='I165',
 DRAWING='@SCM_LIB.SCM(SCH_1):PAGE17',
 PHYS_PAGE='17',
 XY='(3425,2000)',
 ROT='0',
 VER='1',
 PACK_TYPE='C0402',
 LOCATION='C128',
 CDS_LIB='pure_quanta',
 CDS_PART_NAME='Q_CAP_C0402-1UF,25V,10%,X6S,CHA',
 TOLERANCE='10%',
 MATERIAL='X6S',
 VOLTAGE='25V',
 VALUE='1UF',
 PRIM_FILE='W:/<user>/logical/q_cap/chips/chips.prt';

PART_NAME
 C129 'Q_CAP_C0402-1UF,25V,10%,X6S,CHA':;

SECTION_NUMBER 1
 '@SCM_LIB.SCM(SCH_1):PAGE16_I174@PURE_QUANTA.Q_CAP(CHIPS)':
 C_PATH='@scm_lib.scm(sch_1):page16_i174@pure_quanta.q_cap(chips)',
 P_PATH='@scm_lib.scm(sch_1):page16_i174@pure_quanta.q_cap(chips)',
 PATH='I174',
 DRAWING='@SCM_LIB.SCM(SCH_1):PAGE16',
 PHYS_PAGE='16',
 XY='(4425,3825)',
 ROT='0',
 VER='1',
 PACK_TYPE='C0402',
 LOCATION='C129',
 CDS_LIB='pure_quanta',
 CDS_PART_NAME='Q_CAP_C0402-1UF,25V,10%,X6S,CHA',
 TOLERANCE='10%',
 MATERIAL='X6S',
 VOLTAGE='25V',
 VALUE='1UF',
 PRIM_FILE='W:/<user>/logical/q_cap/chips/chips.prt';

PART_NAME
 C130 'Q_CAP_0402-0.1UF,25V,10%,X7R,CA':;

SECTION_NUMBER 1
 '@SCM_LIB.SCM(SCH_1):PAGE17_I163@PURE_QUANTA.Q_CAP(CHIPS)':
 C_PATH='@scm_lib.scm(sch_1):page17_i163@pure_quanta.q_cap(chips)',
 P_PATH='@scm_lib.scm(sch_1):page17_i163@pure_quanta.q_cap(chips)',
 PATH='I163',
 DRAWING='@SCM_LIB.SCM(SCH_1):PAGE17',
 PHYS_PAGE='17',
 XY='(3625,2000)',
 ROT='0',
 VER='1',
 PACK_TYPE='0402',
 LOCATION='C130',
 CDS_LIB='pure_quanta',
 CDS_PART_NAME='Q_CAP_0402-0.1UF,25V,10%,X7R,CA',
 TOLERANCE='10%',
 MATERIAL='X7R',
 VOLTAGE='25V',
 VALUE='0.1UF',
 PRIM_FILE='W:/<user>/logical/q_cap/chips/chips.prt';

PART_NAME
 C131 'Q_CAP_C0603-22UF,6.3V,20%,X6S,A':;

SECTION_NUMBER 1
 '@SCM_LIB.SCM(SCH_1):PAGE16_I192@PURE_QUANTA.Q_CAP(CHIPS)':
 C_PATH='@scm_lib.scm(sch_1):page16_i192@pure_quanta.q_cap(chips)',
 P_PATH='@scm_lib.scm(sch_1):page16_i192@pure_quanta.q_cap(chips)',
 PATH='I192',
 DRAWING='@SCM_LIB.SCM(SCH_1):PAGE16',
 PHYS_PAGE='16',
 XY='(4625,3825)',
 ROT='0',
 VER='1',
 PACK_TYPE='C0603',
 LOCATION='C131',
 CDS_LIB='pure_quanta',
 CDS_PART_NAME='Q_CAP_C0603-22UF,6.3V,20%,X6S,A',
 TOLERANCE='20%',
 MATERIAL='X6S',
 VOLTAGE='6.3V',
 VALUE='22UF',
 PRIM_FILE='W:/<user>/logical/q_cap/chips/chips.prt';

PART_NAME
 C132 'Q_CAP_C0603-22UF,6.3V,20%,X6S,A':;

SECTION_NUMBER 1
 '@SCM_LIB.SCM(SCH_1):PAGE16_I193@PURE_QUANTA.Q_CAP(CHIPS)':
 C_PATH='@scm_lib.scm(sch_1):page16_i193@pure_quanta.q_cap(chips)',
 P_PATH='@scm_lib.scm(sch_1):page16_i193@pure_quanta.q_cap(chips)',
 PATH='I193',
 DRAWING='@SCM_LIB.SCM(SCH_1):PAGE16',
 PHYS_PAGE='16',
 XY='(4825,3825)',
 ROT='0',
 VER='1',
 PACK_TYPE='C0603',
 LOCATION='C132',
 CDS_LIB='pure_quanta',
 CDS_PART_NAME='Q_CAP_C0603-22UF,6.3V,20%,X6S,A',
 TOLERANCE='20%',
 MATERIAL='X6S',
 VOLTAGE='6.3V',
 VALUE='22UF',
 PRIM_FILE='W:/<user>/logical/q_cap/chips/chips.prt';

PART_NAME
 C133 'Q_CAP_C0402-0.01UF,50V,10%,X7RA':;

SECTION_NUMBER 1
 '@SCM_LIB.SCM(SCH_1):PAGE17_I104@PURE_QUANTA.Q_CAP(CHIPS)':
 C_PATH='@scm_lib.scm(sch_1):page17_i104@pure_quanta.q_cap(chips)',
 P_PATH='@scm_lib.scm(sch_1):page17_i104@pure_quanta.q_cap(chips)',
 PATH='I104',
 DRAWING='@SCM_LIB.SCM(SCH_1):PAGE17',
 PHYS_PAGE='17',
 XY='(350,3300)',
 ROT='0',
 VER='2',
 PACK_TYPE='C0402',
 LOCATION='C133',
 CDS_LIB='pure_quanta',
 CDS_PART_NAME='Q_CAP_C0402-0.01UF,50V,10%,X7RA',
 TOLERANCE='10%',
 MATERIAL='X7R',
 VOLTAGE='50V',
 VALUE='0.01UF',
 PRIM_FILE='W:/<user>/logical/q_cap/chips/chips.prt';

PART_NAME
 C134 'Q_CAP_C0402-0.01UF,50V,10%,X7RA':;

SECTION_NUMBER 1
 '@SCM_LIB.SCM(SCH_1):PAGE17_I106@PURE_QUANTA.Q_CAP(CHIPS)':
 C_PATH='@scm_lib.scm(sch_1):page17_i106@pure_quanta.q_cap(chips)',
 P_PATH='@scm_lib.scm(sch_1):page17_i106@pure_quanta.q_cap(chips)',
 PATH='I106',
 DRAWING='@SCM_LIB.SCM(SCH_1):PAGE17',
 PHYS_PAGE='17',
 XY='(400,3900)',
 ROT='0',
 VER='2',
 PACK_TYPE='C0402',
 LOCATION='C134',
 CDS_LIB='pure_quanta',
 CDS_PART_NAME='Q_CAP_C0402-0.01UF,50V,10%,X7RA',
 TOLERANCE='10%',
 MATERIAL='X7R',
 VOLTAGE='50V',
 VALUE='0.01UF',
 PRIM_FILE='W:/<user>/logical/q_cap/chips/chips.prt';

PART_NAME
 C135 'Q_CAP_C0402-0.01UF,50V,10%,X7RA':;

SECTION_NUMBER 1
 '@SCM_LIB.SCM(SCH_1):PAGE17_I107@PURE_QUANTA.Q_CAP(CHIPS)':
 C_PATH='@scm_lib.scm(sch_1):page17_i107@pure_quanta.q_cap(chips)',
 P_PATH='@scm_lib.scm(sch_1):page17_i107@pure_quanta.q_cap(chips)',
 PATH='I107',
 DRAWING='@SCM_LIB.SCM(SCH_1):PAGE17',
 PHYS_PAGE='17',
 XY='(775,3425)',
 ROT='0',
 VER='2',
 PACK_TYPE='C0402',
 LOCATION='C135',
 CDS_LIB='pure_quanta',
 CDS_PART_NAME='Q_CAP_C0402-0.01UF,50V,10%,X7RA',
 TOLERANCE='10%',
 MATERIAL='X7R',
 VOLTAGE='50V',
 VALUE='0.01UF',
 PRIM_FILE='W:/<user>/logical/q_cap/chips/chips.prt';

PART_NAME
 C136 'Q_CAP_C0402-0.01UF,50V,10%,X7RA':;

SECTION_NUMBER 1
 '@SCM_LIB.SCM(SCH_1):PAGE17_I110@PURE_QUANTA.Q_CAP(CHIPS)':
 C_PATH='@scm_lib.scm(sch_1):page17_i110@pure_quanta.q_cap(chips)',
 P_PATH='@scm_lib.scm(sch_1):page17_i110@pure_quanta.q_cap(chips)',
 PATH='I110',
 DRAWING='@SCM_LIB.SCM(SCH_1):PAGE17',
 PHYS_PAGE='17',
 XY='(825,4025)',
 ROT='0',
 VER='2',
 PACK_TYPE='C0402',
 LOCATION='C136',
 CDS_LIB='pure_quanta',
 CDS_PART_NAME='Q_CAP_C0402-0.01UF,50V,10%,X7RA',
 TOLERANCE='10%',
 MATERIAL='X7R',
 VOLTAGE='50V',
 VALUE='0.01UF',
 PRIM_FILE='W:/<user>/logical/q_cap/chips/chips.prt';

PART_NAME
 C137 'Q_CAP_C0402-0.01UF,50V,10%,X7RA':;

SECTION_NUMBER 1
 '@SCM_LIB.SCM(SCH_1):PAGE17_I108@PURE_QUANTA.Q_CAP(CHIPS)':
 C_PATH='@scm_lib.scm(sch_1):page17_i108@pure_quanta.q_cap(chips)',
 P_PATH='@scm_lib.scm(sch_1):page17_i108@pure_quanta.q_cap(chips)',
 PATH='I108',
 DRAWING='@SCM_LIB.SCM(SCH_1):PAGE17',
 PHYS_PAGE='17',
 XY='(1000,3300)',
 ROT='0',
 VER='2',
 PACK_TYPE='C0402',
 LOCATION='C137',
 CDS_LIB='pure_quanta',
 CDS_PART_NAME='Q_CAP_C0402-0.01UF,50V,10%,X7RA',
 TOLERANCE='10%',
 MATERIAL='X7R',
 VOLTAGE='50V',
 VALUE='0.01UF',
 PRIM_FILE='W:/<user>/logical/q_cap/chips/chips.prt';

PART_NAME
 C138 'Q_CAP_C0402-0.01UF,50V,10%,X7RA':;

SECTION_NUMBER 1
 '@SCM_LIB.SCM(SCH_1):PAGE17_I109@PURE_QUANTA.Q_CAP(CHIPS)':
 C_PATH='@scm_lib.scm(sch_1):page17_i109@pure_quanta.q_cap(chips)',
 P_PATH='@scm_lib.scm(sch_1):page17_i109@pure_quanta.q_cap(chips)',
 PATH='I109',
 DRAWING='@SCM_LIB.SCM(SCH_1):PAGE17',
 PHYS_PAGE='17',
 XY='(1050,3900)',
 ROT='0',
 VER='2',
 PACK_TYPE='C0402',
 LOCATION='C138',
 CDS_LIB='pure_quanta',
 CDS_PART_NAME='Q_CAP_C0402-0.01UF,50V,10%,X7RA',
 TOLERANCE='10%',
 MATERIAL='X7R',
 VOLTAGE='50V',
 VALUE='0.01UF',
 PRIM_FILE='W:/<user>/logical/q_cap/chips/chips.prt';

PART_NAME
 C139 'Q_CAP_0402-0.1UF,25V,10%,X7R,CA':;

SECTION_NUMBER 1
 '@SCM_LIB.SCM(SCH_1):PAGE17_I98@PURE_QUANTA.Q_CAP(CHIPS)':
 C_PATH='@scm_lib.scm(sch_1):page17_i98@pure_quanta.q_cap(chips)',
 P_PATH='@scm_lib.scm(sch_1):page17_i98@pure_quanta.q_cap(chips)',
 PATH='I98',
 DRAWING='@SCM_LIB.SCM(SCH_1):PAGE17',
 PHYS_PAGE='17',
 XY='(4100,3775)',
 ROT='0',
 VER='1',
 PACK_TYPE='0402',
 LOCATION='C139',
 CDS_LIB='pure_quanta',
 CDS_PART_NAME='Q_CAP_0402-0.1UF,25V,10%,X7R,CA',
 TOLERANCE='10%',
 MATERIAL='X7R',
 VOLTAGE='25V',
 VALUE='0.1UF',
 PRIM_FILE='W:/<user>/logical/q_cap/chips/chips.prt';

PART_NAME
 C140 'Q_CAP_0402-0.1UF,25V,10%,X7R,CA':;

SECTION_NUMBER 1
 '@SCM_LIB.SCM(SCH_1):PAGE17_I97@PURE_QUANTA.Q_CAP(CHIPS)':
 C_PATH='@scm_lib.scm(sch_1):page17_i97@pure_quanta.q_cap(chips)',
 P_PATH='@scm_lib.scm(sch_1):page17_i97@pure_quanta.q_cap(chips)',
 PATH='I97',
 DRAWING='@SCM_LIB.SCM(SCH_1):PAGE17',
 PHYS_PAGE='17',
 XY='(4100,3025)',
 ROT='0',
 VER='1',
 PACK_TYPE='0402',
 LOCATION='C140',
 CDS_LIB='pure_quanta',
 CDS_PART_NAME='Q_CAP_0402-0.1UF,25V,10%,X7R,CA',
 TOLERANCE='10%',
 MATERIAL='X7R',
 VOLTAGE='25V',
 VALUE='0.1UF',
 PRIM_FILE='W:/<user>/logical/q_cap/chips/chips.prt';

PART_NAME
 C141 'Q_CAP_0402-0.1UF,25V,10%,X7R,CA':;

SECTION_NUMBER 1
 '@SCM_LIB.SCM(SCH_1):PAGE41_I83@PURE_QUANTA.Q_CAP(CHIPS)':
 C_PATH='@scm_lib.scm(sch_1):page41_i83@pure_quanta.q_cap(chips)',
 P_PATH='@scm_lib.scm(sch_1):page41_i83@pure_quanta.q_cap(chips)',
 PATH='I83',
 DRAWING='@SCM_LIB.SCM(SCH_1):PAGE41',
 PHYS_PAGE='41',
 XY='(-2300,4700)',
 ROT='0',
 VER='1',
 PACK_TYPE='0402',
 CDS_LIB='pure_quanta',
 CDS_PART_NAME='Q_CAP_0402-0.1UF,25V,10%,X7R,CA',
 TOLERANCE='10%',
 MATERIAL='X7R',
 VOLTAGE='25V',
 VALUE='0.1UF',
 PRIM_FILE='W:/<user>/logical/q_cap/chips/chips.prt';

PART_NAME
 C142 'Q_CAP_C0805-10UF,25V,10%,X6S,CA':;

SECTION_NUMBER 1
 '@SCM_LIB.SCM(SCH_1):PAGE54_I104@PURE_QUANTA.Q_CAP(CHIPS)':
 C_PATH='@scm_lib.scm(sch_1):page54_i104@pure_quanta.q_cap(chips)',
 P_PATH='@scm_lib.scm(sch_1):page54_i104@pure_quanta.q_cap(chips)',
 PATH='I104',
 DRAWING='@SCM_LIB.SCM(SCH_1):PAGE54',
 PHYS_PAGE='54',
 XY='(1850,2000)',
 ROT='0',
 VER='1',
 PACK_TYPE='C0805',
 CDS_LIB='pure_quanta',
 CDS_PART_NAME='Q_CAP_C0805-10UF,25V,10%,X6S,CA',
 TOLERANCE='10%',
 MATERIAL='X6S',
 VOLTAGE='25V',
 VALUE='10UF',
 PRIM_FILE='W:/<user>/logical/q_cap/chips/chips.prt';

PART_NAME
 C143 'Q_CAP_C0402-10UF,6.3V,20%,X6S,A':;

SECTION_NUMBER 1
 '@SCM_LIB.SCM(SCH_1):PAGE46_I108@PURE_QUANTA.Q_CAP(CHIPS)':
 C_PATH='@scm_lib.scm(sch_1):page46_i108@pure_quanta.q_cap(chips)',
 P_PATH='@scm_lib.scm(sch_1):page46_i108@pure_quanta.q_cap(chips)',
 PATH='I108',
 DRAWING='@SCM_LIB.SCM(SCH_1):PAGE46',
 PHYS_PAGE='46',
 XY='(-7250,-4425)',
 ROT='0',
 VER='1',
 PACK_TYPE='C0402',
 LOCATION='C143',
 CDS_LIB='pure_quanta',
 CDS_PART_NAME='Q_CAP_C0402-10UF,6.3V,20%,X6S,A',
 TOLERANCE='20%',
 MATERIAL='X6S',
 VOLTAGE='6.3V',
 VALUE='10UF',
 PRIM_FILE='W:/<user>/logical/q_cap/chips/chips.prt';

PART_NAME
 C144 'Q_CAP_0402-0.1UF,25V,10%,X7R,CA':;

SECTION_NUMBER 1
 '@SCM_LIB.SCM(SCH_1):PAGE46_I102@PURE_QUANTA.Q_CAP(CHIPS)':
 C_PATH='@scm_lib.scm(sch_1):page46_i102@pure_quanta.q_cap(chips)',
 P_PATH='@scm_lib.scm(sch_1):page46_i102@pure_quanta.q_cap(chips)',
 PATH='I102',
 DRAWING='@SCM_LIB.SCM(SCH_1):PAGE46',
 PHYS_PAGE='46',
 XY='(-6875,-4425)',
 ROT='0',
 VER='1',
 PACK_TYPE='0402',
 LOCATION='C144',
 CDS_LIB='pure_quanta',
 CDS_PART_NAME='Q_CAP_0402-0.1UF,25V,10%,X7R,CA',
 TOLERANCE='10%',
 MATERIAL='X7R',
 VOLTAGE='25V',
 VALUE='0.1UF',
 PRIM_FILE='W:/<user>/logical/q_cap/chips/chips.prt';

PART_NAME
 C145 'Q_CAP_C0402-1UF,25V,10%,X6S,CHA':;

SECTION_NUMBER 1
 '@SCM_LIB.SCM(SCH_1):PAGE41_I99@PURE_QUANTA.Q_CAP(CHIPS)':
 C_PATH='@scm_lib.scm(sch_1):page41_i99@pure_quanta.q_cap(chips)',
 P_PATH='@scm_lib.scm(sch_1):page41_i99@pure_quanta.q_cap(chips)',
 PATH='I99',
 DRAWING='@SCM_LIB.SCM(SCH_1):PAGE41',
 SEC_TYPE='C0402',
 PHYS_PAGE='41',
 XY='(-8800,5800)',
 ROT='0',
 VER='1',
 PACK_TYPE='C0402',
 SEC='1',
 CDS_LIB='pure_quanta',
 CDS_PART_NAME='Q_CAP_C0402-1UF,25V,10%,X6S,CHA',
 TOLERANCE='10%',
 MATERIAL='X6S',
 VOLTAGE='25V',
 VALUE='1UF',
 PRIM_FILE='W:/<user>/logical/q_cap/chips/chips.prt';

PART_NAME
 C146 'Q_CAP_0402-0.1UF,25V,10%,X7R,CA':;

SECTION_NUMBER 1
 '@SCM_LIB.SCM(SCH_1):PAGE44_I292@PURE_QUANTA.Q_CAP(CHIPS)':
 C_PATH='@scm_lib.scm(sch_1):page44_i292@pure_quanta.q_cap(chips)',
 P_PATH='@scm_lib.scm(sch_1):page44_i292@pure_quanta.q_cap(chips)',
 PATH='I292',
 DRAWING='@SCM_LIB.SCM(SCH_1):PAGE44',
 PHYS_PAGE='44',
 XY='(3125,-100)',
 ROT='0',
 VER='1',
 PACK_TYPE='0402',
 LOCATION='C146',
 CDS_LIB='pure_quanta',
 CDS_PART_NAME='Q_CAP_0402-0.1UF,25V,10%,X7R,CA',
 TOLERANCE='10%',
 MATERIAL='X7R',
 VOLTAGE='25V',
 VALUE='0.1UF',
 PRIM_FILE='W:/<user>/logical/q_cap/chips/chips.prt';

PART_NAME
 C147 'Q_CAP_0402-0.1UF,25V,10%,EMPTYA':;

SECTION_NUMBER 1
 '@SCM_LIB.SCM(SCH_1):PAGE22_I17@PURE_QUANTA.Q_CAP(CHIPS)':
 C_PATH='@scm_lib.scm(sch_1):page22_i17@pure_quanta.q_cap(chips)',
 P_PATH='@scm_lib.scm(sch_1):page22_i17@pure_quanta.q_cap(chips)',
 PATH='I17',
 DRAWING='@SCM_LIB.SCM(SCH_1):PAGE22',
 SEC_TYPE='0402',
 PHYS_PAGE='22',
 XY='(3875,2550)',
 ROT='0',
 VER='1',
 PACK_TYPE='0402',
 LOCATION='C147',
 SEC='1',
 CDS_LIB='pure_quanta',
 CDS_PART_NAME='Q_CAP_0402-0.1UF,25V,10%,EMPTYA',
 TOLERANCE='10%',
 MATERIAL='EMPTY',
 VOLTAGE='25V',
 VALUE='0.1UF',
 PRIM_FILE='W:/<user>/logical/q_cap/chips/chips.prt';

PART_NAME
 C148 'Q_CAP_0402-0.1UF,25V,10%,X7R,CA':;

SECTION_NUMBER 1
 '@SCM_LIB.SCM(SCH_1):PAGE29_I172@PURE_QUANTA.Q_CAP(CHIPS)':
 C_PATH='@scm_lib.scm(sch_1):page29_i172@pure_quanta.q_cap(chips)',
 P_PATH='@scm_lib.scm(sch_1):page29_i172@pure_quanta.q_cap(chips)',
 PATH='I172',
 DRAWING='@SCM_LIB.SCM(SCH_1):PAGE29',
 PHYS_PAGE='29',
 XY='(2050,2675)',
 ROT='2',
 VER='1',
 PACK_TYPE='0402',
 LOCATION='C148',
 CDS_LIB='pure_quanta',
 CDS_PART_NAME='Q_CAP_0402-0.1UF,25V,10%,X7R,CA',
 TOLERANCE='10%',
 MATERIAL='X7R',
 VOLTAGE='25V',
 VALUE='0.1UF',
 PRIM_FILE='W:/<user>/logical/q_cap/chips/chips.prt';

PART_NAME
 C149 'Q_CAP_0402-0.1UF,25V,10%,X7R,CA':;

SECTION_NUMBER 1
 '@SCM_LIB.SCM(SCH_1):PAGE29_I161@PURE_QUANTA.Q_CAP(CHIPS)':
 C_PATH='@scm_lib.scm(sch_1):page29_i161@pure_quanta.q_cap(chips)',
 P_PATH='@scm_lib.scm(sch_1):page29_i161@pure_quanta.q_cap(chips)',
 PATH='I161',
 DRAWING='@SCM_LIB.SCM(SCH_1):PAGE29',
 PHYS_PAGE='29',
 XY='(3475,3900)',
 ROT='0',
 VER='1',
 PACK_TYPE='0402',
 LOCATION='C149',
 CDS_LIB='pure_quanta',
 CDS_PART_NAME='Q_CAP_0402-0.1UF,25V,10%,X7R,CA',
 TOLERANCE='10%',
 MATERIAL='X7R',
 VOLTAGE='25V',
 VALUE='0.1UF',
 PRIM_FILE='W:/<user>/logical/q_cap/chips/chips.prt';

PART_NAME
 C150 'Q_CAP_C0402-0.001UF,50V,10%,EMA':;

SECTION_NUMBER 1
 '@SCM_LIB.SCM(SCH_1):PAGE51_I49@PURE_QUANTA.Q_CAP(CHIPS)':
 C_PATH='@scm_lib.scm(sch_1):page51_i49@pure_quanta.q_cap(chips)',
 P_PATH='@scm_lib.scm(sch_1):page51_i49@pure_quanta.q_cap(chips)',
 PATH='I49',
 DRAWING='@SCM_LIB.SCM(SCH_1):PAGE51',
 PHYS_PAGE='51',
 XY='(3550,975)',
 ROT='0',
 VER='1',
 PACK_TYPE='C0402',
 LOCATION='C150',
 CDS_LIB='pure_quanta',
 CDS_PART_NAME='Q_CAP_C0402-0.001UF,50V,10%,EMA',
 TOLERANCE='10%',
 MATERIAL='EMPTY',
 VOLTAGE='50V',
 VALUE='0.001UF',
 PRIM_FILE='W:/<user>/logical/q_cap/chips/chips.prt';

PART_NAME
 C151 'Q_CAP_C0402-0.001UF,50V,10%,EMA':;

SECTION_NUMBER 1
 '@SCM_LIB.SCM(SCH_1):PAGE52_I93@PURE_QUANTA.Q_CAP(CHIPS)':
 C_PATH='@scm_lib.scm(sch_1):page52_i93@pure_quanta.q_cap(chips)',
 P_PATH='@scm_lib.scm(sch_1):page52_i93@pure_quanta.q_cap(chips)',
 PATH='I93',
 DRAWING='@SCM_LIB.SCM(SCH_1):PAGE52',
 PHYS_PAGE='52',
 XY='(2175,1625)',
 ROT='0',
 VER='1',
 PACK_TYPE='C0402',
 LOCATION='C151',
 CDS_LIB='pure_quanta',
 CDS_PART_NAME='Q_CAP_C0402-0.001UF,50V,10%,EMA',
 TOLERANCE='10%',
 MATERIAL='EMPTY',
 VOLTAGE='50V',
 VALUE='0.001UF',
 PRIM_FILE='W:/<user>/logical/q_cap/chips/chips.prt';

PART_NAME
 C152 'Q_CAP_0402-0.1UF,25V,10%,X7R,CA':;

SECTION_NUMBER 1
 '@SCM_LIB.SCM(SCH_1):PAGE41_I88@PURE_QUANTA.Q_CAP(CHIPS)':
 C_PATH='@scm_lib.scm(sch_1):page41_i88@pure_quanta.q_cap(chips)',
 P_PATH='@scm_lib.scm(sch_1):page41_i88@pure_quanta.q_cap(chips)',
 PATH='I88',
 DRAWING='@SCM_LIB.SCM(SCH_1):PAGE41',
 PHYS_PAGE='41',
 XY='(-7200,3250)',
 ROT='0',
 VER='1',
 PACK_TYPE='0402',
 CDS_LIB='pure_quanta',
 CDS_PART_NAME='Q_CAP_0402-0.1UF,25V,10%,X7R,CA',
 TOLERANCE='10%',
 MATERIAL='X7R',
 VOLTAGE='25V',
 VALUE='0.1UF',
 PRIM_FILE='W:/<user>/logical/q_cap/chips/chips.prt';

PART_NAME
 C153 'Q_CAP_C0402-0.001UF,50V,10%,EMA':;

SECTION_NUMBER 1
 '@SCM_LIB.SCM(SCH_1):PAGE53_I64@PURE_QUANTA.Q_CAP(CHIPS)':
 C_PATH='@scm_lib.scm(sch_1):page53_i64@pure_quanta.q_cap(chips)',
 P_PATH='@scm_lib.scm(sch_1):page53_i64@pure_quanta.q_cap(chips)',
 PATH='I64',
 DRAWING='@SCM_LIB.SCM(SCH_1):PAGE53',
 PHYS_PAGE='53',
 XY='(-2025,-325)',
 ROT='0',
 VER='1',
 PACK_TYPE='C0402',
 LOCATION='C153',
 CDS_LIB='pure_quanta',
 CDS_PART_NAME='Q_CAP_C0402-0.001UF,50V,10%,EMA',
 TOLERANCE='10%',
 MATERIAL='EMPTY',
 VOLTAGE='50V',
 VALUE='0.001UF',
 PRIM_FILE='W:/<user>/logical/q_cap/chips/chips.prt';

PART_NAME
 C154 'Q_CAP_C0402-0.001UF,50V,10%,EMA':;

SECTION_NUMBER 1
 '@SCM_LIB.SCM(SCH_1):PAGE54_I100@PURE_QUANTA.Q_CAP(CHIPS)':
 C_PATH='@scm_lib.scm(sch_1):page54_i100@pure_quanta.q_cap(chips)',
 P_PATH='@scm_lib.scm(sch_1):page54_i100@pure_quanta.q_cap(chips)',
 PATH='I100',
 DRAWING='@SCM_LIB.SCM(SCH_1):PAGE54',
 PHYS_PAGE='54',
 XY='(-1075,1425)',
 ROT='0',
 VER='1',
 PACK_TYPE='C0402',
 LOCATION='C154',
 CDS_LIB='pure_quanta',
 CDS_PART_NAME='Q_CAP_C0402-0.001UF,50V,10%,EMA',
 TOLERANCE='10%',
 MATERIAL='EMPTY',
 VOLTAGE='50V',
 VALUE='0.001UF',
 PRIM_FILE='W:/<user>/logical/q_cap/chips/chips.prt';

PART_NAME
 C155 'Q_CAP_C0402-0.001UF,50V,10%,EMA':;

SECTION_NUMBER 1
 '@SCM_LIB.SCM(SCH_1):PAGE55_I52@PURE_QUANTA.Q_CAP(CHIPS)':
 C_PATH='@scm_lib.scm(sch_1):page55_i52@pure_quanta.q_cap(chips)',
 P_PATH='@scm_lib.scm(sch_1):page55_i52@pure_quanta.q_cap(chips)',
 PATH='I52',
 DRAWING='@SCM_LIB.SCM(SCH_1):PAGE55',
 PHYS_PAGE='55',
 XY='(1325,875)',
 ROT='0',
 VER='1',
 PACK_TYPE='C0402',
 LOCATION='C155',
 CDS_LIB='pure_quanta',
 CDS_PART_NAME='Q_CAP_C0402-0.001UF,50V,10%,EMA',
 TOLERANCE='10%',
 MATERIAL='EMPTY',
 VOLTAGE='50V',
 VALUE='0.001UF',
 PRIM_FILE='W:/<user>/logical/q_cap/chips/chips.prt';

PART_NAME
 C156 'Q_CAP_C0402-0.001UF,50V,10%,EMA':;

SECTION_NUMBER 1
 '@SCM_LIB.SCM(SCH_1):PAGE56_I51@PURE_QUANTA.Q_CAP(CHIPS)':
 C_PATH='@scm_lib.scm(sch_1):page56_i51@pure_quanta.q_cap(chips)',
 P_PATH='@scm_lib.scm(sch_1):page56_i51@pure_quanta.q_cap(chips)',
 PATH='I51',
 DRAWING='@SCM_LIB.SCM(SCH_1):PAGE56',
 PHYS_PAGE='56',
 XY='(-525,625)',
 ROT='0',
 VER='1',
 PACK_TYPE='C0402',
 LOCATION='C156',
 CDS_LIB='pure_quanta',
 CDS_PART_NAME='Q_CAP_C0402-0.001UF,50V,10%,EMA',
 TOLERANCE='10%',
 MATERIAL='EMPTY',
 VOLTAGE='50V',
 VALUE='0.001UF',
 PRIM_FILE='W:/<user>/logical/q_cap/chips/chips.prt';

PART_NAME
 C157 'Q_CAP_0402-0.1UF,25V,10%,X7R,CA':;

SECTION_NUMBER 1
 '@SCM_LIB.SCM(SCH_1):PAGE28_I181@PURE_QUANTA.Q_CAP(CHIPS)':
 C_PATH='@scm_lib.scm(sch_1):page28_i181@pure_quanta.q_cap(chips)',
 P_PATH='@scm_lib.scm(sch_1):page28_i181@pure_quanta.q_cap(chips)',
 PATH='I181',
 DRAWING='@SCM_LIB.SCM(SCH_1):PAGE28',
 PHYS_PAGE='28',
 XY='(-1975,3700)',
 ROT='0',
 VER='1',
 PACK_TYPE='0402',
 LOCATION='C157',
 CDS_LIB='pure_quanta',
 CDS_PART_NAME='Q_CAP_0402-0.1UF,25V,10%,X7R,CA',
 TOLERANCE='10%',
 MATERIAL='X7R',
 VOLTAGE='25V',
 VALUE='0.1UF',
 PRIM_FILE='W:/<user>/logical/q_cap/chips/chips.prt';

PART_NAME
 C158 'Q_CAP_0402-0.1UF,25V,10%,X7R,CA':;

SECTION_NUMBER 1
 '@SCM_LIB.SCM(SCH_1):PAGE28_I101@PURE_QUANTA.Q_CAP(CHIPS)':
 C_PATH='@scm_lib.scm(sch_1):page28_i101@pure_quanta.q_cap(chips)',
 P_PATH='@scm_lib.scm(sch_1):page28_i101@pure_quanta.q_cap(chips)',
 PATH='I101',
 DRAWING='@SCM_LIB.SCM(SCH_1):PAGE28',
 PHYS_PAGE='28',
 XY='(-75,2825)',
 ROT='2',
 VER='1',
 PACK_TYPE='0402',
 LOCATION='C158',
 CDS_LIB='pure_quanta',
 CDS_PART_NAME='Q_CAP_0402-0.1UF,25V,10%,X7R,CA',
 TOLERANCE='10%',
 MATERIAL='X7R',
 VOLTAGE='25V',
 VALUE='0.1UF',
 PRIM_FILE='W:/<user>/logical/q_cap/chips/chips.prt';

PART_NAME
 C159 'Q_CAP_0402-0.1UF,25V,10%,X7R,CA':;

SECTION_NUMBER 1
 '@SCM_LIB.SCM(SCH_1):PAGE28_I98@PURE_QUANTA.Q_CAP(CHIPS)':
 C_PATH='@scm_lib.scm(sch_1):page28_i98@pure_quanta.q_cap(chips)',
 P_PATH='@scm_lib.scm(sch_1):page28_i98@pure_quanta.q_cap(chips)',
 PATH='I98',
 DRAWING='@SCM_LIB.SCM(SCH_1):PAGE28',
 PHYS_PAGE='28',
 XY='(1400,2925)',
 ROT='2',
 VER='1',
 PACK_TYPE='0402',
 LOCATION='C159',
 CDS_LIB='pure_quanta',
 CDS_PART_NAME='Q_CAP_0402-0.1UF,25V,10%,X7R,CA',
 TOLERANCE='10%',
 MATERIAL='X7R',
 VOLTAGE='25V',
 VALUE='0.1UF',
 PRIM_FILE='W:/<user>/logical/q_cap/chips/chips.prt';

PART_NAME
 C160 'Q_CAP_0402-0.1UF,25V,10%,X7R,CA':;

SECTION_NUMBER 1
 '@SCM_LIB.SCM(SCH_1):PAGE41_I89@PURE_QUANTA.Q_CAP(CHIPS)':
 C_PATH='@scm_lib.scm(sch_1):page41_i89@pure_quanta.q_cap(chips)',
 P_PATH='@scm_lib.scm(sch_1):page41_i89@pure_quanta.q_cap(chips)',
 PATH='I89',
 DRAWING='@SCM_LIB.SCM(SCH_1):PAGE41',
 PHYS_PAGE='41',
 XY='(-7150,2275)',
 ROT='0',
 VER='1',
 PACK_TYPE='0402',
 CDS_LIB='pure_quanta',
 CDS_PART_NAME='Q_CAP_0402-0.1UF,25V,10%,X7R,CA',
 TOLERANCE='10%',
 MATERIAL='X7R',
 VOLTAGE='25V',
 VALUE='0.1UF',
 PRIM_FILE='W:/<user>/logical/q_cap/chips/chips.prt';

PART_NAME
 C161 'Q_CAP_C0402-1UF,25V,10%,X6S,CHA':;

SECTION_NUMBER 1
 '@SCM_LIB.SCM(SCH_1):PAGE22_I23@PURE_QUANTA.Q_CAP(CHIPS)':
 C_PATH='@scm_lib.scm(sch_1):page22_i23@pure_quanta.q_cap(chips)',
 P_PATH='@scm_lib.scm(sch_1):page22_i23@pure_quanta.q_cap(chips)',
 PATH='I23',
 DRAWING='@SCM_LIB.SCM(SCH_1):PAGE22',
 PHYS_PAGE='22',
 XY='(-450,2775)',
 ROT='0',
 VER='2',
 PACK_TYPE='C0402',
 LOCATION='C161',
 CDS_LIB='pure_quanta',
 CDS_PART_NAME='Q_CAP_C0402-1UF,25V,10%,X6S,CHA',
 TOLERANCE='10%',
 MATERIAL='X6S',
 VOLTAGE='25V',
 VALUE='1UF',
 PRIM_FILE='W:/<user>/logical/q_cap/chips/chips.prt';

PART_NAME
 C162 'Q_CAP_0402-0.1UF,25V,10%,X7R,CA':;

SECTION_NUMBER 1
 '@SCM_LIB.SCM(SCH_1):PAGE41_I91@PURE_QUANTA.Q_CAP(CHIPS)':
 C_PATH='@scm_lib.scm(sch_1):page41_i91@pure_quanta.q_cap(chips)',
 P_PATH='@scm_lib.scm(sch_1):page41_i91@pure_quanta.q_cap(chips)',
 PATH='I91',
 DRAWING='@SCM_LIB.SCM(SCH_1):PAGE41',
 PHYS_PAGE='41',
 XY='(-7100,4500)',
 ROT='0',
 VER='1',
 PACK_TYPE='0402',
 CDS_LIB='pure_quanta',
 CDS_PART_NAME='Q_CAP_0402-0.1UF,25V,10%,X7R,CA',
 TOLERANCE='10%',
 MATERIAL='X7R',
 VOLTAGE='25V',
 VALUE='0.1UF',
 PRIM_FILE='W:/<user>/logical/q_cap/chips/chips.prt';

PART_NAME
 C163 'Q_CAP_C0603-10UF,16V,20%,X6S,CA':;

SECTION_NUMBER 1
 '@SCM_LIB.SCM(SCH_1):PAGE41_I122@PURE_QUANTA.Q_CAP(CHIPS)':
 C_PATH='@scm_lib.scm(sch_1):page41_i122@pure_quanta.q_cap(chips)',
 P_PATH='@scm_lib.scm(sch_1):page41_i122@pure_quanta.q_cap(chips)',
 PATH='I122',
 DRAWING='@SCM_LIB.SCM(SCH_1):PAGE41',
 PHYS_PAGE='41',
 XY='(-5225,1950)',
 ROT='0',
 VER='1',
 PACK_TYPE='C0603',
 CDS_LIB='pure_quanta',
 CDS_PART_NAME='Q_CAP_C0603-10UF,16V,20%,X6S,CA',
 TOLERANCE='20%',
 MATERIAL='X6S',
 VOLTAGE='16V',
 VALUE='10UF',
 PRIM_FILE='W:/<user>/logical/q_cap/chips/chips.prt';

PART_NAME
 C164 'Q_CAP_C0402-1UF,25V,10%,X6S,CHA':;

SECTION_NUMBER 1
 '@SCM_LIB.SCM(SCH_1):PAGE41_I92@PURE_QUANTA.Q_CAP(CHIPS)':
 C_PATH='@scm_lib.scm(sch_1):page41_i92@pure_quanta.q_cap(chips)',
 P_PATH='@scm_lib.scm(sch_1):page41_i92@pure_quanta.q_cap(chips)',
 PATH='I92',
 DRAWING='@SCM_LIB.SCM(SCH_1):PAGE41',
 PHYS_PAGE='41',
 XY='(-4725,4725)',
 ROT='0',
 VER='1',
 PACK_TYPE='C0402',
 CDS_LIB='pure_quanta',
 CDS_PART_NAME='Q_CAP_C0402-1UF,25V,10%,X6S,CHA',
 TOLERANCE='10%',
 MATERIAL='X6S',
 VOLTAGE='25V',
 VALUE='1UF',
 PRIM_FILE='W:/<user>/logical/q_cap/chips/chips.prt';

PART_NAME
 C165 'Q_CAP_C0402-1UF,25V,10%,X6S,CHA':;

SECTION_NUMBER 1
 '@SCM_LIB.SCM(SCH_1):PAGE41_I93@PURE_QUANTA.Q_CAP(CHIPS)':
 C_PATH='@scm_lib.scm(sch_1):page41_i93@pure_quanta.q_cap(chips)',
 P_PATH='@scm_lib.scm(sch_1):page41_i93@pure_quanta.q_cap(chips)',
 PATH='I93',
 DRAWING='@SCM_LIB.SCM(SCH_1):PAGE41',
 PHYS_PAGE='41',
 XY='(-4725,3625)',
 ROT='0',
 VER='1',
 PACK_TYPE='C0402',
 CDS_LIB='pure_quanta',
 CDS_PART_NAME='Q_CAP_C0402-1UF,25V,10%,X6S,CHA',
 TOLERANCE='10%',
 MATERIAL='X6S',
 VOLTAGE='25V',
 VALUE='1UF',
 PRIM_FILE='W:/<user>/logical/q_cap/chips/chips.prt';

PART_NAME
 C166 'Q_CAP_C0402-1UF,25V,10%,X6S,CHA':;

SECTION_NUMBER 1
 '@SCM_LIB.SCM(SCH_1):PAGE41_I8@PURE_QUANTA.Q_CAP(CHIPS)':
 C_PATH='@scm_lib.scm(sch_1):page41_i8@pure_quanta.q_cap(chips)',
 P_PATH='@scm_lib.scm(sch_1):page41_i8@pure_quanta.q_cap(chips)',
 PATH='I8',
 DRAWING='@SCM_LIB.SCM(SCH_1):PAGE41',
 PHYS_PAGE='41',
 XY='(-4700,5875)',
 ROT='0',
 VER='1',
 PACK_TYPE='C0402',
 CDS_LIB='pure_quanta',
 CDS_PART_NAME='Q_CAP_C0402-1UF,25V,10%,X6S,CHA',
 TOLERANCE='10%',
 MATERIAL='X6S',
 VOLTAGE='25V',
 VALUE='1UF',
 PRIM_FILE='W:/<user>/logical/q_cap/chips/chips.prt';

PART_NAME
 C167 'Q_CAP_0402-0.1UF,25V,10%,X7R,CA':;

SECTION_NUMBER 1
 '@SCM_LIB.SCM(SCH_1):PAGE41_I80@PURE_QUANTA.Q_CAP(CHIPS)':
 C_PATH='@scm_lib.scm(sch_1):page41_i80@pure_quanta.q_cap(chips)',
 P_PATH='@scm_lib.scm(sch_1):page41_i80@pure_quanta.q_cap(chips)',
 PATH='I80',
 DRAWING='@SCM_LIB.SCM(SCH_1):PAGE41',
 PHYS_PAGE='41',
 XY='(-4050,4700)',
 ROT='0',
 VER='1',
 PACK_TYPE='0402',
 CDS_LIB='pure_quanta',
 CDS_PART_NAME='Q_CAP_0402-0.1UF,25V,10%,X7R,CA',
 TOLERANCE='10%',
 MATERIAL='X7R',
 VOLTAGE='25V',
 VALUE='0.1UF',
 PRIM_FILE='W:/<user>/logical/q_cap/chips/chips.prt';

PART_NAME
 C168 'Q_CAP_0402-0.1UF,25V,10%,X7R,CA':;

SECTION_NUMBER 1
 '@SCM_LIB.SCM(SCH_1):PAGE20_I32@PURE_QUANTA.Q_CAP(CHIPS)':
 C_PATH='@scm_lib.scm(sch_1):page20_i32@pure_quanta.q_cap(chips)',
 P_PATH='@scm_lib.scm(sch_1):page20_i32@pure_quanta.q_cap(chips)',
 PATH='I32',
 DRAWING='@SCM_LIB.SCM(SCH_1):PAGE20',
 PHYS_PAGE='20',
 XY='(150,-75)',
 ROT='0',
 VER='1',
 PACK_TYPE='0402',
 LOCATION='C168',
 CDS_LIB='pure_quanta',
 CDS_PART_NAME='Q_CAP_0402-0.1UF,25V,10%,X7R,CA',
 TOLERANCE='10%',
 MATERIAL='X7R',
 VOLTAGE='25V',
 VALUE='0.1UF',
 PRIM_FILE='W:/<user>/logical/q_cap/chips/chips.prt';

PART_NAME
 C169 'Q_CAP_C0402-0.01UF,50V,10%,EMPA':;

SECTION_NUMBER 1
 '@SCM_LIB.SCM(SCH_1):PAGE20_I34@PURE_QUANTA.Q_CAP(CHIPS)':
 C_PATH='@scm_lib.scm(sch_1):page20_i34@pure_quanta.q_cap(chips)',
 P_PATH='@scm_lib.scm(sch_1):page20_i34@pure_quanta.q_cap(chips)',
 PATH='I34',
 DRAWING='@SCM_LIB.SCM(SCH_1):PAGE20',
 PHYS_PAGE='20',
 XY='(475,400)',
 ROT='0',
 VER='1',
 PACK_TYPE='C0402',
 LOCATION='C169',
 CDS_LIB='pure_quanta',
 CDS_PART_NAME='Q_CAP_C0402-0.01UF,50V,10%,EMPA',
 TOLERANCE='10%',
 MATERIAL='EMPTY',
 VOLTAGE='50V',
 VALUE='0.01UF',
 PRIM_FILE='W:/<user>/logical/q_cap/chips/chips.prt';

PART_NAME
 C170 'Q_CAP_C0402-0.01UF,50V,10%,X7RA':;

SECTION_NUMBER 1
 '@SCM_LIB.SCM(SCH_1):PAGE20_I33@PURE_QUANTA.Q_CAP(CHIPS)':
 C_PATH='@scm_lib.scm(sch_1):page20_i33@pure_quanta.q_cap(chips)',
 P_PATH='@scm_lib.scm(sch_1):page20_i33@pure_quanta.q_cap(chips)',
 PATH='I33',
 DRAWING='@SCM_LIB.SCM(SCH_1):PAGE20',
 PHYS_PAGE='20',
 XY='(550,-75)',
 ROT='0',
 VER='1',
 PACK_TYPE='C0402',
 LOCATION='C170',
 CDS_LIB='pure_quanta',
 CDS_PART_NAME='Q_CAP_C0402-0.01UF,50V,10%,X7RA',
 TOLERANCE='10%',
 MATERIAL='X7R',
 VOLTAGE='50V',
 VALUE='0.01UF',
 PRIM_FILE='W:/<user>/logical/q_cap/chips/chips.prt';

PART_NAME
 C171 'Q_CAP_C0805-22UF,10V,20%,X6S,CA':;

SECTION_NUMBER 1
 '@SCM_LIB.SCM(SCH_1):PAGE28_I38@PURE_QUANTA.Q_CAP(CHIPS)':
 C_PATH='@scm_lib.scm(sch_1):page28_i38@pure_quanta.q_cap(chips)',
 P_PATH='@scm_lib.scm(sch_1):page28_i38@pure_quanta.q_cap(chips)',
 PATH='I38',
 DRAWING='@SCM_LIB.SCM(SCH_1):PAGE28',
 PHYS_PAGE='28',
 XY='(800,600)',
 ROT='0',
 VER='1',
 PACK_TYPE='C0805',
 LOCATION='C171',
 CDS_LIB='pure_quanta',
 CDS_PART_NAME='Q_CAP_C0805-22UF,10V,20%,X6S,CA',
 TOLERANCE='20%',
 MATERIAL='X6S',
 VOLTAGE='10V',
 VALUE='22UF',
 PRIM_FILE='W:/<user>/logical/q_cap/chips/chips.prt';

PART_NAME
 C172 'Q_CAP_0402-470PF,50V,10%,X7R,TA':;

SECTION_NUMBER 1
 '@SCM_LIB.SCM(SCH_1):PAGE28_I35@PURE_QUANTA.Q_CAP(CHIPS)':
 C_PATH='@scm_lib.scm(sch_1):page28_i35@pure_quanta.q_cap(chips)',
 P_PATH='@scm_lib.scm(sch_1):page28_i35@pure_quanta.q_cap(chips)',
 PATH='I35',
 DRAWING='@SCM_LIB.SCM(SCH_1):PAGE28',
 PHYS_PAGE='28',
 XY='(1400,600)',
 ROT='0',
 VER='1',
 PACK_TYPE='0402',
 LOCATION='C172',
 CDS_LIB='pure_quanta',
 CDS_PART_NAME='Q_CAP_0402-470PF,50V,10%,X7R,TA',
 TOLERANCE='10%',
 MATERIAL='X7R',
 VOLTAGE='50V',
 VALUE='470PF',
 PRIM_FILE='W:/<user>/logical/q_cap/chips/chips.prt';

PART_NAME
 C173 'Q_CAP_0402-2200PF,50V,10%,X7R,A':;

SECTION_NUMBER 1
 '@SCM_LIB.SCM(SCH_1):PAGE22_I107@PURE_QUANTA.Q_CAP(CHIPS)':
 C_PATH='@scm_lib.scm(sch_1):page22_i107@pure_quanta.q_cap(chips)',
 P_PATH='@scm_lib.scm(sch_1):page22_i107@pure_quanta.q_cap(chips)',
 PATH='I107',
 DRAWING='@SCM_LIB.SCM(SCH_1):PAGE22',
 PHYS_PAGE='22',
 XY='(325,2550)',
 ROT='0',
 VER='1',
 PACK_TYPE='0402',
 LOCATION='C173',
 CDS_LIB='pure_quanta',
 CDS_PART_NAME='Q_CAP_0402-2200PF,50V,10%,X7R,A',
 TOLERANCE='10%',
 MATERIAL='X7R',
 VOLTAGE='50V',
 VALUE='2200PF',
 PRIM_FILE='W:/<user>/logical/q_cap/chips/chips.prt';

PART_NAME
 C174 'Q_CAP_0402-0.1UF,25V,10%,EMPTYA':;

SECTION_NUMBER 1
 '@SCM_LIB.SCM(SCH_1):PAGE10_I503@PURE_QUANTA.Q_CAP(CHIPS)':
 C_PATH='@scm_lib.scm(sch_1):page10_i503@pure_quanta.q_cap(chips)',
 P_PATH='@scm_lib.scm(sch_1):page10_i503@pure_quanta.q_cap(chips)',
 PATH='I503',
 DRAWING='@SCM_LIB.SCM(SCH_1):PAGE10',
 SEC_TYPE='0402',
 PHYS_PAGE='10',
 XY='(-4675,-50)',
 ROT='0',
 VER='1',
 PACK_TYPE='0402',
 LOCATION='C174',
 SEC='1',
 CDS_LIB='pure_quanta',
 CDS_PART_NAME='Q_CAP_0402-0.1UF,25V,10%,EMPTYA',
 TOLERANCE='10%',
 MATERIAL='EMPTY',
 VOLTAGE='25V',
 VALUE='0.1UF',
 PRIM_FILE='W:/<user>/logical/q_cap/chips/chips.prt';

PART_NAME
 C175 'Q_CAP_0402-0.1UF,25V,10%,X7R,CA':;

SECTION_NUMBER 1
 '@SCM_LIB.SCM(SCH_1):PAGE30_I151@PURE_QUANTA.Q_CAP(CHIPS)':
 C_PATH='@scm_lib.scm(sch_1):page30_i151@pure_quanta.q_cap(chips)',
 P_PATH='@scm_lib.scm(sch_1):page30_i151@pure_quanta.q_cap(chips)',
 PATH='I151',
 DRAWING='@SCM_LIB.SCM(SCH_1):PAGE30',
 PHYS_PAGE='30',
 XY='(2050,1300)',
 ROT='0',
 VER='1',
 PACK_TYPE='0402',
 LOCATION='C175',
 CDS_LIB='pure_quanta',
 CDS_PART_NAME='Q_CAP_0402-0.1UF,25V,10%,X7R,CA',
 TOLERANCE='10%',
 MATERIAL='X7R',
 VOLTAGE='25V',
 VALUE='0.1UF',
 PRIM_FILE='W:/<user>/logical/q_cap/chips/chips.prt';

PART_NAME
 C176 'Q_CAP_C0402-1UF,25V,10%,X6S,CHA':;

SECTION_NUMBER 1
 '@SCM_LIB.SCM(SCH_1):PAGE41_I108@PURE_QUANTA.Q_CAP(CHIPS)':
 C_PATH='@scm_lib.scm(sch_1):page41_i108@pure_quanta.q_cap(chips)',
 P_PATH='@scm_lib.scm(sch_1):page41_i108@pure_quanta.q_cap(chips)',
 PATH='I108',
 DRAWING='@SCM_LIB.SCM(SCH_1):PAGE41',
 SEC_TYPE='C0402',
 PHYS_PAGE='41',
 XY='(-4650,1975)',
 ROT='0',
 VER='1',
 PACK_TYPE='C0402',
 SEC='1',
 CDS_LIB='pure_quanta',
 CDS_PART_NAME='Q_CAP_C0402-1UF,25V,10%,X6S,CHA',
 TOLERANCE='10%',
 MATERIAL='X6S',
 VOLTAGE='25V',
 VALUE='1UF',
 PRIM_FILE='W:/<user>/logical/q_cap/chips/chips.prt';

PART_NAME
 C177 'Q_CAP_C1206-47UF,6.3V,20%,X6S,A':;

SECTION_NUMBER 1
 '@SCM_LIB.SCM(SCH_1):PAGE29_I219@PURE_QUANTA.Q_CAP(CHIPS)':
 C_PATH='@scm_lib.scm(sch_1):page29_i219@pure_quanta.q_cap(chips)',
 P_PATH='@scm_lib.scm(sch_1):page29_i219@pure_quanta.q_cap(chips)',
 PATH='I219',
 DRAWING='@SCM_LIB.SCM(SCH_1):PAGE29',
 PHYS_PAGE='29',
 XY='(825,1450)',
 ROT='0',
 VER='1',
 PACK_TYPE='C1206',
 LOCATION='C177',
 CDS_LIB='pure_quanta',
 CDS_PART_NAME='Q_CAP_C1206-47UF,6.3V,20%,X6S,A',
 TOLERANCE='20%',
 MATERIAL='X6S',
 VOLTAGE='6.3V',
 VALUE='47UF',
 PRIM_FILE='W:/<user>/logical/q_cap/chips/chips.prt';

PART_NAME
 C178 'Q_CAP_0402-470PF,50V,10%,X7R,TA':;

SECTION_NUMBER 1
 '@SCM_LIB.SCM(SCH_1):PAGE29_I194@PURE_QUANTA.Q_CAP(CHIPS)':
 C_PATH='@scm_lib.scm(sch_1):page29_i194@pure_quanta.q_cap(chips)',
 P_PATH='@scm_lib.scm(sch_1):page29_i194@pure_quanta.q_cap(chips)',
 PATH='I194',
 DRAWING='@SCM_LIB.SCM(SCH_1):PAGE29',
 PHYS_PAGE='29',
 XY='(1400,1450)',
 ROT='0',
 VER='1',
 PACK_TYPE='0402',
 LOCATION='C178',
 CDS_LIB='pure_quanta',
 CDS_PART_NAME='Q_CAP_0402-470PF,50V,10%,X7R,TA',
 TOLERANCE='10%',
 MATERIAL='X7R',
 VOLTAGE='50V',
 VALUE='470PF',
 PRIM_FILE='W:/<user>/logical/q_cap/chips/chips.prt';

PART_NAME
 C179 'Q_CAP_0402-470PF,50V,10%,X7R,TA':;

SECTION_NUMBER 1
 '@SCM_LIB.SCM(SCH_1):PAGE29_I193@PURE_QUANTA.Q_CAP(CHIPS)':
 C_PATH='@scm_lib.scm(sch_1):page29_i193@pure_quanta.q_cap(chips)',
 P_PATH='@scm_lib.scm(sch_1):page29_i193@pure_quanta.q_cap(chips)',
 PATH='I193',
 DRAWING='@SCM_LIB.SCM(SCH_1):PAGE29',
 PHYS_PAGE='29',
 XY='(1750,1450)',
 ROT='0',
 VER='1',
 PACK_TYPE='0402',
 LOCATION='C179',
 CDS_LIB='pure_quanta',
 CDS_PART_NAME='Q_CAP_0402-470PF,50V,10%,X7R,TA',
 TOLERANCE='10%',
 MATERIAL='X7R',
 VOLTAGE='50V',
 VALUE='470PF',
 PRIM_FILE='W:/<user>/logical/q_cap/chips/chips.prt';

PART_NAME
 C180 'Q_CAP_0402-0.1UF,25V,10%,X7R,CA':;

SECTION_NUMBER 1
 '@SCM_LIB.SCM(SCH_1):PAGE13_I440@PURE_QUANTA.Q_CAP(CHIPS)':
 C_PATH='@scm_lib.scm(sch_1):page13_i440@pure_quanta.q_cap(chips)',
 P_PATH='@scm_lib.scm(sch_1):page13_i440@pure_quanta.q_cap(chips)',
 PATH='I440',
 DRAWING='@SCM_LIB.SCM(SCH_1):PAGE13',
 PHYS_PAGE='13',
 XY='(-1175,5025)',
 ROT='2',
 VER='1',
 PACK_TYPE='0402',
 CDS_LIB='pure_quanta',
 CDS_PART_NAME='Q_CAP_0402-0.1UF,25V,10%,X7R,CA',
 TOLERANCE='10%',
 MATERIAL='X7R',
 VOLTAGE='25V',
 VALUE='0.1UF',
 PRIM_FILE='W:/<user>/logical/q_cap/chips/chips.prt';

PART_NAME
 C181 'Q_CAP_0402-0.1UF,25V,10%,X7R,CA':;

SECTION_NUMBER 1
 '@SCM_LIB.SCM(SCH_1):PAGE50_I246@PURE_QUANTA.Q_CAP(CHIPS)':
 C_PATH='@scm_lib.scm(sch_1):page50_i246@pure_quanta.q_cap(chips)',
 P_PATH='@scm_lib.scm(sch_1):page50_i246@pure_quanta.q_cap(chips)',
 PATH='I246',
 DRAWING='@SCM_LIB.SCM(SCH_1):PAGE50',
 PHYS_PAGE='50',
 XY='(3800,2075)',
 ROT='2',
 VER='1',
 PACK_TYPE='0402',
 CDS_LIB='pure_quanta',
 CDS_PART_NAME='Q_CAP_0402-0.1UF,25V,10%,X7R,CA',
 TOLERANCE='10%',
 MATERIAL='X7R',
 VOLTAGE='25V',
 VALUE='0.1UF',
 PRIM_FILE='W:/<user>/logical/q_cap/chips/chips.prt';

PART_NAME
 C187 'Q_CAP_0402-0.1UF,25V,10%,X7R,CA':;

SECTION_NUMBER 1
 '@SCM_LIB.SCM(SCH_1):PAGE41_I84@PURE_QUANTA.Q_CAP(CHIPS)':
 C_PATH='@scm_lib.scm(sch_1):page41_i84@pure_quanta.q_cap(chips)',
 P_PATH='@scm_lib.scm(sch_1):page41_i84@pure_quanta.q_cap(chips)',
 PATH='I84',
 DRAWING='@SCM_LIB.SCM(SCH_1):PAGE41',
 PHYS_PAGE='41',
 XY='(-4050,3600)',
 ROT='0',
 VER='1',
 PACK_TYPE='0402',
 CDS_LIB='pure_quanta',
 CDS_PART_NAME='Q_CAP_0402-0.1UF,25V,10%,X7R,CA',
 TOLERANCE='10%',
 MATERIAL='X7R',
 VOLTAGE='25V',
 VALUE='0.1UF',
 PRIM_FILE='W:/<user>/logical/q_cap/chips/chips.prt';

PART_NAME
 C188 'Q_CAP_0402-0.1UF,25V,10%,X7R,CA':;

SECTION_NUMBER 1
 '@SCM_LIB.SCM(SCH_1):PAGE41_I86@PURE_QUANTA.Q_CAP(CHIPS)':
 C_PATH='@scm_lib.scm(sch_1):page41_i86@pure_quanta.q_cap(chips)',
 P_PATH='@scm_lib.scm(sch_1):page41_i86@pure_quanta.q_cap(chips)',
 PATH='I86',
 DRAWING='@SCM_LIB.SCM(SCH_1):PAGE41',
 PHYS_PAGE='41',
 XY='(-2850,3600)',
 ROT='0',
 VER='1',
 PACK_TYPE='0402',
 CDS_LIB='pure_quanta',
 CDS_PART_NAME='Q_CAP_0402-0.1UF,25V,10%,X7R,CA',
 TOLERANCE='10%',
 MATERIAL='X7R',
 VOLTAGE='25V',
 VALUE='0.1UF',
 PRIM_FILE='W:/<user>/logical/q_cap/chips/chips.prt';

PART_NAME
 C189 'Q_CAP_0402-0.1UF,25V,10%,X7R,CA':;

SECTION_NUMBER 1
 '@SCM_LIB.SCM(SCH_1):PAGE41_I78@PURE_QUANTA.Q_CAP(CHIPS)':
 C_PATH='@scm_lib.scm(sch_1):page41_i78@pure_quanta.q_cap(chips)',
 P_PATH='@scm_lib.scm(sch_1):page41_i78@pure_quanta.q_cap(chips)',
 PATH='I78',
 DRAWING='@SCM_LIB.SCM(SCH_1):PAGE41',
 PHYS_PAGE='41',
 XY='(-2825,5850)',
 ROT='0',
 VER='1',
 PACK_TYPE='0402',
 CDS_LIB='pure_quanta',
 CDS_PART_NAME='Q_CAP_0402-0.1UF,25V,10%,X7R,CA',
 TOLERANCE='10%',
 MATERIAL='X7R',
 VOLTAGE='25V',
 VALUE='0.1UF',
 PRIM_FILE='W:/<user>/logical/q_cap/chips/chips.prt';

PART_NAME
 C190 'Q_CAP_0402-0.1UF,25V,10%,X7R,CA':;

SECTION_NUMBER 1
 '@SCM_LIB.SCM(SCH_1):PAGE41_I116@PURE_QUANTA.Q_CAP(CHIPS)':
 C_PATH='@scm_lib.scm(sch_1):page41_i116@pure_quanta.q_cap(chips)',
 P_PATH='@scm_lib.scm(sch_1):page41_i116@pure_quanta.q_cap(chips)',
 PATH='I116',
 DRAWING='@SCM_LIB.SCM(SCH_1):PAGE41',
 PHYS_PAGE='41',
 XY='(-2875,1950)',
 ROT='0',
 VER='1',
 PACK_TYPE='0402',
 CDS_LIB='pure_quanta',
 CDS_PART_NAME='Q_CAP_0402-0.1UF,25V,10%,X7R,CA',
 TOLERANCE='10%',
 MATERIAL='X7R',
 VOLTAGE='25V',
 VALUE='0.1UF',
 PRIM_FILE='W:/<user>/logical/q_cap/chips/chips.prt';

PART_NAME
 C191 'Q_CAP_0402-0.1UF,25V,10%,X7R,CA':;

SECTION_NUMBER 1
 '@SCM_LIB.SCM(SCH_1):PAGE26_I54@PURE_QUANTA.Q_CAP(CHIPS)':
 C_PATH='@scm_lib.scm(sch_1):page26_i54@pure_quanta.q_cap(chips)',
 P_PATH='@scm_lib.scm(sch_1):page26_i54@pure_quanta.q_cap(chips)',
 PATH='I54',
 DRAWING='@SCM_LIB.SCM(SCH_1):PAGE26',
 PHYS_PAGE='26',
 XY='(-125,3775)',
 ROT='0',
 VER='1',
 PACK_TYPE='0402',
 LOCATION='C191',
 CDS_LIB='pure_quanta',
 CDS_PART_NAME='Q_CAP_0402-0.1UF,25V,10%,X7R,CA',
 TOLERANCE='10%',
 MATERIAL='X7R',
 VOLTAGE='25V',
 VALUE='0.1UF',
 PRIM_FILE='W:/<user>/logical/q_cap/chips/chips.prt';

PART_NAME
 C192 'Q_CAP_0402-0.1UF,25V,10%,X7R,CA':;

SECTION_NUMBER 1
 '@SCM_LIB.SCM(SCH_1):PAGE26_I17@PURE_QUANTA.Q_CAP(CHIPS)':
 C_PATH='@scm_lib.scm(sch_1):page26_i17@pure_quanta.q_cap(chips)',
 P_PATH='@scm_lib.scm(sch_1):page26_i17@pure_quanta.q_cap(chips)',
 PATH='I17',
 DRAWING='@SCM_LIB.SCM(SCH_1):PAGE26',
 PHYS_PAGE='26',
 XY='(875,1150)',
 ROT='0',
 VER='1',
 PACK_TYPE='0402',
 LOCATION='C192',
 CDS_LIB='pure_quanta',
 CDS_PART_NAME='Q_CAP_0402-0.1UF,25V,10%,X7R,CA',
 TOLERANCE='10%',
 MATERIAL='X7R',
 VOLTAGE='25V',
 VALUE='0.1UF',
 PRIM_FILE='W:/<user>/logical/q_cap/chips/chips.prt';

PART_NAME
 C193 'Q_CAP_0402-0.1UF,25V,10%,X7R,CA':;

SECTION_NUMBER 1
 '@SCM_LIB.SCM(SCH_1):PAGE41_I109@PURE_QUANTA.Q_CAP(CHIPS)':
 C_PATH='@scm_lib.scm(sch_1):page41_i109@pure_quanta.q_cap(chips)',
 P_PATH='@scm_lib.scm(sch_1):page41_i109@pure_quanta.q_cap(chips)',
 PATH='I109',
 DRAWING='@SCM_LIB.SCM(SCH_1):PAGE41',
 SEC_TYPE='0402',
 PHYS_PAGE='41',
 XY='(-4075,1950)',
 ROT='0',
 VER='1',
 PACK_TYPE='0402',
 SEC='1',
 CDS_LIB='pure_quanta',
 CDS_PART_NAME='Q_CAP_0402-0.1UF,25V,10%,X7R,CA',
 TOLERANCE='10%',
 MATERIAL='X7R',
 VOLTAGE='25V',
 VALUE='0.1UF',
 PRIM_FILE='W:/<user>/logical/q_cap/chips/chips.prt';

PART_NAME
 C194 'Q_CAP_C0603-10UF,16V,20%,X6S,CA':;

SECTION_NUMBER 1
 '@SCM_LIB.SCM(SCH_1):PAGE41_I101@PURE_QUANTA.Q_CAP(CHIPS)':
 C_PATH='@scm_lib.scm(sch_1):page41_i101@pure_quanta.q_cap(chips)',
 P_PATH='@scm_lib.scm(sch_1):page41_i101@pure_quanta.q_cap(chips)',
 PATH='I101',
 DRAWING='@SCM_LIB.SCM(SCH_1):PAGE41',
 PHYS_PAGE='41',
 XY='(-7900,5700)',
 ROT='0',
 VER='1',
 PACK_TYPE='C0603',
 CDS_LIB='pure_quanta',
 CDS_PART_NAME='Q_CAP_C0603-10UF,16V,20%,X6S,CA',
 TOLERANCE='20%',
 MATERIAL='X6S',
 VOLTAGE='16V',
 VALUE='10UF',
 PRIM_FILE='W:/<user>/logical/q_cap/chips/chips.prt';

PART_NAME
 C195 'Q_CAP_C0402-1UF,25V,10%,X6S,CHA':;

SECTION_NUMBER 1
 '@SCM_LIB.SCM(SCH_1):PAGE41_I96@PURE_QUANTA.Q_CAP(CHIPS)':
 C_PATH='@scm_lib.scm(sch_1):page41_i96@pure_quanta.q_cap(chips)',
 P_PATH='@scm_lib.scm(sch_1):page41_i96@pure_quanta.q_cap(chips)',
 PATH='I96',
 DRAWING='@SCM_LIB.SCM(SCH_1):PAGE41',
 PHYS_PAGE='41',
 XY='(-8175,4525)',
 ROT='0',
 VER='1',
 PACK_TYPE='C0402',
 CDS_LIB='pure_quanta',
 CDS_PART_NAME='Q_CAP_C0402-1UF,25V,10%,X6S,CHA',
 TOLERANCE='10%',
 MATERIAL='X6S',
 VOLTAGE='25V',
 VALUE='1UF',
 PRIM_FILE='W:/<user>/logical/q_cap/chips/chips.prt';

PART_NAME
 C196 'Q_CAP_C0402-1UF,25V,10%,X6S,CHA':;

SECTION_NUMBER 1
 '@SCM_LIB.SCM(SCH_1):PAGE50_I165@PURE_QUANTA.Q_CAP(CHIPS)':
 C_PATH='@scm_lib.scm(sch_1):page50_i165@pure_quanta.q_cap(chips)',
 P_PATH='@scm_lib.scm(sch_1):page50_i165@pure_quanta.q_cap(chips)',
 PATH='I165',
 DRAWING='@SCM_LIB.SCM(SCH_1):PAGE50',
 PHYS_PAGE='50',
 XY='(4650,4700)',
 ROT='0',
 VER='1',
 PACK_TYPE='C0402',
 LOCATION='C196',
 CDS_LIB='pure_quanta',
 CDS_PART_NAME='Q_CAP_C0402-1UF,25V,10%,X6S,CHA',
 TOLERANCE='10%',
 MATERIAL='X6S',
 VOLTAGE='25V',
 VALUE='1UF',
 PRIM_FILE='W:/<user>/logical/q_cap/chips/chips.prt';

PART_NAME
 C197 'Q_CAP_0402-0.1UF,25V,10%,X7R,CA':;

SECTION_NUMBER 1
 '@SCM_LIB.SCM(SCH_1):PAGE49_I45@PURE_QUANTA.Q_CAP(CHIPS)':
 C_PATH='@scm_lib.scm(sch_1):page49_i45@pure_quanta.q_cap(chips)',
 P_PATH='@scm_lib.scm(sch_1):page49_i45@pure_quanta.q_cap(chips)',
 PATH='I45',
 DRAWING='@SCM_LIB.SCM(SCH_1):PAGE49',
 PHYS_PAGE='49',
 XY='(-4975,2150)',
 ROT='0',
 VER='1',
 PACK_TYPE='0402',
 LOCATION='C197',
 CDS_LIB='pure_quanta',
 CDS_PART_NAME='Q_CAP_0402-0.1UF,25V,10%,X7R,CA',
 TOLERANCE='10%',
 MATERIAL='X7R',
 VOLTAGE='25V',
 VALUE='0.1UF',
 PRIM_FILE='W:/<user>/logical/q_cap/chips/chips.prt';

PART_NAME
 C198 'Q_CAP_C0402-1UF,25V,10%,X6S,CHA':;

SECTION_NUMBER 1
 '@SCM_LIB.SCM(SCH_1):PAGE50_I44@PURE_QUANTA.Q_CAP(CHIPS)':
 C_PATH='@scm_lib.scm(sch_1):page50_i44@pure_quanta.q_cap(chips)',
 P_PATH='@scm_lib.scm(sch_1):page50_i44@pure_quanta.q_cap(chips)',
 PATH='I44',
 DRAWING='@SCM_LIB.SCM(SCH_1):PAGE50',
 PHYS_PAGE='50',
 XY='(-1175,4375)',
 ROT='0',
 VER='1',
 PACK_TYPE='C0402',
 LOCATION='C198',
 CDS_LIB='pure_quanta',
 CDS_PART_NAME='Q_CAP_C0402-1UF,25V,10%,X6S,CHA',
 TOLERANCE='10%',
 MATERIAL='X6S',
 VOLTAGE='25V',
 VALUE='1UF',
 PRIM_FILE='W:/<user>/logical/q_cap/chips/chips.prt';

PART_NAME
 C199 'Q_CAP_C0402-1UF,25V,10%,X6S,CHA':;

SECTION_NUMBER 1
 '@SCM_LIB.SCM(SCH_1):PAGE50_I55@PURE_QUANTA.Q_CAP(CHIPS)':
 C_PATH='@scm_lib.scm(sch_1):page50_i55@pure_quanta.q_cap(chips)',
 P_PATH='@scm_lib.scm(sch_1):page50_i55@pure_quanta.q_cap(chips)',
 PATH='I55',
 DRAWING='@SCM_LIB.SCM(SCH_1):PAGE50',
 PHYS_PAGE='50',
 XY='(-1150,2975)',
 ROT='0',
 VER='1',
 PACK_TYPE='C0402',
 LOCATION='C199',
 CDS_LIB='pure_quanta',
 CDS_PART_NAME='Q_CAP_C0402-1UF,25V,10%,X6S,CHA',
 TOLERANCE='10%',
 MATERIAL='X6S',
 VOLTAGE='25V',
 VALUE='1UF',
 PRIM_FILE='W:/<user>/logical/q_cap/chips/chips.prt';

PART_NAME
 C200 'Q_CAP_0402-0.1UF,25V,10%,X7R,CA':;

SECTION_NUMBER 1
 '@SCM_LIB.SCM(SCH_1):PAGE50_I43@PURE_QUANTA.Q_CAP(CHIPS)':
 C_PATH='@scm_lib.scm(sch_1):page50_i43@pure_quanta.q_cap(chips)',
 P_PATH='@scm_lib.scm(sch_1):page50_i43@pure_quanta.q_cap(chips)',
 PATH='I43',
 DRAWING='@SCM_LIB.SCM(SCH_1):PAGE50',
 PHYS_PAGE='50',
 XY='(-475,5050)',
 ROT='2',
 VER='1',
 PACK_TYPE='0402',
 LOCATION='C200',
 CDS_LIB='pure_quanta',
 CDS_PART_NAME='Q_CAP_0402-0.1UF,25V,10%,X7R,CA',
 TOLERANCE='10%',
 MATERIAL='X7R',
 VOLTAGE='25V',
 VALUE='0.1UF',
 PRIM_FILE='W:/<user>/logical/q_cap/chips/chips.prt';

PART_NAME
 C201 'Q_CAP_0402-0.1UF,25V,10%,X7R,CA':;

SECTION_NUMBER 1
 '@SCM_LIB.SCM(SCH_1):PAGE50_I51@PURE_QUANTA.Q_CAP(CHIPS)':
 C_PATH='@scm_lib.scm(sch_1):page50_i51@pure_quanta.q_cap(chips)',
 P_PATH='@scm_lib.scm(sch_1):page50_i51@pure_quanta.q_cap(chips)',
 PATH='I51',
 DRAWING='@SCM_LIB.SCM(SCH_1):PAGE50',
 PHYS_PAGE='50',
 XY='(-450,3650)',
 ROT='2',
 VER='1',
 PACK_TYPE='0402',
 LOCATION='C201',
 CDS_LIB='pure_quanta',
 CDS_PART_NAME='Q_CAP_0402-0.1UF,25V,10%,X7R,CA',
 TOLERANCE='10%',
 MATERIAL='X7R',
 VOLTAGE='25V',
 VALUE='0.1UF',
 PRIM_FILE='W:/<user>/logical/q_cap/chips/chips.prt';

PART_NAME
 C202 'Q_CAP_0402-0.1UF,25V,10%,X7R,CA':;

SECTION_NUMBER 1
 '@SCM_LIB.SCM(SCH_1):PAGE23_I11@PURE_QUANTA.Q_CAP(CHIPS)':
 C_PATH='@scm_lib.scm(sch_1):page23_i11@pure_quanta.q_cap(chips)',
 P_PATH='@scm_lib.scm(sch_1):page23_i11@pure_quanta.q_cap(chips)',
 PATH='I11',
 DRAWING='@SCM_LIB.SCM(SCH_1):PAGE23',
 PHYS_PAGE='23',
 XY='(-2100,575)',
 ROT='0',
 VER='1',
 PACK_TYPE='0402',
 LOCATION='C202',
 CDS_LIB='pure_quanta',
 CDS_PART_NAME='Q_CAP_0402-0.1UF,25V,10%,X7R,CA',
 TOLERANCE='10%',
 MATERIAL='X7R',
 VOLTAGE='25V',
 VALUE='0.1UF',
 PRIM_FILE='W:/<user>/logical/q_cap/chips/chips.prt';

PART_NAME
 C203 'Q_CAP_0402-0.1UF,25V,10%,X7R,CA':;

SECTION_NUMBER 1
 '@SCM_LIB.SCM(SCH_1):PAGE23_I12@PURE_QUANTA.Q_CAP(CHIPS)':
 C_PATH='@scm_lib.scm(sch_1):page23_i12@pure_quanta.q_cap(chips)',
 P_PATH='@scm_lib.scm(sch_1):page23_i12@pure_quanta.q_cap(chips)',
 PATH='I12',
 DRAWING='@SCM_LIB.SCM(SCH_1):PAGE23',
 PHYS_PAGE='23',
 XY='(-1875,575)',
 ROT='0',
 VER='1',
 PACK_TYPE='0402',
 LOCATION='C203',
 CDS_LIB='pure_quanta',
 CDS_PART_NAME='Q_CAP_0402-0.1UF,25V,10%,X7R,CA',
 TOLERANCE='10%',
 MATERIAL='X7R',
 VOLTAGE='25V',
 VALUE='0.1UF',
 PRIM_FILE='W:/<user>/logical/q_cap/chips/chips.prt';

PART_NAME
 C204 'Q_CAP_0603-1UF,16V,10%,EMPTY,TA':;

SECTION_NUMBER 1
 '@SCM_LIB.SCM(SCH_1):PAGE23_I45@PURE_QUANTA.Q_CAP(CHIPS)':
 C_PATH='@scm_lib.scm(sch_1):page23_i45@pure_quanta.q_cap(chips)',
 P_PATH='@scm_lib.scm(sch_1):page23_i45@pure_quanta.q_cap(chips)',
 PATH='I45',
 DRAWING='@SCM_LIB.SCM(SCH_1):PAGE23',
 PHYS_PAGE='23',
 XY='(-1425,3875)',
 ROT='0',
 VER='1',
 PACK_TYPE='0603',
 LOCATION='C204',
 CDS_LIB='pure_quanta',
 CDS_PART_NAME='Q_CAP_0603-1UF,16V,10%,EMPTY,TA',
 TOLERANCE='10%',
 MATERIAL='EMPTY',
 VOLTAGE='16V',
 VALUE='1UF',
 PRIM_FILE='W:/<user>/logical/q_cap/chips/chips.prt';

PART_NAME
 C205 'Q_CAP_0402-15PF,50V,5%,C0G,CH0A':;

SECTION_NUMBER 1
 '@SCM_LIB.SCM(SCH_1):PAGE23_I25@PURE_QUANTA.Q_CAP(CHIPS)':
 C_PATH='@scm_lib.scm(sch_1):page23_i25@pure_quanta.q_cap(chips)',
 P_PATH='@scm_lib.scm(sch_1):page23_i25@pure_quanta.q_cap(chips)',
 PATH='I25',
 DRAWING='@SCM_LIB.SCM(SCH_1):PAGE23',
 PHYS_PAGE='23',
 XY='(-1150,1075)',
 ROT='0',
 VER='1',
 PACK_TYPE='0402',
 LOCATION='C205',
 CDS_LIB='pure_quanta',
 CDS_PART_NAME='Q_CAP_0402-15PF,50V,5%,C0G,CH0A',
 TOLERANCE='5%',
 MATERIAL='C0G',
 VOLTAGE='50V',
 VALUE='15PF',
 PRIM_FILE='W:/<user>/logical/q_cap/chips/chips.prt';

PART_NAME
 C206 'Q_CAP_0402-15PF,50V,5%,C0G,CH0A':;

SECTION_NUMBER 1
 '@SCM_LIB.SCM(SCH_1):PAGE23_I26@PURE_QUANTA.Q_CAP(CHIPS)':
 C_PATH='@scm_lib.scm(sch_1):page23_i26@pure_quanta.q_cap(chips)',
 P_PATH='@scm_lib.scm(sch_1):page23_i26@pure_quanta.q_cap(chips)',
 PATH='I26',
 DRAWING='@SCM_LIB.SCM(SCH_1):PAGE23',
 PHYS_PAGE='23',
 XY='(-775,1075)',
 ROT='0',
 VER='1',
 PACK_TYPE='0402',
 LOCATION='C206',
 CDS_LIB='pure_quanta',
 CDS_PART_NAME='Q_CAP_0402-15PF,50V,5%,C0G,CH0A',
 TOLERANCE='5%',
 MATERIAL='C0G',
 VOLTAGE='50V',
 VALUE='15PF',
 PRIM_FILE='W:/<user>/logical/q_cap/chips/chips.prt';

PART_NAME
 C207 'Q_CAP_0402-15PF,50V,5%,C0G,CH0A':;

SECTION_NUMBER 1
 '@SCM_LIB.SCM(SCH_1):PAGE23_I29@PURE_QUANTA.Q_CAP(CHIPS)':
 C_PATH='@scm_lib.scm(sch_1):page23_i29@pure_quanta.q_cap(chips)',
 P_PATH='@scm_lib.scm(sch_1):page23_i29@pure_quanta.q_cap(chips)',
 PATH='I29',
 DRAWING='@SCM_LIB.SCM(SCH_1):PAGE23',
 PHYS_PAGE='23',
 XY='(-425,1075)',
 ROT='0',
 VER='1',
 PACK_TYPE='0402',
 LOCATION='C207',
 CDS_LIB='pure_quanta',
 CDS_PART_NAME='Q_CAP_0402-15PF,50V,5%,C0G,CH0A',
 TOLERANCE='5%',
 MATERIAL='C0G',
 VOLTAGE='50V',
 VALUE='15PF',
 PRIM_FILE='W:/<user>/logical/q_cap/chips/chips.prt';

PART_NAME
 C208 'Q_CAP_0402-22PF,50V,5%,NPO,TMPA':;

SECTION_NUMBER 1
 '@SCM_LIB.SCM(SCH_1):PAGE23_I169@PURE_QUANTA.Q_CAP(CHIPS)':
 C_PATH='@scm_lib.scm(sch_1):page23_i169@pure_quanta.q_cap(chips)',
 P_PATH='@scm_lib.scm(sch_1):page23_i169@pure_quanta.q_cap(chips)',
 PATH='I169',
 DRAWING='@SCM_LIB.SCM(SCH_1):PAGE23',
 PHYS_PAGE='23',
 XY='(175,1100)',
 ROT='0',
 VER='1',
 PACK_TYPE='0402',
 LOCATION='C208',
 CDS_LIB='pure_quanta',
 CDS_PART_NAME='Q_CAP_0402-22PF,50V,5%,NPO,TMPA',
 TOLERANCE='5%',
 MATERIAL='NPO',
 VOLTAGE='50V',
 VALUE='22PF',
 PRIM_FILE='W:/<user>/logical/q_cap/chips/chips.prt';

PART_NAME
 C209 'Q_CAP_0402-18PF,50V,5%,C0G,CH0A':;

SECTION_NUMBER 1
 '@SCM_LIB.SCM(SCH_1):PAGE23_I54@PURE_QUANTA.Q_CAP(CHIPS)':
 C_PATH='@scm_lib.scm(sch_1):page23_i54@pure_quanta.q_cap(chips)',
 P_PATH='@scm_lib.scm(sch_1):page23_i54@pure_quanta.q_cap(chips)',
 PATH='I54',
 DRAWING='@SCM_LIB.SCM(SCH_1):PAGE23',
 PHYS_PAGE='23',
 XY='(575,1100)',
 ROT='0',
 VER='1',
 PACK_TYPE='0402',
 LOCATION='C209',
 CDS_LIB='pure_quanta',
 CDS_PART_NAME='Q_CAP_0402-18PF,50V,5%,C0G,CH0A',
 TOLERANCE='5%',
 MATERIAL='C0G',
 VOLTAGE='50V',
 VALUE='18PF',
 PRIM_FILE='W:/<user>/logical/q_cap/chips/chips.prt';

PART_NAME
 C210 'Q_CAP_0402-22PF,50V,5%,NPO,TMPA':;

SECTION_NUMBER 1
 '@SCM_LIB.SCM(SCH_1):PAGE23_I170@PURE_QUANTA.Q_CAP(CHIPS)':
 C_PATH='@scm_lib.scm(sch_1):page23_i170@pure_quanta.q_cap(chips)',
 P_PATH='@scm_lib.scm(sch_1):page23_i170@pure_quanta.q_cap(chips)',
 PATH='I170',
 DRAWING='@SCM_LIB.SCM(SCH_1):PAGE23',
 PHYS_PAGE='23',
 XY='(975,1100)',
 ROT='0',
 VER='1',
 PACK_TYPE='0402',
 LOCATION='C210',
 CDS_LIB='pure_quanta',
 CDS_PART_NAME='Q_CAP_0402-22PF,50V,5%,NPO,TMPA',
 TOLERANCE='5%',
 MATERIAL='NPO',
 VOLTAGE='50V',
 VALUE='22PF',
 PRIM_FILE='W:/<user>/logical/q_cap/chips/chips.prt';

PART_NAME
 C211 'Q_CAP_0402-10PF,50V,1%,NPO,TMPA':;

SECTION_NUMBER 1
 '@SCM_LIB.SCM(SCH_1):PAGE23_I67@PURE_QUANTA.Q_CAP(CHIPS)':
 C_PATH='@scm_lib.scm(sch_1):page23_i67@pure_quanta.q_cap(chips)',
 P_PATH='@scm_lib.scm(sch_1):page23_i67@pure_quanta.q_cap(chips)',
 PATH='I67',
 DRAWING='@SCM_LIB.SCM(SCH_1):PAGE23',
 PHYS_PAGE='23',
 XY='(4750,700)',
 ROT='0',
 VER='1',
 PACK_TYPE='0402',
 LOCATION='C211',
 CDS_LIB='pure_quanta',
 CDS_PART_NAME='Q_CAP_0402-10PF,50V,1%,NPO,TMPA',
 TOLERANCE='1%',
 MATERIAL='NPO',
 VOLTAGE='50V',
 VALUE='10PF',
 PRIM_FILE='W:/<user>/logical/q_cap/chips/chips.prt';

PART_NAME
 C212 'Q_CAP_0402-10PF,50V,1%,NPO,TMPA':;

SECTION_NUMBER 1
 '@SCM_LIB.SCM(SCH_1):PAGE23_I77@PURE_QUANTA.Q_CAP(CHIPS)':
 C_PATH='@scm_lib.scm(sch_1):page23_i77@pure_quanta.q_cap(chips)',
 P_PATH='@scm_lib.scm(sch_1):page23_i77@pure_quanta.q_cap(chips)',
 PATH='I77',
 DRAWING='@SCM_LIB.SCM(SCH_1):PAGE23',
 PHYS_PAGE='23',
 XY='(5200,700)',
 ROT='0',
 VER='1',
 PACK_TYPE='0402',
 LOCATION='C212',
 CDS_LIB='pure_quanta',
 CDS_PART_NAME='Q_CAP_0402-10PF,50V,1%,NPO,TMPA',
 TOLERANCE='1%',
 MATERIAL='NPO',
 VOLTAGE='50V',
 VALUE='10PF',
 PRIM_FILE='W:/<user>/logical/q_cap/chips/chips.prt';

PART_NAME
 C213 'Q_CAP_0402-100PF,50V,5%,EMPTY,A':;

SECTION_NUMBER 1
 '@SCM_LIB.SCM(SCH_1):PAGE23_I83@PURE_QUANTA.Q_CAP(CHIPS)':
 C_PATH='@scm_lib.scm(sch_1):page23_i83@pure_quanta.q_cap(chips)',
 P_PATH='@scm_lib.scm(sch_1):page23_i83@pure_quanta.q_cap(chips)',
 PATH='I83',
 DRAWING='@SCM_LIB.SCM(SCH_1):PAGE23',
 PHYS_PAGE='23',
 XY='(5600,700)',
 ROT='0',
 VER='1',
 PACK_TYPE='0402',
 LOCATION='C213',
 CDS_LIB='pure_quanta',
 CDS_PART_NAME='Q_CAP_0402-100PF,50V,5%,EMPTY,A',
 TOLERANCE='5%',
 MATERIAL='EMPTY',
 VOLTAGE='50V',
 VALUE='100PF',
 PRIM_FILE='W:/<user>/logical/q_cap/chips/chips.prt';

PART_NAME
 C214 'Q_CAP_0402-100PF,50V,5%,EMPTY,A':;

SECTION_NUMBER 1
 '@SCM_LIB.SCM(SCH_1):PAGE23_I84@PURE_QUANTA.Q_CAP(CHIPS)':
 C_PATH='@scm_lib.scm(sch_1):page23_i84@pure_quanta.q_cap(chips)',
 P_PATH='@scm_lib.scm(sch_1):page23_i84@pure_quanta.q_cap(chips)',
 PATH='I84',
 DRAWING='@SCM_LIB.SCM(SCH_1):PAGE23',
 PHYS_PAGE='23',
 XY='(6000,700)',
 ROT='0',
 VER='1',
 PACK_TYPE='0402',
 LOCATION='C214',
 CDS_LIB='pure_quanta',
 CDS_PART_NAME='Q_CAP_0402-100PF,50V,5%,EMPTY,A',
 TOLERANCE='5%',
 MATERIAL='EMPTY',
 VOLTAGE='50V',
 VALUE='100PF',
 PRIM_FILE='W:/<user>/logical/q_cap/chips/chips.prt';

PART_NAME
 C215 'Q_CAP_C0402-10UF,6.3V,20%,X6S,A':;

SECTION_NUMBER 1
 '@SCM_LIB.SCM(SCH_1):PAGE32_I22@PURE_QUANTA.Q_CAP(CHIPS)':
 C_PATH='@scm_lib.scm(sch_1):page32_i22@pure_quanta.q_cap(chips)',
 P_PATH='@scm_lib.scm(sch_1):page32_i22@pure_quanta.q_cap(chips)',
 PATH='I22',
 DRAWING='@SCM_LIB.SCM(SCH_1):PAGE32',
 PHYS_PAGE='32',
 XY='(3275,4000)',
 ROT='0',
 VER='1',
 PACK_TYPE='C0402',
 LOCATION='C215',
 CDS_LIB='pure_quanta',
 CDS_PART_NAME='Q_CAP_C0402-10UF,6.3V,20%,X6S,A',
 TOLERANCE='20%',
 MATERIAL='X6S',
 VOLTAGE='6.3V',
 VALUE='10UF',
 PRIM_FILE='W:/<user>/logical/q_cap/chips/chips.prt';

PART_NAME
 C216 'Q_CAP_C0402-1UF,25V,10%,X6S,CHA':;

SECTION_NUMBER 1
 '@SCM_LIB.SCM(SCH_1):PAGE41_I94@PURE_QUANTA.Q_CAP(CHIPS)':
 C_PATH='@scm_lib.scm(sch_1):page41_i94@pure_quanta.q_cap(chips)',
 P_PATH='@scm_lib.scm(sch_1):page41_i94@pure_quanta.q_cap(chips)',
 PATH='I94',
 DRAWING='@SCM_LIB.SCM(SCH_1):PAGE41',
 PHYS_PAGE='41',
 XY='(-7850,3275)',
 ROT='0',
 VER='1',
 PACK_TYPE='C0402',
 CDS_LIB='pure_quanta',
 CDS_PART_NAME='Q_CAP_C0402-1UF,25V,10%,X6S,CHA',
 TOLERANCE='10%',
 MATERIAL='X6S',
 VOLTAGE='25V',
 VALUE='1UF',
 PRIM_FILE='W:/<user>/logical/q_cap/chips/chips.prt';

PART_NAME
 C217 'Q_CAP_0402-0.1UF,25V,10%,X7R,CA':;

SECTION_NUMBER 1
 '@SCM_LIB.SCM(SCH_1):PAGE32_I21@PURE_QUANTA.Q_CAP(CHIPS)':
 C_PATH='@scm_lib.scm(sch_1):page32_i21@pure_quanta.q_cap(chips)',
 P_PATH='@scm_lib.scm(sch_1):page32_i21@pure_quanta.q_cap(chips)',
 PATH='I21',
 DRAWING='@SCM_LIB.SCM(SCH_1):PAGE32',
 PHYS_PAGE='32',
 XY='(3575,4000)',
 ROT='0',
 VER='1',
 PACK_TYPE='0402',
 LOCATION='C217',
 CDS_LIB='pure_quanta',
 CDS_PART_NAME='Q_CAP_0402-0.1UF,25V,10%,X7R,CA',
 TOLERANCE='10%',
 MATERIAL='X7R',
 VOLTAGE='25V',
 VALUE='0.1UF',
 PRIM_FILE='W:/<user>/logical/q_cap/chips/chips.prt';

PART_NAME
 C218 'Q_CAP_C0402-1UF,25V,10%,X6S,CHA':;

SECTION_NUMBER 1
 '@SCM_LIB.SCM(SCH_1):PAGE41_I95@PURE_QUANTA.Q_CAP(CHIPS)':
 C_PATH='@scm_lib.scm(sch_1):page41_i95@pure_quanta.q_cap(chips)',
 P_PATH='@scm_lib.scm(sch_1):page41_i95@pure_quanta.q_cap(chips)',
 PATH='I95',
 DRAWING='@SCM_LIB.SCM(SCH_1):PAGE41',
 PHYS_PAGE='41',
 XY='(-7800,2300)',
 ROT='0',
 VER='1',
 PACK_TYPE='C0402',
 CDS_LIB='pure_quanta',
 CDS_PART_NAME='Q_CAP_C0402-1UF,25V,10%,X6S,CHA',
 TOLERANCE='10%',
 MATERIAL='X6S',
 VOLTAGE='25V',
 VALUE='1UF',
 PRIM_FILE='W:/<user>/logical/q_cap/chips/chips.prt';

PART_NAME
 C219 'Q_CAP_0402-0.1UF,25V,10%,X7R,CA':;

SECTION_NUMBER 1
 '@SCM_LIB.SCM(SCH_1):PAGE29_I150@PURE_QUANTA.Q_CAP(CHIPS)':
 C_PATH='@scm_lib.scm(sch_1):page29_i150@pure_quanta.q_cap(chips)',
 P_PATH='@scm_lib.scm(sch_1):page29_i150@pure_quanta.q_cap(chips)',
 PATH='I150',
 DRAWING='@SCM_LIB.SCM(SCH_1):PAGE29',
 PHYS_PAGE='29',
 XY='(-3625,275)',
 ROT='2',
 VER='1',
 PACK_TYPE='0402',
 LOCATION='C219',
 CDS_LIB='pure_quanta',
 CDS_PART_NAME='Q_CAP_0402-0.1UF,25V,10%,X7R,CA',
 TOLERANCE='10%',
 MATERIAL='X7R',
 VOLTAGE='25V',
 VALUE='0.1UF',
 PRIM_FILE='W:/<user>/logical/q_cap/chips/chips.prt';

PART_NAME
 C220 'Q_CAP_0402-0.1UF,25V,10%,X7R,CA':;

SECTION_NUMBER 1
 '@SCM_LIB.SCM(SCH_1):PAGE41_I90@PURE_QUANTA.Q_CAP(CHIPS)':
 C_PATH='@scm_lib.scm(sch_1):page41_i90@pure_quanta.q_cap(chips)',
 P_PATH='@scm_lib.scm(sch_1):page41_i90@pure_quanta.q_cap(chips)',
 PATH='I90',
 DRAWING='@SCM_LIB.SCM(SCH_1):PAGE41',
 PHYS_PAGE='41',
 XY='(-7525,4500)',
 ROT='0',
 VER='1',
 PACK_TYPE='0402',
 CDS_LIB='pure_quanta',
 CDS_PART_NAME='Q_CAP_0402-0.1UF,25V,10%,X7R,CA',
 TOLERANCE='10%',
 MATERIAL='X7R',
 VOLTAGE='25V',
 VALUE='0.1UF',
 PRIM_FILE='W:/<user>/logical/q_cap/chips/chips.prt';

PART_NAME
 C221 'Q_CAP_0402-0.1UF,25V,10%,X7R,CA':;

SECTION_NUMBER 1
 '@SCM_LIB.SCM(SCH_1):PAGE20_I199@PURE_QUANTA.Q_CAP(CHIPS)':
 C_PATH='@scm_lib.scm(sch_1):page20_i199@pure_quanta.q_cap(chips)',
 P_PATH='@scm_lib.scm(sch_1):page20_i199@pure_quanta.q_cap(chips)',
 PATH='I199',
 DRAWING='@SCM_LIB.SCM(SCH_1):PAGE20',
 SEC_TYPE='0402',
 PHYS_PAGE='20',
 XY='(-2550,1950)',
 ROT='0',
 VER='1',
 PACK_TYPE='0402',
 LOCATION='C221',
 SEC='1',
 CDS_LIB='pure_quanta',
 CDS_PART_NAME='Q_CAP_0402-0.1UF,25V,10%,X7R,CA',
 TOLERANCE='10%',
 MATERIAL='X7R',
 VOLTAGE='25V',
 VALUE='0.1UF',
 PRIM_FILE='W:/<user>/logical/q_cap/chips/chips.prt';

PART_NAME
 C222 'Q_CAP_0402-0.1UF,25V,10%,X7R,CA':;

SECTION_NUMBER 1
 '@SCM_LIB.SCM(SCH_1):PAGE20_I198@PURE_QUANTA.Q_CAP(CHIPS)':
 C_PATH='@scm_lib.scm(sch_1):page20_i198@pure_quanta.q_cap(chips)',
 P_PATH='@scm_lib.scm(sch_1):page20_i198@pure_quanta.q_cap(chips)',
 PATH='I198',
 DRAWING='@SCM_LIB.SCM(SCH_1):PAGE20',
 SEC_TYPE='0402',
 PHYS_PAGE='20',
 XY='(-2350,1950)',
 ROT='0',
 VER='1',
 PACK_TYPE='0402',
 LOCATION='C222',
 SEC='1',
 CDS_LIB='pure_quanta',
 CDS_PART_NAME='Q_CAP_0402-0.1UF,25V,10%,X7R,CA',
 TOLERANCE='10%',
 MATERIAL='X7R',
 VOLTAGE='25V',
 VALUE='0.1UF',
 PRIM_FILE='W:/<user>/logical/q_cap/chips/chips.prt';

PART_NAME
 C223 'Q_CAP_C0402-4700P,25V,10%,EMPTA':;

SECTION_NUMBER 1
 '@SCM_LIB.SCM(SCH_1):PAGE22_I46@PURE_QUANTA.Q_CAP(CHIPS)':
 C_PATH='@scm_lib.scm(sch_1):page22_i46@pure_quanta.q_cap(chips)',
 P_PATH='@scm_lib.scm(sch_1):page22_i46@pure_quanta.q_cap(chips)',
 PATH='I46',
 DRAWING='@SCM_LIB.SCM(SCH_1):PAGE22',
 PHYS_PAGE='22',
 XY='(1275,775)',
 ROT='0',
 VER='1',
 PACK_TYPE='C0402',
 LOCATION='C223',
 CDS_LIB='pure_quanta',
 CDS_PART_NAME='Q_CAP_C0402-4700P,25V,10%,EMPTA',
 TOLERANCE='10%',
 MATERIAL='EMPTY',
 VOLTAGE='25V',
 VALUE='4700P',
 PRIM_FILE='W:/<user>/logical/q_cap/chips/chips.prt';

PART_NAME
 C224 'Q_CAP_C0402-10UF,6.3V,20%,X6S,A':;

SECTION_NUMBER 1
 '@SCM_LIB.SCM(SCH_1):PAGE17_I180@PURE_QUANTA.Q_CAP(CHIPS)':
 C_PATH='@scm_lib.scm(sch_1):page17_i180@pure_quanta.q_cap(chips)',
 P_PATH='@scm_lib.scm(sch_1):page17_i180@pure_quanta.q_cap(chips)',
 PATH='I180',
 DRAWING='@SCM_LIB.SCM(SCH_1):PAGE17',
 PHYS_PAGE='17',
 XY='(1650,250)',
 ROT='0',
 VER='1',
 PACK_TYPE='C0402',
 LOCATION='C224',
 CDS_LIB='pure_quanta',
 CDS_PART_NAME='Q_CAP_C0402-10UF,6.3V,20%,X6S,A',
 TOLERANCE='20%',
 MATERIAL='X6S',
 VOLTAGE='6.3V',
 VALUE='10UF',
 PRIM_FILE='W:/<user>/logical/q_cap/chips/chips.prt';

PART_NAME
 C225 'Q_CAP_0402-0.1UF,25V,10%,X7R,CA':;

SECTION_NUMBER 1
 '@SCM_LIB.SCM(SCH_1):PAGE20_I197@PURE_QUANTA.Q_CAP(CHIPS)':
 C_PATH='@scm_lib.scm(sch_1):page20_i197@pure_quanta.q_cap(chips)',
 P_PATH='@scm_lib.scm(sch_1):page20_i197@pure_quanta.q_cap(chips)',
 PATH='I197',
 DRAWING='@SCM_LIB.SCM(SCH_1):PAGE20',
 SEC_TYPE='0402',
 PHYS_PAGE='20',
 XY='(-2125,1950)',
 ROT='0',
 VER='1',
 PACK_TYPE='0402',
 LOCATION='C225',
 SEC='1',
 CDS_LIB='pure_quanta',
 CDS_PART_NAME='Q_CAP_0402-0.1UF,25V,10%,X7R,CA',
 TOLERANCE='10%',
 MATERIAL='X7R',
 VOLTAGE='25V',
 VALUE='0.1UF',
 PRIM_FILE='W:/<user>/logical/q_cap/chips/chips.prt';

PART_NAME
 C226 'Q_CAP_C0402-1UF,25V,10%,X6S,CHA':;

SECTION_NUMBER 1
 '@SCM_LIB.SCM(SCH_1):PAGE51_I60@PURE_QUANTA.Q_CAP(CHIPS)':
 C_PATH='@scm_lib.scm(sch_1):page51_i60@pure_quanta.q_cap(chips)',
 P_PATH='@scm_lib.scm(sch_1):page51_i60@pure_quanta.q_cap(chips)',
 PATH='I60',
 DRAWING='@SCM_LIB.SCM(SCH_1):PAGE51',
 PHYS_PAGE='51',
 XY='(-1125,3525)',
 ROT='0',
 VER='1',
 PACK_TYPE='C0402',
 CDS_LIB='pure_quanta',
 CDS_PART_NAME='Q_CAP_C0402-1UF,25V,10%,X6S,CHA',
 TOLERANCE='10%',
 MATERIAL='X6S',
 VOLTAGE='25V',
 VALUE='1UF',
 PRIM_FILE='W:/<user>/logical/q_cap/chips/chips.prt';

PART_NAME
 C227 'Q_CAP_C0402-2.2UF,10V,10%,X6S,A':;

SECTION_NUMBER 1
 '@SCM_LIB.SCM(SCH_1):PAGE51_I68@PURE_QUANTA.Q_CAP(CHIPS)':
 C_PATH='@scm_lib.scm(sch_1):page51_i68@pure_quanta.q_cap(chips)',
 P_PATH='@scm_lib.scm(sch_1):page51_i68@pure_quanta.q_cap(chips)',
 PATH='I68',
 DRAWING='@SCM_LIB.SCM(SCH_1):PAGE51',
 PHYS_PAGE='51',
 XY='(850,3525)',
 ROT='0',
 VER='1',
 PACK_TYPE='C0402',
 LOCATION='C227',
 CDS_LIB='pure_quanta',
 CDS_PART_NAME='Q_CAP_C0402-2.2UF,10V,10%,X6S,A',
 TOLERANCE='10%',
 MATERIAL='X6S',
 VOLTAGE='10V',
 VALUE='2.2UF',
 PRIM_FILE='W:/<user>/logical/q_cap/chips/chips.prt';

PART_NAME
 C228 'Q_CAP_0402-0.1UF,25V,10%,EMPTYA':;

SECTION_NUMBER 1
 '@SCM_LIB.SCM(SCH_1):PAGE21_I21@PURE_QUANTA.Q_CAP(CHIPS)':
 C_PATH='@scm_lib.scm(sch_1):page21_i21@pure_quanta.q_cap(chips)',
 P_PATH='@scm_lib.scm(sch_1):page21_i21@pure_quanta.q_cap(chips)',
 PATH='I21',
 DRAWING='@SCM_LIB.SCM(SCH_1):PAGE21',
 PHYS_PAGE='21',
 XY='(4775,-600)',
 ROT='0',
 VER='1',
 PACK_TYPE='0402',
 LOCATION='C228',
 CDS_LIB='pure_quanta',
 CDS_PART_NAME='Q_CAP_0402-0.1UF,25V,10%,EMPTYA',
 TOLERANCE='10%',
 MATERIAL='EMPTY',
 VOLTAGE='25V',
 VALUE='0.1UF',
 PRIM_FILE='W:/<user>/logical/q_cap/chips/chips.prt';

PART_NAME
 C229 'Q_CAP_0402-0.22UF,16V,10%,EMPTA':;

SECTION_NUMBER 1
 '@SCM_LIB.SCM(SCH_1):PAGE20_I107@PURE_QUANTA.Q_CAP(CHIPS)':
 C_PATH='@scm_lib.scm(sch_1):page20_i107@pure_quanta.q_cap(chips)',
 P_PATH='@scm_lib.scm(sch_1):page20_i107@pure_quanta.q_cap(chips)',
 PATH='I107',
 DRAWING='@SCM_LIB.SCM(SCH_1):PAGE20',
 SEC_TYPE='0402',
 PHYS_PAGE='20',
 XY='(3700,-750)',
 ROT='0',
 VER='2',
 PACK_TYPE='0402',
 LOCATION='C229',
 SEC='1',
 CDS_LIB='pure_quanta',
 CDS_PART_NAME='Q_CAP_0402-0.22UF,16V,10%,EMPTA',
 TOLERANCE='10%',
 MATERIAL='EMPTY',
 VOLTAGE='16V',
 VALUE='0.22UF',
 PRIM_FILE='W:/<user>/logical/q_cap/chips/chips.prt';

PART_NAME
 C231 'Q_CAP_0402-0.1UF,25V,10%,X7R,CA':;

SECTION_NUMBER 1
 '@SCM_LIB.SCM(SCH_1):PAGE31_I45@PURE_QUANTA.Q_CAP(CHIPS)':
 C_PATH='@scm_lib.scm(sch_1):page31_i45@pure_quanta.q_cap(chips)',
 P_PATH='@scm_lib.scm(sch_1):page31_i45@pure_quanta.q_cap(chips)',
 PATH='I45',
 DRAWING='@SCM_LIB.SCM(SCH_1):PAGE31',
 PHYS_PAGE='31',
 XY='(-4025,1750)',
 ROT='2',
 VER='1',
 PACK_TYPE='0402',
 CDS_LIB='pure_quanta',
 CDS_PART_NAME='Q_CAP_0402-0.1UF,25V,10%,X7R,CA',
 TOLERANCE='10%',
 MATERIAL='X7R',
 VOLTAGE='25V',
 VALUE='0.1UF',
 PRIM_FILE='W:/<user>/logical/q_cap/chips/chips.prt';

PART_NAME
 C234 'Q_CAP_C0603-22UF,10V,20%,EMPTYA':;

SECTION_NUMBER 1
 '@SCM_LIB.SCM(SCH_1):PAGE21_I81@PURE_QUANTA.Q_CAP(CHIPS)':
 C_PATH='@scm_lib.scm(sch_1):page21_i81@pure_quanta.q_cap(chips)',
 P_PATH='@scm_lib.scm(sch_1):page21_i81@pure_quanta.q_cap(chips)',
 PATH='I81',
 DRAWING='@SCM_LIB.SCM(SCH_1):PAGE21',
 PHYS_PAGE='21',
 XY='(4100,-600)',
 ROT='0',
 VER='1',
 PACK_TYPE='C0603',
 LOCATION='C234',
 CDS_LIB='pure_quanta',
 CDS_PART_NAME='Q_CAP_C0603-22UF,10V,20%,EMPTYA',
 TOLERANCE='20%',
 MATERIAL='EMPTY',
 VOLTAGE='10V',
 VALUE='22UF',
 PRIM_FILE='W:/<user>/logical/q_cap/chips/chips.prt';

PART_NAME
 C235 'Q_CAP_0402-0.1UF,25V,10%,EMPTYA':;

SECTION_NUMBER 1
 '@SCM_LIB.SCM(SCH_1):PAGE21_I80@PURE_QUANTA.Q_CAP(CHIPS)':
 C_PATH='@scm_lib.scm(sch_1):page21_i80@pure_quanta.q_cap(chips)',
 P_PATH='@scm_lib.scm(sch_1):page21_i80@pure_quanta.q_cap(chips)',
 PATH='I80',
 DRAWING='@SCM_LIB.SCM(SCH_1):PAGE21',
 PHYS_PAGE='21',
 XY='(4500,-600)',
 ROT='0',
 VER='1',
 PACK_TYPE='0402',
 LOCATION='C235',
 CDS_LIB='pure_quanta',
 CDS_PART_NAME='Q_CAP_0402-0.1UF,25V,10%,EMPTYA',
 TOLERANCE='10%',
 MATERIAL='EMPTY',
 VOLTAGE='25V',
 VALUE='0.1UF',
 PRIM_FILE='W:/<user>/logical/q_cap/chips/chips.prt';

PART_NAME
 C236 'Q_CAP_0402-0.1UF,25V,10%,X7R,CA':;

SECTION_NUMBER 1
 '@SCM_LIB.SCM(SCH_1):PAGE29_I148@PURE_QUANTA.Q_CAP(CHIPS)':
 C_PATH='@scm_lib.scm(sch_1):page29_i148@pure_quanta.q_cap(chips)',
 P_PATH='@scm_lib.scm(sch_1):page29_i148@pure_quanta.q_cap(chips)',
 PATH='I148',
 DRAWING='@SCM_LIB.SCM(SCH_1):PAGE29',
 PHYS_PAGE='29',
 XY='(-3050,275)',
 ROT='2',
 VER='1',
 PACK_TYPE='0402',
 LOCATION='C236',
 CDS_LIB='pure_quanta',
 CDS_PART_NAME='Q_CAP_0402-0.1UF,25V,10%,X7R,CA',
 TOLERANCE='10%',
 MATERIAL='X7R',
 VOLTAGE='25V',
 VALUE='0.1UF',
 PRIM_FILE='W:/<user>/logical/q_cap/chips/chips.prt';

PART_NAME
 C237 'Q_CAP_0402-0.1UF,25V,10%,X7R,CA':;

SECTION_NUMBER 1
 '@SCM_LIB.SCM(SCH_1):PAGE29_I146@PURE_QUANTA.Q_CAP(CHIPS)':
 C_PATH='@scm_lib.scm(sch_1):page29_i146@pure_quanta.q_cap(chips)',
 P_PATH='@scm_lib.scm(sch_1):page29_i146@pure_quanta.q_cap(chips)',
 PATH='I146',
 DRAWING='@SCM_LIB.SCM(SCH_1):PAGE29',
 PHYS_PAGE='29',
 XY='(-2425,300)',
 ROT='2',
 VER='1',
 PACK_TYPE='0402',
 LOCATION='C237',
 CDS_LIB='pure_quanta',
 CDS_PART_NAME='Q_CAP_0402-0.1UF,25V,10%,X7R,CA',
 TOLERANCE='10%',
 MATERIAL='X7R',
 VOLTAGE='25V',
 VALUE='0.1UF',
 PRIM_FILE='W:/<user>/logical/q_cap/chips/chips.prt';

PART_NAME
 C238 'Q_CAP_0402-0.1UF,25V,10%,EMPTYA':;

SECTION_NUMBER 1
 '@SCM_LIB.SCM(SCH_1):PAGE29_I142@PURE_QUANTA.Q_CAP(CHIPS)':
 C_PATH='@scm_lib.scm(sch_1):page29_i142@pure_quanta.q_cap(chips)',
 P_PATH='@scm_lib.scm(sch_1):page29_i142@pure_quanta.q_cap(chips)',
 PATH='I142',
 DRAWING='@SCM_LIB.SCM(SCH_1):PAGE29',
 PHYS_PAGE='29',
 XY='(-50,225)',
 ROT='2',
 VER='2',
 PACK_TYPE='0402',
 LOCATION='C238',
 CDS_LIB='pure_quanta',
 CDS_PART_NAME='Q_CAP_0402-0.1UF,25V,10%,EMPTYA',
 TOLERANCE='10%',
 MATERIAL='EMPTY',
 VOLTAGE='25V',
 VALUE='0.1UF',
 PRIM_FILE='W:/<user>/logical/q_cap/chips/chips.prt';

PART_NAME
 C239 'Q_CAP_0402-0.1UF,25V,10%,EMPTYA':;

SECTION_NUMBER 1
 '@SCM_LIB.SCM(SCH_1):PAGE29_I143@PURE_QUANTA.Q_CAP(CHIPS)':
 C_PATH='@scm_lib.scm(sch_1):page29_i143@pure_quanta.q_cap(chips)',
 P_PATH='@scm_lib.scm(sch_1):page29_i143@pure_quanta.q_cap(chips)',
 PATH='I143',
 DRAWING='@SCM_LIB.SCM(SCH_1):PAGE29',
 PHYS_PAGE='29',
 XY='(-50,50)',
 ROT='2',
 VER='2',
 PACK_TYPE='0402',
 LOCATION='C239',
 CDS_LIB='pure_quanta',
 CDS_PART_NAME='Q_CAP_0402-0.1UF,25V,10%,EMPTYA',
 TOLERANCE='10%',
 MATERIAL='EMPTY',
 VOLTAGE='25V',
 VALUE='0.1UF',
 PRIM_FILE='W:/<user>/logical/q_cap/chips/chips.prt';

PART_NAME
 C240 'Q_CAP_0402-0.1UF,25V,10%,X7R,CA':;

SECTION_NUMBER 1
 '@SCM_LIB.SCM(SCH_1):PAGE52_I63@PURE_QUANTA.Q_CAP(CHIPS)':
 C_PATH='@scm_lib.scm(sch_1):page52_i63@pure_quanta.q_cap(chips)',
 P_PATH='@scm_lib.scm(sch_1):page52_i63@pure_quanta.q_cap(chips)',
 PATH='I63',
 DRAWING='@SCM_LIB.SCM(SCH_1):PAGE52',
 PHYS_PAGE='52',
 XY='(-1975,-1250)',
 ROT='0',
 VER='1',
 PACK_TYPE='0402',
 LOCATION='C240',
 CDS_LIB='pure_quanta',
 CDS_PART_NAME='Q_CAP_0402-0.1UF,25V,10%,X7R,CA',
 TOLERANCE='10%',
 MATERIAL='X7R',
 VOLTAGE='25V',
 VALUE='0.1UF',
 PRIM_FILE='W:/<user>/logical/q_cap/chips/chips.prt';

PART_NAME
 C241 'Q_CAP_0402-0.1UF,25V,10%,X7R,CA':;

SECTION_NUMBER 1
 '@SCM_LIB.SCM(SCH_1):PAGE51_I52@PURE_QUANTA.Q_CAP(CHIPS)':
 C_PATH='@scm_lib.scm(sch_1):page51_i52@pure_quanta.q_cap(chips)',
 P_PATH='@scm_lib.scm(sch_1):page51_i52@pure_quanta.q_cap(chips)',
 PATH='I52',
 DRAWING='@SCM_LIB.SCM(SCH_1):PAGE51',
 PHYS_PAGE='51',
 XY='(-2275,1475)',
 ROT='0',
 VER='1',
 PACK_TYPE='0402',
 CDS_LIB='pure_quanta',
 CDS_PART_NAME='Q_CAP_0402-0.1UF,25V,10%,X7R,CA',
 TOLERANCE='10%',
 MATERIAL='X7R',
 VOLTAGE='25V',
 VALUE='0.1UF',
 PRIM_FILE='W:/<user>/logical/q_cap/chips/chips.prt';

PART_NAME
 C242 'Q_CAP_0402-0.1UF,25V,10%,X7R,CA':;

SECTION_NUMBER 1
 '@SCM_LIB.SCM(SCH_1):PAGE41_I1@PURE_QUANTA.Q_CAP(CHIPS)':
 C_PATH='@scm_lib.scm(sch_1):page41_i1@pure_quanta.q_cap(chips)',
 P_PATH='@scm_lib.scm(sch_1):page41_i1@pure_quanta.q_cap(chips)',
 PATH='I1',
 DRAWING='@SCM_LIB.SCM(SCH_1):PAGE41',
 PHYS_PAGE='41',
 XY='(-4025,5850)',
 ROT='0',
 VER='1',
 PACK_TYPE='0402',
 CDS_LIB='pure_quanta',
 CDS_PART_NAME='Q_CAP_0402-0.1UF,25V,10%,X7R,CA',
 TOLERANCE='10%',
 MATERIAL='X7R',
 VOLTAGE='25V',
 VALUE='0.1UF',
 PRIM_FILE='W:/<user>/logical/q_cap/chips/chips.prt';

PART_NAME
 C243 'Q_CAP_0402-0.1UF,25V,10%,X7R,CA':;

SECTION_NUMBER 1
 '@SCM_LIB.SCM(SCH_1):PAGE41_I81@PURE_QUANTA.Q_CAP(CHIPS)':
 C_PATH='@scm_lib.scm(sch_1):page41_i81@pure_quanta.q_cap(chips)',
 P_PATH='@scm_lib.scm(sch_1):page41_i81@pure_quanta.q_cap(chips)',
 PATH='I81',
 DRAWING='@SCM_LIB.SCM(SCH_1):PAGE41',
 PHYS_PAGE='41',
 XY='(-3450,4700)',
 ROT='0',
 VER='1',
 PACK_TYPE='0402',
 CDS_LIB='pure_quanta',
 CDS_PART_NAME='Q_CAP_0402-0.1UF,25V,10%,X7R,CA',
 TOLERANCE='10%',
 MATERIAL='X7R',
 VOLTAGE='25V',
 VALUE='0.1UF',
 PRIM_FILE='W:/<user>/logical/q_cap/chips/chips.prt';

PART_NAME
 C244 'Q_CAP_C0402-1UF,25V,10%,X6S,CHA':;

SECTION_NUMBER 1
 '@SCM_LIB.SCM(SCH_1):PAGE45_I42@PURE_QUANTA.Q_CAP(CHIPS)':
 C_PATH='@scm_lib.scm(sch_1):page45_i42@pure_quanta.q_cap(chips)',
 P_PATH='@scm_lib.scm(sch_1):page45_i42@pure_quanta.q_cap(chips)',
 PATH='I42',
 DRAWING='@SCM_LIB.SCM(SCH_1):PAGE45',
 PHYS_PAGE='45',
 XY='(-800,3025)',
 ROT='0',
 VER='1',
 PACK_TYPE='C0402',
 LOCATION='C244',
 CDS_LIB='pure_quanta',
 CDS_PART_NAME='Q_CAP_C0402-1UF,25V,10%,X6S,CHA',
 TOLERANCE='10%',
 MATERIAL='X6S',
 VOLTAGE='25V',
 VALUE='1UF',
 PRIM_FILE='W:/<user>/logical/q_cap/chips/chips.prt';

PART_NAME
 C245 'Q_CAP_0402-0.1UF,25V,10%,X7R,CA':;

SECTION_NUMBER 1
 '@SCM_LIB.SCM(SCH_1):PAGE41_I85@PURE_QUANTA.Q_CAP(CHIPS)':
 C_PATH='@scm_lib.scm(sch_1):page41_i85@pure_quanta.q_cap(chips)',
 P_PATH='@scm_lib.scm(sch_1):page41_i85@pure_quanta.q_cap(chips)',
 PATH='I85',
 DRAWING='@SCM_LIB.SCM(SCH_1):PAGE41',
 PHYS_PAGE='41',
 XY='(-3425,3600)',
 ROT='0',
 VER='1',
 PACK_TYPE='0402',
 CDS_LIB='pure_quanta',
 CDS_PART_NAME='Q_CAP_0402-0.1UF,25V,10%,X7R,CA',
 TOLERANCE='10%',
 MATERIAL='X7R',
 VOLTAGE='25V',
 VALUE='0.1UF',
 PRIM_FILE='W:/<user>/logical/q_cap/chips/chips.prt';

PART_NAME
 C246 'Q_CAP_C0402-0.01UF,50V,10%,X7RA':;

SECTION_NUMBER 1
 '@SCM_LIB.SCM(SCH_1):PAGE45_I45@PURE_QUANTA.Q_CAP(CHIPS)':
 C_PATH='@scm_lib.scm(sch_1):page45_i45@pure_quanta.q_cap(chips)',
 P_PATH='@scm_lib.scm(sch_1):page45_i45@pure_quanta.q_cap(chips)',
 PATH='I45',
 DRAWING='@SCM_LIB.SCM(SCH_1):PAGE45',
 PHYS_PAGE='45',
 XY='(-350,3025)',
 ROT='0',
 VER='1',
 PACK_TYPE='C0402',
 LOCATION='C246',
 CDS_LIB='pure_quanta',
 CDS_PART_NAME='Q_CAP_C0402-0.01UF,50V,10%,X7RA',
 TOLERANCE='10%',
 MATERIAL='X7R',
 VOLTAGE='50V',
 VALUE='0.01UF',
 PRIM_FILE='W:/<user>/logical/q_cap/chips/chips.prt';

PART_NAME
 C247 'Q_CAP_0402-0.1UF,25V,10%,X7R,CA':;

SECTION_NUMBER 1
 '@SCM_LIB.SCM(SCH_1):PAGE41_I77@PURE_QUANTA.Q_CAP(CHIPS)':
 C_PATH='@scm_lib.scm(sch_1):page41_i77@pure_quanta.q_cap(chips)',
 P_PATH='@scm_lib.scm(sch_1):page41_i77@pure_quanta.q_cap(chips)',
 PATH='I77',
 DRAWING='@SCM_LIB.SCM(SCH_1):PAGE41',
 PHYS_PAGE='41',
 XY='(-3400,5850)',
 ROT='0',
 VER='1',
 PACK_TYPE='0402',
 CDS_LIB='pure_quanta',
 CDS_PART_NAME='Q_CAP_0402-0.1UF,25V,10%,X7R,CA',
 TOLERANCE='10%',
 MATERIAL='X7R',
 VOLTAGE='25V',
 VALUE='0.1UF',
 PRIM_FILE='W:/<user>/logical/q_cap/chips/chips.prt';

PART_NAME
 C248 'Q_CAP_C0402-10UF,6.3V,20%,X6S,A':;

SECTION_NUMBER 1
 '@SCM_LIB.SCM(SCH_1):PAGE46_I69@PURE_QUANTA.Q_CAP(CHIPS)':
 C_PATH='@scm_lib.scm(sch_1):page46_i69@pure_quanta.q_cap(chips)',
 P_PATH='@scm_lib.scm(sch_1):page46_i69@pure_quanta.q_cap(chips)',
 PATH='I69',
 DRAWING='@SCM_LIB.SCM(SCH_1):PAGE46',
 PHYS_PAGE='46',
 XY='(-7175,-1550)',
 ROT='0',
 VER='1',
 PACK_TYPE='C0402',
 LOCATION='C248',
 CDS_LIB='pure_quanta',
 CDS_PART_NAME='Q_CAP_C0402-10UF,6.3V,20%,X6S,A',
 TOLERANCE='20%',
 MATERIAL='X6S',
 VOLTAGE='6.3V',
 VALUE='10UF',
 PRIM_FILE='W:/<user>/logical/q_cap/chips/chips.prt';

PART_NAME
 C249 'Q_CAP_0402-0.1UF,25V,10%,X7R,CA':;

SECTION_NUMBER 1
 '@SCM_LIB.SCM(SCH_1):PAGE46_I67@PURE_QUANTA.Q_CAP(CHIPS)':
 C_PATH='@scm_lib.scm(sch_1):page46_i67@pure_quanta.q_cap(chips)',
 P_PATH='@scm_lib.scm(sch_1):page46_i67@pure_quanta.q_cap(chips)',
 PATH='I67',
 DRAWING='@SCM_LIB.SCM(SCH_1):PAGE46',
 PHYS_PAGE='46',
 XY='(-6800,-1550)',
 ROT='0',
 VER='1',
 PACK_TYPE='0402',
 LOCATION='C249',
 CDS_LIB='pure_quanta',
 CDS_PART_NAME='Q_CAP_0402-0.1UF,25V,10%,X7R,CA',
 TOLERANCE='10%',
 MATERIAL='X7R',
 VOLTAGE='25V',
 VALUE='0.1UF',
 PRIM_FILE='W:/<user>/logical/q_cap/chips/chips.prt';

PART_NAME
 C250 'Q_CAP_0402-0.1UF,25V,10%,X7R,CA':;

SECTION_NUMBER 1
 '@SCM_LIB.SCM(SCH_1):PAGE41_I115@PURE_QUANTA.Q_CAP(CHIPS)':
 C_PATH='@scm_lib.scm(sch_1):page41_i115@pure_quanta.q_cap(chips)',
 P_PATH='@scm_lib.scm(sch_1):page41_i115@pure_quanta.q_cap(chips)',
 PATH='I115',
 DRAWING='@SCM_LIB.SCM(SCH_1):PAGE41',
 PHYS_PAGE='41',
 XY='(-3450,1950)',
 ROT='0',
 VER='1',
 PACK_TYPE='0402',
 CDS_LIB='pure_quanta',
 CDS_PART_NAME='Q_CAP_0402-0.1UF,25V,10%,X7R,CA',
 TOLERANCE='10%',
 MATERIAL='X7R',
 VOLTAGE='25V',
 VALUE='0.1UF',
 PRIM_FILE='W:/<user>/logical/q_cap/chips/chips.prt';

PART_NAME
 C251 'Q_CAP_0402-0.1UF,25V,10%,X7R,CA':;

SECTION_NUMBER 1
 '@SCM_LIB.SCM(SCH_1):PAGE52_I66@PURE_QUANTA.Q_CAP(CHIPS)':
 C_PATH='@scm_lib.scm(sch_1):page52_i66@pure_quanta.q_cap(chips)',
 P_PATH='@scm_lib.scm(sch_1):page52_i66@pure_quanta.q_cap(chips)',
 PATH='I66',
 DRAWING='@SCM_LIB.SCM(SCH_1):PAGE52',
 PHYS_PAGE='52',
 XY='(-775,-1300)',
 ROT='0',
 VER='1',
 PACK_TYPE='0402',
 LOCATION='C251',
 CDS_LIB='pure_quanta',
 CDS_PART_NAME='Q_CAP_0402-0.1UF,25V,10%,X7R,CA',
 TOLERANCE='10%',
 MATERIAL='X7R',
 VOLTAGE='25V',
 VALUE='0.1UF',
 PRIM_FILE='W:/<user>/logical/q_cap/chips/chips.prt';

PART_NAME
 C252 'Q_CAP_C0402-1UF,25V,10%,EMPTY,A':;

SECTION_NUMBER 1
 '@SCM_LIB.SCM(SCH_1):PAGE52_I73@PURE_QUANTA.Q_CAP(CHIPS)':
 C_PATH='@scm_lib.scm(sch_1):page52_i73@pure_quanta.q_cap(chips)',
 P_PATH='@scm_lib.scm(sch_1):page52_i73@pure_quanta.q_cap(chips)',
 PATH='I73',
 DRAWING='@SCM_LIB.SCM(SCH_1):PAGE52',
 SEC_TYPE='C0402',
 PHYS_PAGE='52',
 XY='(-50,-2050)',
 ROT='0',
 VER='1',
 PACK_TYPE='C0402',
 LOCATION='C252',
 SEC='1',
 CDS_LIB='pure_quanta',
 CDS_PART_NAME='Q_CAP_C0402-1UF,25V,10%,EMPTY,A',
 TOLERANCE='10%',
 MATERIAL='EMPTY',
 VOLTAGE='25V',
 VALUE='1UF',
 PRIM_FILE='W:/<user>/logical/q_cap/chips/chips.prt';

PART_NAME
 C253 'Q_CAP_0402-0.1UF,25V,10%,X7R,CA':;

SECTION_NUMBER 1
 '@SCM_LIB.SCM(SCH_1):PAGE22_I57@PURE_QUANTA.Q_CAP(CHIPS)':
 C_PATH='@scm_lib.scm(sch_1):page22_i57@pure_quanta.q_cap(chips)',
 P_PATH='@scm_lib.scm(sch_1):page22_i57@pure_quanta.q_cap(chips)',
 PATH='I57',
 DRAWING='@SCM_LIB.SCM(SCH_1):PAGE22',
 PHYS_PAGE='22',
 XY='(-875,225)',
 ROT='0',
 VER='1',
 PACK_TYPE='0402',
 LOCATION='C253',
 CDS_LIB='pure_quanta',
 CDS_PART_NAME='Q_CAP_0402-0.1UF,25V,10%,X7R,CA',
 TOLERANCE='10%',
 MATERIAL='X7R',
 VOLTAGE='25V',
 VALUE='0.1UF',
 PRIM_FILE='W:/<user>/logical/q_cap/chips/chips.prt';

PART_NAME
 C254 'Q_CAP_0402-0.1UF,25V,10%,X7R,CA':;

SECTION_NUMBER 1
 '@SCM_LIB.SCM(SCH_1):PAGE41_I82@PURE_QUANTA.Q_CAP(CHIPS)':
 C_PATH='@scm_lib.scm(sch_1):page41_i82@pure_quanta.q_cap(chips)',
 P_PATH='@scm_lib.scm(sch_1):page41_i82@pure_quanta.q_cap(chips)',
 PATH='I82',
 DRAWING='@SCM_LIB.SCM(SCH_1):PAGE41',
 PHYS_PAGE='41',
 XY='(-2875,4700)',
 ROT='0',
 VER='1',
 PACK_TYPE='0402',
 CDS_LIB='pure_quanta',
 CDS_PART_NAME='Q_CAP_0402-0.1UF,25V,10%,X7R,CA',
 TOLERANCE='10%',
 MATERIAL='X7R',
 VOLTAGE='25V',
 VALUE='0.1UF',
 PRIM_FILE='W:/<user>/logical/q_cap/chips/chips.prt';

PART_NAME
 C255 'Q_CAP_0402-0.1UF,25V,10%,X7R,CA':;

SECTION_NUMBER 1
 '@SCM_LIB.SCM(SCH_1):PAGE44_I278@PURE_QUANTA.Q_CAP(CHIPS)':
 C_PATH='@scm_lib.scm(sch_1):page44_i278@pure_quanta.q_cap(chips)',
 P_PATH='@scm_lib.scm(sch_1):page44_i278@pure_quanta.q_cap(chips)',
 PATH='I278',
 DRAWING='@SCM_LIB.SCM(SCH_1):PAGE44',
 PHYS_PAGE='44',
 XY='(3100,1600)',
 ROT='0',
 VER='1',
 PACK_TYPE='0402',
 LOCATION='C255',
 CDS_LIB='pure_quanta',
 CDS_PART_NAME='Q_CAP_0402-0.1UF,25V,10%,X7R,CA',
 TOLERANCE='10%',
 MATERIAL='X7R',
 VOLTAGE='25V',
 VALUE='0.1UF',
 PRIM_FILE='W:/<user>/logical/q_cap/chips/chips.prt';

PART_NAME
 C256 'Q_CAP_C0402-1UF,25V,10%,X6S,CHA':;

SECTION_NUMBER 1
 '@SCM_LIB.SCM(SCH_1):PAGE34_I140@PURE_QUANTA.Q_CAP(CHIPS)':
 C_PATH='@scm_lib.scm(sch_1):page34_i140@pure_quanta.q_cap(chips)',
 P_PATH='@scm_lib.scm(sch_1):page34_i140@pure_quanta.q_cap(chips)',
 PATH='I140',
 DRAWING='@SCM_LIB.SCM(SCH_1):PAGE34',
 PHYS_PAGE='34',
 XY='(-7375,1650)',
 ROT='0',
 VER='1',
 PACK_TYPE='C0402',
 CDS_LIB='pure_quanta',
 CDS_PART_NAME='Q_CAP_C0402-1UF,25V,10%,X6S,CHA',
 TOLERANCE='10%',
 MATERIAL='X6S',
 VOLTAGE='25V',
 VALUE='1UF',
 PRIM_FILE='W:/<user>/logical/q_cap/chips/chips.prt';

PART_NAME
 C257 'Q_CAP_0402-0.1UF,25V,10%,X7R,CA':;

SECTION_NUMBER 1
 '@SCM_LIB.SCM(SCH_1):PAGE34_I144@PURE_QUANTA.Q_CAP(CHIPS)':
 C_PATH='@scm_lib.scm(sch_1):page34_i144@pure_quanta.q_cap(chips)',
 P_PATH='@scm_lib.scm(sch_1):page34_i144@pure_quanta.q_cap(chips)',
 PATH='I144',
 DRAWING='@SCM_LIB.SCM(SCH_1):PAGE34',
 PHYS_PAGE='34',
 XY='(-6725,1625)',
 ROT='0',
 VER='1',
 PACK_TYPE='0402',
 CDS_LIB='pure_quanta',
 CDS_PART_NAME='Q_CAP_0402-0.1UF,25V,10%,X7R,CA',
 TOLERANCE='10%',
 MATERIAL='X7R',
 VOLTAGE='25V',
 VALUE='0.1UF',
 PRIM_FILE='W:/<user>/logical/q_cap/chips/chips.prt';

PART_NAME
 C260 'Q_CAP_0402-0.1UF,25V,10%,X7R,CA':;

SECTION_NUMBER 1
 '@SCM_LIB.SCM(SCH_1):PAGE41_I87@PURE_QUANTA.Q_CAP(CHIPS)':
 C_PATH='@scm_lib.scm(sch_1):page41_i87@pure_quanta.q_cap(chips)',
 P_PATH='@scm_lib.scm(sch_1):page41_i87@pure_quanta.q_cap(chips)',
 PATH='I87',
 DRAWING='@SCM_LIB.SCM(SCH_1):PAGE41',
 PHYS_PAGE='41',
 XY='(-2275,3600)',
 ROT='0',
 VER='1',
 PACK_TYPE='0402',
 CDS_LIB='pure_quanta',
 CDS_PART_NAME='Q_CAP_0402-0.1UF,25V,10%,X7R,CA',
 TOLERANCE='10%',
 MATERIAL='X7R',
 VOLTAGE='25V',
 VALUE='0.1UF',
 PRIM_FILE='W:/<user>/logical/q_cap/chips/chips.prt';

PART_NAME
 C261 'Q_CAP_0402-0.1UF,25V,10%,X7R,CA':;

SECTION_NUMBER 1
 '@SCM_LIB.SCM(SCH_1):PAGE41_I79@PURE_QUANTA.Q_CAP(CHIPS)':
 C_PATH='@scm_lib.scm(sch_1):page41_i79@pure_quanta.q_cap(chips)',
 P_PATH='@scm_lib.scm(sch_1):page41_i79@pure_quanta.q_cap(chips)',
 PATH='I79',
 DRAWING='@SCM_LIB.SCM(SCH_1):PAGE41',
 PHYS_PAGE='41',
 XY='(-2250,5850)',
 ROT='0',
 VER='1',
 PACK_TYPE='0402',
 CDS_LIB='pure_quanta',
 CDS_PART_NAME='Q_CAP_0402-0.1UF,25V,10%,X7R,CA',
 TOLERANCE='10%',
 MATERIAL='X7R',
 VOLTAGE='25V',
 VALUE='0.1UF',
 PRIM_FILE='W:/<user>/logical/q_cap/chips/chips.prt';

PART_NAME
 C262 'Q_CAP_0402-0.1UF,25V,10%,X7R,CA':;

SECTION_NUMBER 1
 '@SCM_LIB.SCM(SCH_1):PAGE52_I101@PURE_QUANTA.Q_CAP(CHIPS)':
 C_PATH='@scm_lib.scm(sch_1):page52_i101@pure_quanta.q_cap(chips)',
 P_PATH='@scm_lib.scm(sch_1):page52_i101@pure_quanta.q_cap(chips)',
 PATH='I101',
 DRAWING='@SCM_LIB.SCM(SCH_1):PAGE52',
 PHYS_PAGE='52',
 XY='(-3375,2125)',
 ROT='0',
 VER='1',
 PACK_TYPE='0402',
 CDS_LIB='pure_quanta',
 CDS_PART_NAME='Q_CAP_0402-0.1UF,25V,10%,X7R,CA',
 TOLERANCE='10%',
 MATERIAL='X7R',
 VOLTAGE='25V',
 VALUE='0.1UF',
 PRIM_FILE='W:/<user>/logical/q_cap/chips/chips.prt';

PART_NAME
 C263 'Q_CAP_0402-0.1UF,25V,10%,X7R,CA':;

SECTION_NUMBER 1
 '@SCM_LIB.SCM(SCH_1):PAGE41_I117@PURE_QUANTA.Q_CAP(CHIPS)':
 C_PATH='@scm_lib.scm(sch_1):page41_i117@pure_quanta.q_cap(chips)',
 P_PATH='@scm_lib.scm(sch_1):page41_i117@pure_quanta.q_cap(chips)',
 PATH='I117',
 DRAWING='@SCM_LIB.SCM(SCH_1):PAGE41',
 PHYS_PAGE='41',
 XY='(-2325,1950)',
 ROT='0',
 VER='1',
 PACK_TYPE='0402',
 CDS_LIB='pure_quanta',
 CDS_PART_NAME='Q_CAP_0402-0.1UF,25V,10%,X7R,CA',
 TOLERANCE='10%',
 MATERIAL='X7R',
 VOLTAGE='25V',
 VALUE='0.1UF',
 PRIM_FILE='W:/<user>/logical/q_cap/chips/chips.prt';

PART_NAME
 C264 'Q_CAP_0402-0.1UF,25V,10%,X7R,CA':;

SECTION_NUMBER 1
 '@SCM_LIB.SCM(SCH_1):PAGE22_I59@PURE_QUANTA.Q_CAP(CHIPS)':
 C_PATH='@scm_lib.scm(sch_1):page22_i59@pure_quanta.q_cap(chips)',
 P_PATH='@scm_lib.scm(sch_1):page22_i59@pure_quanta.q_cap(chips)',
 PATH='I59',
 DRAWING='@SCM_LIB.SCM(SCH_1):PAGE22',
 PHYS_PAGE='22',
 XY='(-250,-425)',
 ROT='0',
 VER='1',
 PACK_TYPE='0402',
 LOCATION='C264',
 CDS_LIB='pure_quanta',
 CDS_PART_NAME='Q_CAP_0402-0.1UF,25V,10%,X7R,CA',
 TOLERANCE='10%',
 MATERIAL='X7R',
 VOLTAGE='25V',
 VALUE='0.1UF',
 PRIM_FILE='W:/<user>/logical/q_cap/chips/chips.prt';

PART_NAME
 C265 'Q_CAP_C0805-22UF,16V,20%,X6S,CA':;

SECTION_NUMBER 1
 '@SCM_LIB.SCM(SCH_1):PAGE52_I102@PURE_QUANTA.Q_CAP(CHIPS)':
 C_PATH='@scm_lib.scm(sch_1):page52_i102@pure_quanta.q_cap(chips)',
 P_PATH='@scm_lib.scm(sch_1):page52_i102@pure_quanta.q_cap(chips)',
 PATH='I102',
 DRAWING='@SCM_LIB.SCM(SCH_1):PAGE52',
 PHYS_PAGE='52',
 XY='(-2500,2050)',
 ROT='0',
 VER='1',
 PACK_TYPE='C0805',
 CDS_LIB='pure_quanta',
 CDS_PART_NAME='Q_CAP_C0805-22UF,16V,20%,X6S,CA',
 TOLERANCE='20%',
 MATERIAL='X6S',
 VOLTAGE='16V',
 VALUE='22UF',
 PRIM_FILE='W:/<user>/logical/q_cap/chips/chips.prt';

PART_NAME
 C266 'Q_CAP_0402-0.1UF,25V,10%,X7R,CA':;

SECTION_NUMBER 1
 '@SCM_LIB.SCM(SCH_1):PAGE41_I119@PURE_QUANTA.Q_CAP(CHIPS)':
 C_PATH='@scm_lib.scm(sch_1):page41_i119@pure_quanta.q_cap(chips)',
 P_PATH='@scm_lib.scm(sch_1):page41_i119@pure_quanta.q_cap(chips)',
 PATH='I119',
 DRAWING='@SCM_LIB.SCM(SCH_1):PAGE41',
 PHYS_PAGE='41',
 XY='(-1775,1950)',
 ROT='0',
 VER='1',
 PACK_TYPE='0402',
 CDS_LIB='pure_quanta',
 CDS_PART_NAME='Q_CAP_0402-0.1UF,25V,10%,X7R,CA',
 TOLERANCE='10%',
 MATERIAL='X7R',
 VOLTAGE='25V',
 VALUE='0.1UF',
 PRIM_FILE='W:/<user>/logical/q_cap/chips/chips.prt';

PART_NAME
 C267 'Q_CAP_0402-1UF,16V,10%,EMPTY,TA':;

SECTION_NUMBER 1
 '@SCM_LIB.SCM(SCH_1):PAGE27_I166@PURE_QUANTA.Q_CAP(CHIPS)':
 C_PATH='@scm_lib.scm(sch_1):page27_i166@pure_quanta.q_cap(chips)',
 P_PATH='@scm_lib.scm(sch_1):page27_i166@pure_quanta.q_cap(chips)',
 PATH='I166',
 DRAWING='@SCM_LIB.SCM(SCH_1):PAGE27',
 PHYS_PAGE='27',
 XY='(2650,-900)',
 ROT='0',
 VER='1',
 PACK_TYPE='0402',
 LOCATION='C267',
 CDS_LIB='pure_quanta',
 CDS_PART_NAME='Q_CAP_0402-1UF,16V,10%,EMPTY,TA',
 TOLERANCE='10%',
 MATERIAL='EMPTY',
 VOLTAGE='16V',
 VALUE='1UF',
 PRIM_FILE='W:/<user>/logical/q_cap/chips/chips.prt';

PART_NAME
 C268 'Q_CAP_0402-0.1UF,25V,10%,X7R,CA':;

SECTION_NUMBER 1
 '@SCM_LIB.SCM(SCH_1):PAGE30_I229@PURE_QUANTA.Q_CAP(CHIPS)':
 C_PATH='@scm_lib.scm(sch_1):page30_i229@pure_quanta.q_cap(chips)',
 P_PATH='@scm_lib.scm(sch_1):page30_i229@pure_quanta.q_cap(chips)',
 PATH='I229',
 DRAWING='@SCM_LIB.SCM(SCH_1):PAGE30',
 PHYS_PAGE='30',
 XY='(375,2500)',
 ROT='0',
 VER='1',
 PACK_TYPE='0402',
 LOCATION='C268',
 CDS_LIB='pure_quanta',
 CDS_PART_NAME='Q_CAP_0402-0.1UF,25V,10%,X7R,CA',
 TOLERANCE='10%',
 MATERIAL='X7R',
 VOLTAGE='25V',
 VALUE='0.1UF',
 PRIM_FILE='W:/<user>/logical/q_cap/chips/chips.prt';

PART_NAME
 C269 'Q_CAP_0402-0.1UF,25V,10%,X7R,CA':;

SECTION_NUMBER 1
 '@SCM_LIB.SCM(SCH_1):PAGE41_I118@PURE_QUANTA.Q_CAP(CHIPS)':
 C_PATH='@scm_lib.scm(sch_1):page41_i118@pure_quanta.q_cap(chips)',
 P_PATH='@scm_lib.scm(sch_1):page41_i118@pure_quanta.q_cap(chips)',
 PATH='I118',
 DRAWING='@SCM_LIB.SCM(SCH_1):PAGE41',
 PHYS_PAGE='41',
 XY='(-1200,1950)',
 ROT='0',
 VER='1',
 PACK_TYPE='0402',
 CDS_LIB='pure_quanta',
 CDS_PART_NAME='Q_CAP_0402-0.1UF,25V,10%,X7R,CA',
 TOLERANCE='10%',
 MATERIAL='X7R',
 VOLTAGE='25V',
 VALUE='0.1UF',
 PRIM_FILE='W:/<user>/logical/q_cap/chips/chips.prt';

PART_NAME
 C270 'Q_CAP_0402-1UF,16V,10%,EMPTY,TA':;

SECTION_NUMBER 1
 '@SCM_LIB.SCM(SCH_1):PAGE17_I239@PURE_QUANTA.Q_CAP(CHIPS)':
 C_PATH='@scm_lib.scm(sch_1):page17_i239@pure_quanta.q_cap(chips)',
 P_PATH='@scm_lib.scm(sch_1):page17_i239@pure_quanta.q_cap(chips)',
 PATH='I239',
 DRAWING='@SCM_LIB.SCM(SCH_1):PAGE17',
 PHYS_PAGE='17',
 XY='(2200,-1375)',
 ROT='0',
 VER='1',
 PACK_TYPE='0402',
 LOCATION='C270',
 CDS_LIB='pure_quanta',
 CDS_PART_NAME='Q_CAP_0402-1UF,16V,10%,EMPTY,TA',
 TOLERANCE='10%',
 MATERIAL='EMPTY',
 VOLTAGE='16V',
 VALUE='1UF',
 PRIM_FILE='W:/<user>/logical/q_cap/chips/chips.prt';

PART_NAME
 C271 'Q_CAP_0402-0.1UF,25V,10%,X7R,CA':;

SECTION_NUMBER 1
 '@SCM_LIB.SCM(SCH_1):PAGE12_I429@PURE_QUANTA.Q_CAP(CHIPS)':
 C_PATH='@scm_lib.scm(sch_1):page12_i429@pure_quanta.q_cap(chips)',
 P_PATH='@scm_lib.scm(sch_1):page12_i429@pure_quanta.q_cap(chips)',
 PATH='I429',
 DRAWING='@SCM_LIB.SCM(SCH_1):PAGE12',
 PHYS_PAGE='12',
 XY='(3825,4200)',
 ROT='0',
 VER='2',
 PACK_TYPE='0402',
 CDS_LIB='pure_quanta',
 CDS_PART_NAME='Q_CAP_0402-0.1UF,25V,10%,X7R,CA',
 TOLERANCE='10%',
 MATERIAL='X7R',
 VOLTAGE='25V',
 VALUE='0.1UF',
 PRIM_FILE='W:/<user>/logical/q_cap/chips/chips.prt';

PART_NAME
 C272 'Q_CAP_0402-0.1UF,25V,10%,X7R,CA':;

SECTION_NUMBER 1
 '@SCM_LIB.SCM(SCH_1):PAGE12_I428@PURE_QUANTA.Q_CAP(CHIPS)':
 C_PATH='@scm_lib.scm(sch_1):page12_i428@pure_quanta.q_cap(chips)',
 P_PATH='@scm_lib.scm(sch_1):page12_i428@pure_quanta.q_cap(chips)',
 PATH='I428',
 DRAWING='@SCM_LIB.SCM(SCH_1):PAGE12',
 PHYS_PAGE='12',
 XY='(3825,4150)',
 ROT='0',
 VER='2',
 PACK_TYPE='0402',
 CDS_LIB='pure_quanta',
 CDS_PART_NAME='Q_CAP_0402-0.1UF,25V,10%,X7R,CA',
 TOLERANCE='10%',
 MATERIAL='X7R',
 VOLTAGE='25V',
 VALUE='0.1UF',
 PRIM_FILE='W:/<user>/logical/q_cap/chips/chips.prt';

PART_NAME
 C273 'Q_CAP_0402-1UF,16V,10%,EMPTY,TA':;

SECTION_NUMBER 1
 '@SCM_LIB.SCM(SCH_1):PAGE17_I234@PURE_QUANTA.Q_CAP(CHIPS)':
 C_PATH='@scm_lib.scm(sch_1):page17_i234@pure_quanta.q_cap(chips)',
 P_PATH='@scm_lib.scm(sch_1):page17_i234@pure_quanta.q_cap(chips)',
 PATH='I234',
 DRAWING='@SCM_LIB.SCM(SCH_1):PAGE17',
 PHYS_PAGE='17',
 XY='(3300,-1400)',
 ROT='0',
 VER='1',
 PACK_TYPE='0402',
 LOCATION='C273',
 CDS_LIB='pure_quanta',
 CDS_PART_NAME='Q_CAP_0402-1UF,16V,10%,EMPTY,TA',
 TOLERANCE='10%',
 MATERIAL='EMPTY',
 VOLTAGE='16V',
 VALUE='1UF',
 PRIM_FILE='W:/<user>/logical/q_cap/chips/chips.prt';

PART_NAME
 C274 'Q_CAP_0402-0.1UF,25V,10%,X7R,CA':;

SECTION_NUMBER 1
 '@SCM_LIB.SCM(SCH_1):PAGE49_I13@PURE_QUANTA.Q_CAP(CHIPS)':
 C_PATH='@scm_lib.scm(sch_1):page49_i13@pure_quanta.q_cap(chips)',
 P_PATH='@scm_lib.scm(sch_1):page49_i13@pure_quanta.q_cap(chips)',
 PATH='I13',
 DRAWING='@SCM_LIB.SCM(SCH_1):PAGE49',
 PHYS_PAGE='49',
 XY='(-7875,5700)',
 ROT='2',
 VER='1',
 PACK_TYPE='0402',
 CDS_LIB='pure_quanta',
 CDS_PART_NAME='Q_CAP_0402-0.1UF,25V,10%,X7R,CA',
 TOLERANCE='10%',
 MATERIAL='X7R',
 VOLTAGE='25V',
 VALUE='0.1UF',
 PRIM_FILE='W:/<user>/logical/q_cap/chips/chips.prt';

PART_NAME
 C275 'Q_CAP_0402-100PF,50V,5%,NPO,CHA':;

SECTION_NUMBER 1
 '@SCM_LIB.SCM(SCH_1):PAGE15_I180@PURE_QUANTA.Q_CAP(CHIPS)':
 C_PATH='@scm_lib.scm(sch_1):page15_i180@pure_quanta.q_cap(chips)',
 P_PATH='@scm_lib.scm(sch_1):page15_i180@pure_quanta.q_cap(chips)',
 PATH='I180',
 DRAWING='@SCM_LIB.SCM(SCH_1):PAGE15',
 PHYS_PAGE='15',
 XY='(1100,-1250)',
 ROT='0',
 VER='1',
 PACK_TYPE='0402',
 LOCATION='C275',
 CDS_LIB='pure_quanta',
 CDS_PART_NAME='Q_CAP_0402-100PF,50V,5%,NPO,CHA',
 TOLERANCE='5%',
 MATERIAL='NPO',
 VOLTAGE='50V',
 VALUE='100PF',
 PRIM_FILE='W:/<user>/logical/q_cap/chips/chips.prt';

PART_NAME
 C276 'Q_CAP_0402-0.1UF,25V,10%,X7R,CA':;

SECTION_NUMBER 1
 '@SCM_LIB.SCM(SCH_1):PAGE49_I75@PURE_QUANTA.Q_CAP(CHIPS)':
 C_PATH='@scm_lib.scm(sch_1):page49_i75@pure_quanta.q_cap(chips)',
 P_PATH='@scm_lib.scm(sch_1):page49_i75@pure_quanta.q_cap(chips)',
 PATH='I75',
 DRAWING='@SCM_LIB.SCM(SCH_1):PAGE49',
 PHYS_PAGE='49',
 XY='(-5900,5625)',
 ROT='2',
 VER='1',
 PACK_TYPE='0402',
 CDS_LIB='pure_quanta',
 CDS_PART_NAME='Q_CAP_0402-0.1UF,25V,10%,X7R,CA',
 TOLERANCE='10%',
 MATERIAL='X7R',
 VOLTAGE='25V',
 VALUE='0.1UF',
 PRIM_FILE='W:/<user>/logical/q_cap/chips/chips.prt';

PART_NAME
 C277 'Q_CAP_C0402-1UF,25V,10%,X6S,CHA':;

SECTION_NUMBER 1
 '@SCM_LIB.SCM(SCH_1):PAGE17_I253@PURE_QUANTA.Q_CAP(CHIPS)':
 C_PATH='@scm_lib.scm(sch_1):page17_i253@pure_quanta.q_cap(chips)',
 P_PATH='@scm_lib.scm(sch_1):page17_i253@pure_quanta.q_cap(chips)',
 PATH='I253',
 DRAWING='@SCM_LIB.SCM(SCH_1):PAGE17',
 PHYS_PAGE='17',
 XY='(-2900,-1225)',
 ROT='0',
 VER='1',
 PACK_TYPE='C0402',
 LOCATION='C277',
 CDS_LIB='pure_quanta',
 CDS_PART_NAME='Q_CAP_C0402-1UF,25V,10%,X6S,CHA',
 TOLERANCE='10%',
 MATERIAL='X6S',
 VOLTAGE='25V',
 VALUE='1UF',
 PRIM_FILE='W:/<user>/logical/q_cap/chips/chips.prt';

PART_NAME
 C278 'Q_CAP_0402-0.1UF,25V,10%,X7R,CA':;

SECTION_NUMBER 1
 '@SCM_LIB.SCM(SCH_1):PAGE55_I54@PURE_QUANTA.Q_CAP(CHIPS)':
 C_PATH='@scm_lib.scm(sch_1):page55_i54@pure_quanta.q_cap(chips)',
 P_PATH='@scm_lib.scm(sch_1):page55_i54@pure_quanta.q_cap(chips)',
 PATH='I54',
 DRAWING='@SCM_LIB.SCM(SCH_1):PAGE55',
 PHYS_PAGE='55',
 XY='(-3375,1375)',
 ROT='0',
 VER='1',
 PACK_TYPE='0402',
 CDS_LIB='pure_quanta',
 CDS_PART_NAME='Q_CAP_0402-0.1UF,25V,10%,X7R,CA',
 TOLERANCE='10%',
 MATERIAL='X7R',
 VOLTAGE='25V',
 VALUE='0.1UF',
 PRIM_FILE='W:/<user>/logical/q_cap/chips/chips.prt';

PART_NAME
 C279 'Q_CAP_0402-0.1UF,25V,10%,X7R,CA':;

SECTION_NUMBER 1
 '@SCM_LIB.SCM(SCH_1):PAGE17_I255@PURE_QUANTA.Q_CAP(CHIPS)':
 C_PATH='@scm_lib.scm(sch_1):page17_i255@pure_quanta.q_cap(chips)',
 P_PATH='@scm_lib.scm(sch_1):page17_i255@pure_quanta.q_cap(chips)',
 PATH='I255',
 DRAWING='@SCM_LIB.SCM(SCH_1):PAGE17',
 PHYS_PAGE='17',
 XY='(-2550,-1225)',
 ROT='0',
 VER='1',
 PACK_TYPE='0402',
 LOCATION='C279',
 CDS_LIB='pure_quanta',
 CDS_PART_NAME='Q_CAP_0402-0.1UF,25V,10%,X7R,CA',
 TOLERANCE='10%',
 MATERIAL='X7R',
 VOLTAGE='25V',
 VALUE='0.1UF',
 PRIM_FILE='W:/<user>/logical/q_cap/chips/chips.prt';

PART_NAME
 C280 'Q_CAP_0402-0.1UF,25V,10%,X7R,CA':;

SECTION_NUMBER 1
 '@SCM_LIB.SCM(SCH_1):PAGE56_I58@PURE_QUANTA.Q_CAP(CHIPS)':
 C_PATH='@scm_lib.scm(sch_1):page56_i58@pure_quanta.q_cap(chips)',
 P_PATH='@scm_lib.scm(sch_1):page56_i58@pure_quanta.q_cap(chips)',
 PATH='I58',
 DRAWING='@SCM_LIB.SCM(SCH_1):PAGE56',
 PHYS_PAGE='56',
 XY='(-5225,1125)',
 ROT='0',
 VER='1',
 PACK_TYPE='0402',
 CDS_LIB='pure_quanta',
 CDS_PART_NAME='Q_CAP_0402-0.1UF,25V,10%,X7R,CA',
 TOLERANCE='10%',
 MATERIAL='X7R',
 VOLTAGE='25V',
 VALUE='0.1UF',
 PRIM_FILE='W:/<user>/logical/q_cap/chips/chips.prt';

PART_NAME
 C281 'Q_CAP_C0402-0.01UF,50V,10%,EMPA':;

SECTION_NUMBER 1
 '@SCM_LIB.SCM(SCH_1):PAGE41_I125@PURE_QUANTA.Q_CAP(CHIPS)':
 C_PATH='@scm_lib.scm(sch_1):page41_i125@pure_quanta.q_cap(chips)',
 P_PATH='@scm_lib.scm(sch_1):page41_i125@pure_quanta.q_cap(chips)',
 PATH='I125',
 DRAWING='@SCM_LIB.SCM(SCH_1):PAGE41',
 PHYS_PAGE='41',
 XY='(-1575,4675)',
 ROT='0',
 VER='1',
 PACK_TYPE='C0402',
 CDS_LIB='pure_quanta',
 CDS_PART_NAME='Q_CAP_C0402-0.01UF,50V,10%,EMPA',
 TOLERANCE='10%',
 MATERIAL='EMPTY',
 VOLTAGE='50V',
 VALUE='0.01UF',
 PRIM_FILE='W:/<user>/logical/q_cap/chips/chips.prt';

PART_NAME
 C282 'Q_CAP_C0402-1UF,25V,10%,X6S,CHA':;

SECTION_NUMBER 1
 '@SCM_LIB.SCM(SCH_1):PAGE17_I252@PURE_QUANTA.Q_CAP(CHIPS)':
 C_PATH='@scm_lib.scm(sch_1):page17_i252@pure_quanta.q_cap(chips)',
 P_PATH='@scm_lib.scm(sch_1):page17_i252@pure_quanta.q_cap(chips)',
 PATH='I252',
 DRAWING='@SCM_LIB.SCM(SCH_1):PAGE17',
 PHYS_PAGE='17',
 XY='(-600,-1225)',
 ROT='0',
 VER='1',
 PACK_TYPE='C0402',
 LOCATION='C282',
 CDS_LIB='pure_quanta',
 CDS_PART_NAME='Q_CAP_C0402-1UF,25V,10%,X6S,CHA',
 TOLERANCE='10%',
 MATERIAL='X6S',
 VOLTAGE='25V',
 VALUE='1UF',
 PRIM_FILE='W:/<user>/logical/q_cap/chips/chips.prt';

PART_NAME
 C283 'Q_CAP_C0402-0.01UF,50V,10%,EMPA':;

SECTION_NUMBER 1
 '@SCM_LIB.SCM(SCH_1):PAGE41_I126@PURE_QUANTA.Q_CAP(CHIPS)':
 C_PATH='@scm_lib.scm(sch_1):page41_i126@pure_quanta.q_cap(chips)',
 P_PATH='@scm_lib.scm(sch_1):page41_i126@pure_quanta.q_cap(chips)',
 PATH='I126',
 DRAWING='@SCM_LIB.SCM(SCH_1):PAGE41',
 PHYS_PAGE='41',
 XY='(-1550,5850)',
 ROT='0',
 VER='1',
 PACK_TYPE='C0402',
 CDS_LIB='pure_quanta',
 CDS_PART_NAME='Q_CAP_C0402-0.01UF,50V,10%,EMPA',
 TOLERANCE='10%',
 MATERIAL='EMPTY',
 VOLTAGE='50V',
 VALUE='0.01UF',
 PRIM_FILE='W:/<user>/logical/q_cap/chips/chips.prt';

PART_NAME
 C284 'Q_CAP_0402-0.1UF,25V,10%,X7R,CA':;

SECTION_NUMBER 1
 '@SCM_LIB.SCM(SCH_1):PAGE17_I250@PURE_QUANTA.Q_CAP(CHIPS)':
 C_PATH='@scm_lib.scm(sch_1):page17_i250@pure_quanta.q_cap(chips)',
 P_PATH='@scm_lib.scm(sch_1):page17_i250@pure_quanta.q_cap(chips)',
 PATH='I250',
 DRAWING='@SCM_LIB.SCM(SCH_1):PAGE17',
 PHYS_PAGE='17',
 XY='(-250,-1225)',
 ROT='0',
 VER='1',
 PACK_TYPE='0402',
 LOCATION='C284',
 CDS_LIB='pure_quanta',
 CDS_PART_NAME='Q_CAP_0402-0.1UF,25V,10%,X7R,CA',
 TOLERANCE='10%',
 MATERIAL='X7R',
 VOLTAGE='25V',
 VALUE='0.1UF',
 PRIM_FILE='W:/<user>/logical/q_cap/chips/chips.prt';

PART_NAME
 C285 'Q_CAP_C0402-0.01UF,50V,10%,EMPA':;

SECTION_NUMBER 1
 '@SCM_LIB.SCM(SCH_1):PAGE41_I124@PURE_QUANTA.Q_CAP(CHIPS)':
 C_PATH='@scm_lib.scm(sch_1):page41_i124@pure_quanta.q_cap(chips)',
 P_PATH='@scm_lib.scm(sch_1):page41_i124@pure_quanta.q_cap(chips)',
 PATH='I124',
 DRAWING='@SCM_LIB.SCM(SCH_1):PAGE41',
 PHYS_PAGE='41',
 XY='(-1550,3575)',
 ROT='0',
 VER='1',
 PACK_TYPE='C0402',
 CDS_LIB='pure_quanta',
 CDS_PART_NAME='Q_CAP_C0402-0.01UF,50V,10%,EMPA',
 TOLERANCE='10%',
 MATERIAL='EMPTY',
 VOLTAGE='50V',
 VALUE='0.01UF',
 PRIM_FILE='W:/<user>/logical/q_cap/chips/chips.prt';

PART_NAME
 C286 'Q_CAP_C0402-0.01UF,50V,10%,EMPA':;

SECTION_NUMBER 1
 '@SCM_LIB.SCM(SCH_1):PAGE41_I123@PURE_QUANTA.Q_CAP(CHIPS)':
 C_PATH='@scm_lib.scm(sch_1):page41_i123@pure_quanta.q_cap(chips)',
 P_PATH='@scm_lib.scm(sch_1):page41_i123@pure_quanta.q_cap(chips)',
 PATH='I123',
 DRAWING='@SCM_LIB.SCM(SCH_1):PAGE41',
 PHYS_PAGE='41',
 XY='(-575,1950)',
 ROT='0',
 VER='1',
 PACK_TYPE='C0402',
 CDS_LIB='pure_quanta',
 CDS_PART_NAME='Q_CAP_C0402-0.01UF,50V,10%,EMPA',
 TOLERANCE='10%',
 MATERIAL='EMPTY',
 VOLTAGE='50V',
 VALUE='0.01UF',
 PRIM_FILE='W:/<user>/logical/q_cap/chips/chips.prt';

PART_NAME
 C287 'Q_CAP_C0402-1UF,25V,10%,X6S,CHA':;

SECTION_NUMBER 1
 '@SCM_LIB.SCM(SCH_1):PAGE53_I67@PURE_QUANTA.Q_CAP(CHIPS)':
 C_PATH='@scm_lib.scm(sch_1):page53_i67@pure_quanta.q_cap(chips)',
 P_PATH='@scm_lib.scm(sch_1):page53_i67@pure_quanta.q_cap(chips)',
 PATH='I67',
 DRAWING='@SCM_LIB.SCM(SCH_1):PAGE53',
 PHYS_PAGE='53',
 XY='(-1650,1100)',
 ROT='0',
 VER='1',
 PACK_TYPE='C0402',
 CDS_LIB='pure_quanta',
 CDS_PART_NAME='Q_CAP_C0402-1UF,25V,10%,X6S,CHA',
 TOLERANCE='10%',
 MATERIAL='X6S',
 VOLTAGE='25V',
 VALUE='1UF',
 PRIM_FILE='W:/<user>/logical/q_cap/chips/chips.prt';

PART_NAME
 C288 'Q_CAP_C0805-10UF,25V,10%,X6S,CA':;

SECTION_NUMBER 1
 '@SCM_LIB.SCM(SCH_1):PAGE53_I71@PURE_QUANTA.Q_CAP(CHIPS)':
 C_PATH='@scm_lib.scm(sch_1):page53_i71@pure_quanta.q_cap(chips)',
 P_PATH='@scm_lib.scm(sch_1):page53_i71@pure_quanta.q_cap(chips)',
 PATH='I71',
 DRAWING='@SCM_LIB.SCM(SCH_1):PAGE53',
 PHYS_PAGE='53',
 XY='(400,1275)',
 ROT='0',
 VER='1',
 PACK_TYPE='C0805',
 CDS_LIB='pure_quanta',
 CDS_PART_NAME='Q_CAP_C0805-10UF,25V,10%,X6S,CA',
 TOLERANCE='10%',
 MATERIAL='X6S',
 VOLTAGE='25V',
 VALUE='10UF',
 PRIM_FILE='W:/<user>/logical/q_cap/chips/chips.prt';

PART_NAME
 C289 'Q_CAP_C0805-10UF,25V,10%,X6S,CA':;

SECTION_NUMBER 1
 '@SCM_LIB.SCM(SCH_1):PAGE53_I69@PURE_QUANTA.Q_CAP(CHIPS)':
 C_PATH='@scm_lib.scm(sch_1):page53_i69@pure_quanta.q_cap(chips)',
 P_PATH='@scm_lib.scm(sch_1):page53_i69@pure_quanta.q_cap(chips)',
 PATH='I69',
 DRAWING='@SCM_LIB.SCM(SCH_1):PAGE53',
 PHYS_PAGE='53',
 XY='(1250,250)',
 ROT='0',
 VER='1',
 PACK_TYPE='C0805',
 CDS_LIB='pure_quanta',
 CDS_PART_NAME='Q_CAP_C0805-10UF,25V,10%,X6S,CA',
 TOLERANCE='10%',
 MATERIAL='X6S',
 VOLTAGE='25V',
 VALUE='10UF',
 PRIM_FILE='W:/<user>/logical/q_cap/chips/chips.prt';

PART_NAME
 C290 'Q_CAP_0402-0.1UF,25V,10%,X7R,CA':;

SECTION_NUMBER 1
 '@SCM_LIB.SCM(SCH_1):PAGE15_I201@PURE_QUANTA.Q_CAP(CHIPS)':
 C_PATH='@scm_lib.scm(sch_1):page15_i201@pure_quanta.q_cap(chips)',
 P_PATH='@scm_lib.scm(sch_1):page15_i201@pure_quanta.q_cap(chips)',
 PATH='I201',
 DRAWING='@SCM_LIB.SCM(SCH_1):PAGE15',
 PHYS_PAGE='15',
 XY='(-2425,3100)',
 ROT='0',
 VER='1',
 PACK_TYPE='0402',
 LOCATION='C290',
 CDS_LIB='pure_quanta',
 CDS_PART_NAME='Q_CAP_0402-0.1UF,25V,10%,X7R,CA',
 TOLERANCE='10%',
 MATERIAL='X7R',
 VOLTAGE='25V',
 VALUE='0.1UF',
 PRIM_FILE='W:/<user>/logical/q_cap/chips/chips.prt';

PART_NAME
 C291 'Q_CAP_0402-0.1UF,25V,10%,X7R,CA':;

SECTION_NUMBER 1
 '@SCM_LIB.SCM(SCH_1):PAGE53_I70@PURE_QUANTA.Q_CAP(CHIPS)':
 C_PATH='@scm_lib.scm(sch_1):page53_i70@pure_quanta.q_cap(chips)',
 P_PATH='@scm_lib.scm(sch_1):page53_i70@pure_quanta.q_cap(chips)',
 PATH='I70',
 DRAWING='@SCM_LIB.SCM(SCH_1):PAGE53',
 PHYS_PAGE='53',
 XY='(1900,250)',
 ROT='0',
 VER='1',
 PACK_TYPE='0402',
 CDS_LIB='pure_quanta',
 CDS_PART_NAME='Q_CAP_0402-0.1UF,25V,10%,X7R,CA',
 TOLERANCE='10%',
 MATERIAL='X7R',
 VOLTAGE='25V',
 VALUE='0.1UF',
 PRIM_FILE='W:/<user>/logical/q_cap/chips/chips.prt';

PART_NAME
 C292 'Q_CAP_C0402-1UF,25V,10%,X6S,CHA':;

SECTION_NUMBER 1
 '@SCM_LIB.SCM(SCH_1):PAGE54_I107@PURE_QUANTA.Q_CAP(CHIPS)':
 C_PATH='@scm_lib.scm(sch_1):page54_i107@pure_quanta.q_cap(chips)',
 P_PATH='@scm_lib.scm(sch_1):page54_i107@pure_quanta.q_cap(chips)',
 PATH='I107',
 DRAWING='@SCM_LIB.SCM(SCH_1):PAGE54',
 PHYS_PAGE='54',
 XY='(-1000,2850)',
 ROT='0',
 VER='1',
 PACK_TYPE='C0402',
 CDS_LIB='pure_quanta',
 CDS_PART_NAME='Q_CAP_C0402-1UF,25V,10%,X6S,CHA',
 TOLERANCE='10%',
 MATERIAL='X6S',
 VOLTAGE='25V',
 VALUE='1UF',
 PRIM_FILE='W:/<user>/logical/q_cap/chips/chips.prt';

PART_NAME
 C293 'Q_CAP_C0805-10UF,25V,10%,X6S,CA':;

SECTION_NUMBER 1
 '@SCM_LIB.SCM(SCH_1):PAGE54_I106@PURE_QUANTA.Q_CAP(CHIPS)':
 C_PATH='@scm_lib.scm(sch_1):page54_i106@pure_quanta.q_cap(chips)',
 P_PATH='@scm_lib.scm(sch_1):page54_i106@pure_quanta.q_cap(chips)',
 PATH='I106',
 DRAWING='@SCM_LIB.SCM(SCH_1):PAGE54',
 PHYS_PAGE='54',
 XY='(1050,3025)',
 ROT='0',
 VER='1',
 PACK_TYPE='C0805',
 CDS_LIB='pure_quanta',
 CDS_PART_NAME='Q_CAP_C0805-10UF,25V,10%,X6S,CA',
 TOLERANCE='10%',
 MATERIAL='X6S',
 VOLTAGE='25V',
 VALUE='10UF',
 PRIM_FILE='W:/<user>/logical/q_cap/chips/chips.prt';

PART_NAME
 C294 'Q_CAP_0402-0.1UF,25V,10%,X7R,CA':;

SECTION_NUMBER 1
 '@SCM_LIB.SCM(SCH_1):PAGE54_I105@PURE_QUANTA.Q_CAP(CHIPS)':
 C_PATH='@scm_lib.scm(sch_1):page54_i105@pure_quanta.q_cap(chips)',
 P_PATH='@scm_lib.scm(sch_1):page54_i105@pure_quanta.q_cap(chips)',
 PATH='I105',
 DRAWING='@SCM_LIB.SCM(SCH_1):PAGE54',
 PHYS_PAGE='54',
 XY='(2500,2000)',
 ROT='0',
 VER='1',
 PACK_TYPE='0402',
 CDS_LIB='pure_quanta',
 CDS_PART_NAME='Q_CAP_0402-0.1UF,25V,10%,X7R,CA',
 TOLERANCE='10%',
 MATERIAL='X7R',
 VOLTAGE='25V',
 VALUE='0.1UF',
 PRIM_FILE='W:/<user>/logical/q_cap/chips/chips.prt';

PART_NAME
 C295 'Q_CAP_0402-0.1UF,25V,10%,X7R,CA':;

SECTION_NUMBER 1
 '@SCM_LIB.SCM(SCH_1):PAGE15_I207@PURE_QUANTA.Q_CAP(CHIPS)':
 C_PATH='@scm_lib.scm(sch_1):page15_i207@pure_quanta.q_cap(chips)',
 P_PATH='@scm_lib.scm(sch_1):page15_i207@pure_quanta.q_cap(chips)',
 PATH='I207',
 DRAWING='@SCM_LIB.SCM(SCH_1):PAGE15',
 PHYS_PAGE='15',
 XY='(-2425,2150)',
 ROT='0',
 VER='1',
 PACK_TYPE='0402',
 LOCATION='C295',
 CDS_LIB='pure_quanta',
 CDS_PART_NAME='Q_CAP_0402-0.1UF,25V,10%,X7R,CA',
 TOLERANCE='10%',
 MATERIAL='X7R',
 VOLTAGE='25V',
 VALUE='0.1UF',
 PRIM_FILE='W:/<user>/logical/q_cap/chips/chips.prt';

PART_NAME
 C296 'Q_CAP_0402-0.1UF,25V,10%,X7R,CA':;

SECTION_NUMBER 1
 '@SCM_LIB.SCM(SCH_1):PAGE52_I119@PURE_QUANTA.Q_CAP(CHIPS)':
 C_PATH='@scm_lib.scm(sch_1):page52_i119@pure_quanta.q_cap(chips)',
 P_PATH='@scm_lib.scm(sch_1):page52_i119@pure_quanta.q_cap(chips)',
 PATH='I119',
 DRAWING='@SCM_LIB.SCM(SCH_1):PAGE52',
 PHYS_PAGE='52',
 XY='(3900,-925)',
 ROT='2',
 VER='1',
 PACK_TYPE='0402',
 CDS_LIB='pure_quanta',
 CDS_PART_NAME='Q_CAP_0402-0.1UF,25V,10%,X7R,CA',
 TOLERANCE='10%',
 MATERIAL='X7R',
 VOLTAGE='25V',
 VALUE='0.1UF',
 PRIM_FILE='W:/<user>/logical/q_cap/chips/chips.prt';

PART_NAME
 C297 'Q_CAP_0402-0.1UF,25V,10%,X7R,CA':;

SECTION_NUMBER 1
 '@SCM_LIB.SCM(SCH_1):PAGE52_I107@PURE_QUANTA.Q_CAP(CHIPS)':
 C_PATH='@scm_lib.scm(sch_1):page52_i107@pure_quanta.q_cap(chips)',
 P_PATH='@scm_lib.scm(sch_1):page52_i107@pure_quanta.q_cap(chips)',
 PATH='I107',
 DRAWING='@SCM_LIB.SCM(SCH_1):PAGE52',
 PHYS_PAGE='52',
 XY='(2250,3100)',
 ROT='2',
 VER='1',
 PACK_TYPE='0402',
 CDS_LIB='pure_quanta',
 CDS_PART_NAME='Q_CAP_0402-0.1UF,25V,10%,X7R,CA',
 TOLERANCE='10%',
 MATERIAL='X7R',
 VOLTAGE='25V',
 VALUE='0.1UF',
 PRIM_FILE='W:/<user>/logical/q_cap/chips/chips.prt';

PART_NAME
 C298 'Q_CAP_0402-0.1UF,25V,10%,X7R,CA':;

SECTION_NUMBER 1
 '@SCM_LIB.SCM(SCH_1):PAGE54_I112@PURE_QUANTA.Q_CAP(CHIPS)':
 C_PATH='@scm_lib.scm(sch_1):page54_i112@pure_quanta.q_cap(chips)',
 P_PATH='@scm_lib.scm(sch_1):page54_i112@pure_quanta.q_cap(chips)',
 PATH='I112',
 DRAWING='@SCM_LIB.SCM(SCH_1):PAGE54',
 PHYS_PAGE='54',
 XY='(1500,50)',
 ROT='2',
 VER='1',
 PACK_TYPE='0402',
 CDS_LIB='pure_quanta',
 CDS_PART_NAME='Q_CAP_0402-0.1UF,25V,10%,X7R,CA',
 TOLERANCE='10%',
 MATERIAL='X7R',
 VOLTAGE='25V',
 VALUE='0.1UF',
 PRIM_FILE='W:/<user>/logical/q_cap/chips/chips.prt';

PART_NAME
 C299 'Q_CAP_0402-0.1UF,25V,10%,X7R,CA':;

SECTION_NUMBER 1
 '@SCM_LIB.SCM(SCH_1):PAGE15_I215@PURE_QUANTA.Q_CAP(CHIPS)':
 C_PATH='@scm_lib.scm(sch_1):page15_i215@pure_quanta.q_cap(chips)',
 P_PATH='@scm_lib.scm(sch_1):page15_i215@pure_quanta.q_cap(chips)',
 PATH='I215',
 DRAWING='@SCM_LIB.SCM(SCH_1):PAGE15',
 PHYS_PAGE='15',
 XY='(-2425,1150)',
 ROT='0',
 VER='1',
 PACK_TYPE='0402',
 LOCATION='C299',
 CDS_LIB='pure_quanta',
 CDS_PART_NAME='Q_CAP_0402-0.1UF,25V,10%,X7R,CA',
 TOLERANCE='10%',
 MATERIAL='X7R',
 VOLTAGE='25V',
 VALUE='0.1UF',
 PRIM_FILE='W:/<user>/logical/q_cap/chips/chips.prt';

PART_NAME
 C300 'Q_CAP_0402-0.1UF,25V,10%,X7R,CA':;

SECTION_NUMBER 1
 '@SCM_LIB.SCM(SCH_1):PAGE28_I146@PURE_QUANTA.Q_CAP(CHIPS)':
 C_PATH='@scm_lib.scm(sch_1):page28_i146@pure_quanta.q_cap(chips)',
 P_PATH='@scm_lib.scm(sch_1):page28_i146@pure_quanta.q_cap(chips)',
 PATH='I146',
 DRAWING='@SCM_LIB.SCM(SCH_1):PAGE28',
 PHYS_PAGE='28',
 XY='(-1475,-300)',
 ROT='0',
 VER='1',
 PACK_TYPE='0402',
 LOCATION='C300',
 CDS_LIB='pure_quanta',
 CDS_PART_NAME='Q_CAP_0402-0.1UF,25V,10%,X7R,CA',
 TOLERANCE='10%',
 MATERIAL='X7R',
 VOLTAGE='25V',
 VALUE='0.1UF',
 PRIM_FILE='W:/<user>/logical/q_cap/chips/chips.prt';

PART_NAME
 C301 'Q_CAP_0402-0.1UF,25V,10%,X7R,CA':;

SECTION_NUMBER 1
 '@SCM_LIB.SCM(SCH_1):PAGE55_I61@PURE_QUANTA.Q_CAP(CHIPS)':
 C_PATH='@scm_lib.scm(sch_1):page55_i61@pure_quanta.q_cap(chips)',
 P_PATH='@scm_lib.scm(sch_1):page55_i61@pure_quanta.q_cap(chips)',
 PATH='I61',
 DRAWING='@SCM_LIB.SCM(SCH_1):PAGE55',
 PHYS_PAGE='55',
 XY='(-1700,3425)',
 ROT='2',
 VER='1',
 PACK_TYPE='0402',
 CDS_LIB='pure_quanta',
 CDS_PART_NAME='Q_CAP_0402-0.1UF,25V,10%,X7R,CA',
 TOLERANCE='10%',
 MATERIAL='X7R',
 VOLTAGE='25V',
 VALUE='0.1UF',
 PRIM_FILE='W:/<user>/logical/q_cap/chips/chips.prt';

PART_NAME
 C302 'Q_CAP_0402-0.1UF,25V,10%,X7R,CA':;

SECTION_NUMBER 1
 '@SCM_LIB.SCM(SCH_1):PAGE56_I64@PURE_QUANTA.Q_CAP(CHIPS)':
 C_PATH='@scm_lib.scm(sch_1):page56_i64@pure_quanta.q_cap(chips)',
 P_PATH='@scm_lib.scm(sch_1):page56_i64@pure_quanta.q_cap(chips)',
 PATH='I64',
 DRAWING='@SCM_LIB.SCM(SCH_1):PAGE56',
 PHYS_PAGE='56',
 XY='(-3450,3250)',
 ROT='2',
 VER='1',
 PACK_TYPE='0402',
 CDS_LIB='pure_quanta',
 CDS_PART_NAME='Q_CAP_0402-0.1UF,25V,10%,X7R,CA',
 TOLERANCE='10%',
 MATERIAL='X7R',
 VOLTAGE='25V',
 VALUE='0.1UF',
 PRIM_FILE='W:/<user>/logical/q_cap/chips/chips.prt';

PART_NAME
 C303 'Q_CAP_0402-0.1UF,25V,10%,X7R,CA':;

SECTION_NUMBER 1
 '@SCM_LIB.SCM(SCH_1):PAGE15_I235@PURE_QUANTA.Q_CAP(CHIPS)':
 C_PATH='@scm_lib.scm(sch_1):page15_i235@pure_quanta.q_cap(chips)',
 P_PATH='@scm_lib.scm(sch_1):page15_i235@pure_quanta.q_cap(chips)',
 PATH='I235',
 DRAWING='@SCM_LIB.SCM(SCH_1):PAGE15',
 PHYS_PAGE='15',
 XY='(-2425,25)',
 ROT='0',
 VER='1',
 PACK_TYPE='0402',
 LOCATION='C303',
 CDS_LIB='pure_quanta',
 CDS_PART_NAME='Q_CAP_0402-0.1UF,25V,10%,X7R,CA',
 TOLERANCE='10%',
 MATERIAL='X7R',
 VOLTAGE='25V',
 VALUE='0.1UF',
 PRIM_FILE='W:/<user>/logical/q_cap/chips/chips.prt';

PART_NAME
 C304 'Q_CAP_0402-0.1UF,25V,10%,X7R,CA':;

SECTION_NUMBER 1
 '@SCM_LIB.SCM(SCH_1):PAGE25_I65@PURE_QUANTA.Q_CAP(CHIPS)':
 C_PATH='@scm_lib.scm(sch_1):page25_i65@pure_quanta.q_cap(chips)',
 P_PATH='@scm_lib.scm(sch_1):page25_i65@pure_quanta.q_cap(chips)',
 PATH='I65',
 DRAWING='@SCM_LIB.SCM(SCH_1):PAGE25',
 SEC_TYPE='0402',
 PHYS_PAGE='25',
 XY='(-25,-450)',
 ROT='0',
 VER='1',
 PACK_TYPE='0402',
 LOCATION='C304',
 SEC='1',
 CDS_LIB='pure_quanta',
 CDS_PART_NAME='Q_CAP_0402-0.1UF,25V,10%,X7R,CA',
 TOLERANCE='10%',
 MATERIAL='X7R',
 VOLTAGE='25V',
 VALUE='0.1UF',
 PRIM_FILE='W:/<user>/logical/q_cap/chips/chips.prt';

PART_NAME
 C305 'Q_CAP_C0402-1UF,25V,10%,X6S,CHA':;

SECTION_NUMBER 1
 '@SCM_LIB.SCM(SCH_1):PAGE52_I125@PURE_QUANTA.Q_CAP(CHIPS)':
 C_PATH='@scm_lib.scm(sch_1):page52_i125@pure_quanta.q_cap(chips)',
 P_PATH='@scm_lib.scm(sch_1):page52_i125@pure_quanta.q_cap(chips)',
 PATH='I125',
 DRAWING='@SCM_LIB.SCM(SCH_1):PAGE52',
 PHYS_PAGE='52',
 XY='(2925,-1650)',
 ROT='0',
 VER='1',
 PACK_TYPE='C0402',
 CDS_LIB='pure_quanta',
 CDS_PART_NAME='Q_CAP_C0402-1UF,25V,10%,X6S,CHA',
 TOLERANCE='10%',
 MATERIAL='X6S',
 VOLTAGE='25V',
 VALUE='1UF',
 PRIM_FILE='W:/<user>/logical/q_cap/chips/chips.prt';

PART_NAME
 C307 'Q_CAP_0402-0.1UF,25V,10%,X7R,CA':;

SECTION_NUMBER 1
 '@SCM_LIB.SCM(SCH_1):PAGE15_I240@PURE_QUANTA.Q_CAP(CHIPS)':
 C_PATH='@scm_lib.scm(sch_1):page15_i240@pure_quanta.q_cap(chips)',
 P_PATH='@scm_lib.scm(sch_1):page15_i240@pure_quanta.q_cap(chips)',
 PATH='I240',
 DRAWING='@SCM_LIB.SCM(SCH_1):PAGE15',
 PHYS_PAGE='15',
 XY='(-2425,-1075)',
 ROT='0',
 VER='1',
 PACK_TYPE='0402',
 LOCATION='C307',
 CDS_LIB='pure_quanta',
 CDS_PART_NAME='Q_CAP_0402-0.1UF,25V,10%,X7R,CA',
 TOLERANCE='10%',
 MATERIAL='X7R',
 VOLTAGE='25V',
 VALUE='0.1UF',
 PRIM_FILE='W:/<user>/logical/q_cap/chips/chips.prt';

PART_NAME
 C309 'Q_CAP_0402-0.1UF,25V,10%,X7R,CA':;

SECTION_NUMBER 1
 '@SCM_LIB.SCM(SCH_1):PAGE15_I247@PURE_QUANTA.Q_CAP(CHIPS)':
 C_PATH='@scm_lib.scm(sch_1):page15_i247@pure_quanta.q_cap(chips)',
 P_PATH='@scm_lib.scm(sch_1):page15_i247@pure_quanta.q_cap(chips)',
 PATH='I247',
 DRAWING='@SCM_LIB.SCM(SCH_1):PAGE15',
 PHYS_PAGE='15',
 XY='(-1650,1025)',
 ROT='0',
 VER='1',
 PACK_TYPE='0402',
 LOCATION='C309',
 CDS_LIB='pure_quanta',
 CDS_PART_NAME='Q_CAP_0402-0.1UF,25V,10%,X7R,CA',
 TOLERANCE='10%',
 MATERIAL='X7R',
 VOLTAGE='25V',
 VALUE='0.1UF',
 PRIM_FILE='W:/<user>/logical/q_cap/chips/chips.prt';

PART_NAME
 C310 'Q_CAP_C0402-1UF,25V,10%,X6S,CHA':;

SECTION_NUMBER 1
 '@SCM_LIB.SCM(SCH_1):PAGE54_I130@PURE_QUANTA.Q_CAP(CHIPS)':
 C_PATH='@scm_lib.scm(sch_1):page54_i130@pure_quanta.q_cap(chips)',
 P_PATH='@scm_lib.scm(sch_1):page54_i130@pure_quanta.q_cap(chips)',
 PATH='I130',
 DRAWING='@SCM_LIB.SCM(SCH_1):PAGE54',
 PHYS_PAGE='54',
 XY='(-375,-825)',
 ROT='0',
 VER='1',
 PACK_TYPE='C0402',
 CDS_LIB='pure_quanta',
 CDS_PART_NAME='Q_CAP_C0402-1UF,25V,10%,X6S,CHA',
 TOLERANCE='10%',
 MATERIAL='X6S',
 VOLTAGE='25V',
 VALUE='1UF',
 PRIM_FILE='W:/<user>/logical/q_cap/chips/chips.prt';

PART_NAME
 C311 'Q_CAP_0402-0.1UF,25V,10%,X7R,CA':;

SECTION_NUMBER 1
 '@SCM_LIB.SCM(SCH_1):PAGE15_I256@PURE_QUANTA.Q_CAP(CHIPS)':
 C_PATH='@scm_lib.scm(sch_1):page15_i256@pure_quanta.q_cap(chips)',
 P_PATH='@scm_lib.scm(sch_1):page15_i256@pure_quanta.q_cap(chips)',
 PATH='I256',
 DRAWING='@SCM_LIB.SCM(SCH_1):PAGE15',
 PHYS_PAGE='15',
 XY='(-1625,-75)',
 ROT='0',
 VER='1',
 PACK_TYPE='0402',
 LOCATION='C311',
 CDS_LIB='pure_quanta',
 CDS_PART_NAME='Q_CAP_0402-0.1UF,25V,10%,X7R,CA',
 TOLERANCE='10%',
 MATERIAL='X7R',
 VOLTAGE='25V',
 VALUE='0.1UF',
 PRIM_FILE='W:/<user>/logical/q_cap/chips/chips.prt';

PART_NAME
 C312 'Q_CAP_0402-0.1UF,25V,10%,X7R,CA':;

SECTION_NUMBER 1
 '@SCM_LIB.SCM(SCH_1):PAGE25_I146@PURE_QUANTA.Q_CAP(CHIPS)':
 C_PATH='@scm_lib.scm(sch_1):page25_i146@pure_quanta.q_cap(chips)',
 P_PATH='@scm_lib.scm(sch_1):page25_i146@pure_quanta.q_cap(chips)',
 PATH='I146',
 DRAWING='@SCM_LIB.SCM(SCH_1):PAGE25',
 PHYS_PAGE='25',
 XY='(2375,4000)',
 ROT='0',
 VER='1',
 PACK_TYPE='0402',
 CDS_LIB='pure_quanta',
 CDS_PART_NAME='Q_CAP_0402-0.1UF,25V,10%,X7R,CA',
 TOLERANCE='10%',
 MATERIAL='X7R',
 VOLTAGE='25V',
 VALUE='0.1UF',
 PRIM_FILE='W:/<user>/logical/q_cap/chips/chips.prt';

PART_NAME
 C313 'Q_CAP_0402-0.1UF,25V,10%,X7R,CA':;

SECTION_NUMBER 1
 '@SCM_LIB.SCM(SCH_1):PAGE25_I154@PURE_QUANTA.Q_CAP(CHIPS)':
 C_PATH='@scm_lib.scm(sch_1):page25_i154@pure_quanta.q_cap(chips)',
 P_PATH='@scm_lib.scm(sch_1):page25_i154@pure_quanta.q_cap(chips)',
 PATH='I154',
 DRAWING='@SCM_LIB.SCM(SCH_1):PAGE25',
 PHYS_PAGE='25',
 XY='(3675,3000)',
 ROT='0',
 VER='1',
 PACK_TYPE='0402',
 CDS_LIB='pure_quanta',
 CDS_PART_NAME='Q_CAP_0402-0.1UF,25V,10%,X7R,CA',
 TOLERANCE='10%',
 MATERIAL='X7R',
 VOLTAGE='25V',
 VALUE='0.1UF',
 PRIM_FILE='W:/<user>/logical/q_cap/chips/chips.prt';

PART_NAME
 C314 'Q_CAP_0402-0.1UF,25V,10%,X7R,CA':;

SECTION_NUMBER 1
 '@SCM_LIB.SCM(SCH_1):PAGE15_I259@PURE_QUANTA.Q_CAP(CHIPS)':
 C_PATH='@scm_lib.scm(sch_1):page15_i259@pure_quanta.q_cap(chips)',
 P_PATH='@scm_lib.scm(sch_1):page15_i259@pure_quanta.q_cap(chips)',
 PATH='I259',
 DRAWING='@SCM_LIB.SCM(SCH_1):PAGE15',
 PHYS_PAGE='15',
 XY='(-1300,-1550)',
 ROT='0',
 VER='1',
 PACK_TYPE='0402',
 LOCATION='C314',
 CDS_LIB='pure_quanta',
 CDS_PART_NAME='Q_CAP_0402-0.1UF,25V,10%,X7R,CA',
 TOLERANCE='10%',
 MATERIAL='X7R',
 VOLTAGE='25V',
 VALUE='0.1UF',
 PRIM_FILE='W:/<user>/logical/q_cap/chips/chips.prt';

PART_NAME
 C318 'Q_CAP_0402-0.1UF,25V,10%,X7R,CA':;

SECTION_NUMBER 1
 '@SCM_LIB.SCM(SCH_1):PAGE34_I122@PURE_QUANTA.Q_CAP(CHIPS)':
 C_PATH='@scm_lib.scm(sch_1):page34_i122@pure_quanta.q_cap(chips)',
 P_PATH='@scm_lib.scm(sch_1):page34_i122@pure_quanta.q_cap(chips)',
 PATH='I122',
 DRAWING='@SCM_LIB.SCM(SCH_1):PAGE34',
 PHYS_PAGE='34',
 XY='(-3975,1125)',
 ROT='0',
 VER='1',
 PACK_TYPE='0402',
 LOCATION='C318',
 CDS_LIB='pure_quanta',
 CDS_PART_NAME='Q_CAP_0402-0.1UF,25V,10%,X7R,CA',
 TOLERANCE='10%',
 MATERIAL='X7R',
 VOLTAGE='25V',
 VALUE='0.1UF',
 PRIM_FILE='W:/<user>/logical/q_cap/chips/chips.prt';

PART_NAME
 C321 'Q_CAP_0402-0.1UF,25V,10%,X7R,CA':;

SECTION_NUMBER 1
 '@SCM_LIB.SCM(SCH_1):PAGE49_I43@PURE_QUANTA.Q_CAP(CHIPS)':
 C_PATH='@scm_lib.scm(sch_1):page49_i43@pure_quanta.q_cap(chips)',
 P_PATH='@scm_lib.scm(sch_1):page49_i43@pure_quanta.q_cap(chips)',
 PATH='I43',
 DRAWING='@SCM_LIB.SCM(SCH_1):PAGE49',
 PHYS_PAGE='49',
 XY='(-5200,2150)',
 ROT='0',
 VER='1',
 PACK_TYPE='0402',
 LOCATION='C321',
 CDS_LIB='pure_quanta',
 CDS_PART_NAME='Q_CAP_0402-0.1UF,25V,10%,X7R,CA',
 TOLERANCE='10%',
 MATERIAL='X7R',
 VOLTAGE='25V',
 VALUE='0.1UF',
 PRIM_FILE='W:/<user>/logical/q_cap/chips/chips.prt';

PART_NAME
 C324 'Q_CAP_0402-470PF,50V,10%,X7R,TA':;

SECTION_NUMBER 1
 '@SCM_LIB.SCM(SCH_1):PAGE49_I37@PURE_QUANTA.Q_CAP(CHIPS)':
 C_PATH='@scm_lib.scm(sch_1):page49_i37@pure_quanta.q_cap(chips)',
 P_PATH='@scm_lib.scm(sch_1):page49_i37@pure_quanta.q_cap(chips)',
 PATH='I37',
 DRAWING='@SCM_LIB.SCM(SCH_1):PAGE49',
 PHYS_PAGE='49',
 XY='(-6925,2150)',
 ROT='0',
 VER='1',
 PACK_TYPE='0402',
 LOCATION='C324',
 CDS_LIB='pure_quanta',
 CDS_PART_NAME='Q_CAP_0402-470PF,50V,10%,X7R,TA',
 TOLERANCE='10%',
 MATERIAL='X7R',
 VOLTAGE='50V',
 VALUE='470PF',
 PRIM_FILE='W:/<user>/logical/q_cap/chips/chips.prt';

PART_NAME
 C326 'Q_CAP_0402-470PF,50V,10%,X7R,TA':;

SECTION_NUMBER 1
 '@SCM_LIB.SCM(SCH_1):PAGE49_I38@PURE_QUANTA.Q_CAP(CHIPS)':
 C_PATH='@scm_lib.scm(sch_1):page49_i38@pure_quanta.q_cap(chips)',
 P_PATH='@scm_lib.scm(sch_1):page49_i38@pure_quanta.q_cap(chips)',
 PATH='I38',
 DRAWING='@SCM_LIB.SCM(SCH_1):PAGE49',
 PHYS_PAGE='49',
 XY='(-6650,2150)',
 ROT='0',
 VER='1',
 PACK_TYPE='0402',
 LOCATION='C326',
 CDS_LIB='pure_quanta',
 CDS_PART_NAME='Q_CAP_0402-470PF,50V,10%,X7R,TA',
 TOLERANCE='10%',
 MATERIAL='X7R',
 VOLTAGE='50V',
 VALUE='470PF',
 PRIM_FILE='W:/<user>/logical/q_cap/chips/chips.prt';

PART_NAME
 C327 'Q_CAP_C1206-47UF,6.3V,20%,X6S,A':;

SECTION_NUMBER 1
 '@SCM_LIB.SCM(SCH_1):PAGE29_I220@PURE_QUANTA.Q_CAP(CHIPS)':
 C_PATH='@scm_lib.scm(sch_1):page29_i220@pure_quanta.q_cap(chips)',
 P_PATH='@scm_lib.scm(sch_1):page29_i220@pure_quanta.q_cap(chips)',
 PATH='I220',
 DRAWING='@SCM_LIB.SCM(SCH_1):PAGE29',
 PHYS_PAGE='29',
 XY='(1150,1450)',
 ROT='0',
 VER='1',
 PACK_TYPE='C1206',
 LOCATION='C327',
 CDS_LIB='pure_quanta',
 CDS_PART_NAME='Q_CAP_C1206-47UF,6.3V,20%,X6S,A',
 TOLERANCE='20%',
 MATERIAL='X6S',
 VOLTAGE='6.3V',
 VALUE='47UF',
 PRIM_FILE='W:/<user>/logical/q_cap/chips/chips.prt';

PART_NAME
 C329 'Q_CAP_C0805-22UF,16V,20%,X6S,CA':;

SECTION_NUMBER 1
 '@SCM_LIB.SCM(SCH_1):PAGE10_I573@PURE_QUANTA.Q_CAP(CHIPS)':
 C_PATH='@scm_lib.scm(sch_1):page10_i573@pure_quanta.q_cap(chips)',
 P_PATH='@scm_lib.scm(sch_1):page10_i573@pure_quanta.q_cap(chips)',
 PATH='I573',
 DRAWING='@SCM_LIB.SCM(SCH_1):PAGE10',
 PHYS_PAGE='10',
 XY='(-10225,3375)',
 ROT='0',
 VER='1',
 PACK_TYPE='C0805',
 LOCATION='C329',
 CDS_LIB='pure_quanta',
 CDS_PART_NAME='Q_CAP_C0805-22UF,16V,20%,X6S,CA',
 TOLERANCE='20%',
 MATERIAL='X6S',
 VOLTAGE='16V',
 VALUE='22UF',
 PRIM_FILE='W:/<user>/logical/q_cap/chips/chips.prt';

PART_NAME
 C330 'Q_CAP_C0805-22UF,16V,20%,X6S,CA':;

SECTION_NUMBER 1
 '@SCM_LIB.SCM(SCH_1):PAGE10_I574@PURE_QUANTA.Q_CAP(CHIPS)':
 C_PATH='@scm_lib.scm(sch_1):page10_i574@pure_quanta.q_cap(chips)',
 P_PATH='@scm_lib.scm(sch_1):page10_i574@pure_quanta.q_cap(chips)',
 PATH='I574',
 DRAWING='@SCM_LIB.SCM(SCH_1):PAGE10',
 PHYS_PAGE='10',
 XY='(-9800,3375)',
 ROT='0',
 VER='1',
 PACK_TYPE='C0805',
 LOCATION='C330',
 CDS_LIB='pure_quanta',
 CDS_PART_NAME='Q_CAP_C0805-22UF,16V,20%,X6S,CA',
 TOLERANCE='20%',
 MATERIAL='X6S',
 VOLTAGE='16V',
 VALUE='22UF',
 PRIM_FILE='W:/<user>/logical/q_cap/chips/chips.prt';

PART_NAME
 C335 'Q_CAP_C0402-1UF,25V,10%,X6S,CHA':;

SECTION_NUMBER 1
 '@SCM_LIB.SCM(SCH_1):PAGE50_I285@PURE_QUANTA.Q_CAP(CHIPS)':
 C_PATH='@scm_lib.scm(sch_1):page50_i285@pure_quanta.q_cap(chips)',
 P_PATH='@scm_lib.scm(sch_1):page50_i285@pure_quanta.q_cap(chips)',
 PATH='I285',
 DRAWING='@SCM_LIB.SCM(SCH_1):PAGE50',
 PHYS_PAGE='50',
 XY='(3050,775)',
 ROT='0',
 VER='1',
 PACK_TYPE='C0402',
 CDS_LIB='pure_quanta',
 CDS_PART_NAME='Q_CAP_C0402-1UF,25V,10%,X6S,CHA',
 TOLERANCE='10%',
 MATERIAL='X6S',
 VOLTAGE='25V',
 VALUE='1UF',
 PRIM_FILE='W:/<user>/logical/q_cap/chips/chips.prt';

PART_NAME
 C336 'Q_CAP_0402-0.1UF,25V,10%,X7R,CA':;

SECTION_NUMBER 1
 '@SCM_LIB.SCM(SCH_1):PAGE50_I281@PURE_QUANTA.Q_CAP(CHIPS)':
 C_PATH='@scm_lib.scm(sch_1):page50_i281@pure_quanta.q_cap(chips)',
 P_PATH='@scm_lib.scm(sch_1):page50_i281@pure_quanta.q_cap(chips)',
 PATH='I281',
 DRAWING='@SCM_LIB.SCM(SCH_1):PAGE50',
 PHYS_PAGE='50',
 XY='(3750,1450)',
 ROT='2',
 VER='1',
 PACK_TYPE='0402',
 CDS_LIB='pure_quanta',
 CDS_PART_NAME='Q_CAP_0402-0.1UF,25V,10%,X7R,CA',
 TOLERANCE='10%',
 MATERIAL='X7R',
 VOLTAGE='25V',
 VALUE='0.1UF',
 PRIM_FILE='W:/<user>/logical/q_cap/chips/chips.prt';

PART_NAME
 C337 'Q_CAP_0402-0.1UF,25V,10%,X7R,CA':;

SECTION_NUMBER 1
 '@SCM_LIB.SCM(SCH_1):PAGE22_I97@PURE_QUANTA.Q_CAP(CHIPS)':
 C_PATH='@scm_lib.scm(sch_1):page22_i97@pure_quanta.q_cap(chips)',
 P_PATH='@scm_lib.scm(sch_1):page22_i97@pure_quanta.q_cap(chips)',
 PATH='I97',
 DRAWING='@SCM_LIB.SCM(SCH_1):PAGE22',
 PHYS_PAGE='22',
 XY='(-2050,3125)',
 ROT='2',
 VER='1',
 PACK_TYPE='0402',
 CDS_LIB='pure_quanta',
 CDS_PART_NAME='Q_CAP_0402-0.1UF,25V,10%,X7R,CA',
 TOLERANCE='10%',
 MATERIAL='X7R',
 VOLTAGE='25V',
 VALUE='0.1UF',
 PRIM_FILE='W:/<user>/logical/q_cap/chips/chips.prt';

PART_NAME
 C500 'Q_CAP_0402-0.1UF,25V,10%,X7R,CA':;

SECTION_NUMBER 1
 '@SCM_LIB.SCM(SCH_1):PAGE31_I17@PURE_QUANTA.Q_CAP(CHIPS)':
 C_PATH='@scm_lib.scm(sch_1):page31_i17@pure_quanta.q_cap(chips)',
 P_PATH='@scm_lib.scm(sch_1):page31_i17@pure_quanta.q_cap(chips)',
 PATH='I17',
 DRAWING='@SCM_LIB.SCM(SCH_1):PAGE31',
 PHYS_PAGE='31',
 XY='(-4125,6025)',
 ROT='2',
 VER='1',
 PACK_TYPE='0402',
 LOCATION='C500',
 CDS_LIB='pure_quanta',
 CDS_PART_NAME='Q_CAP_0402-0.1UF,25V,10%,X7R,CA',
 TOLERANCE='10%',
 MATERIAL='X7R',
 VOLTAGE='25V',
 VALUE='0.1UF',
 PRIM_FILE='W:/<user>/logical/q_cap/chips/chips.prt';

PART_NAME
 C501 'Q_CAP_0402-0.1UF,25V,10%,X7R,CA':;

SECTION_NUMBER 1
 '@SCM_LIB.SCM(SCH_1):PAGE31_I11@PURE_QUANTA.Q_CAP(CHIPS)':
 C_PATH='@scm_lib.scm(sch_1):page31_i11@pure_quanta.q_cap(chips)',
 P_PATH='@scm_lib.scm(sch_1):page31_i11@pure_quanta.q_cap(chips)',
 PATH='I11',
 DRAWING='@SCM_LIB.SCM(SCH_1):PAGE31',
 PHYS_PAGE='31',
 XY='(-4150,4825)',
 ROT='2',
 VER='1',
 PACK_TYPE='0402',
 LOCATION='C501',
 CDS_LIB='pure_quanta',
 CDS_PART_NAME='Q_CAP_0402-0.1UF,25V,10%,X7R,CA',
 TOLERANCE='10%',
 MATERIAL='X7R',
 VOLTAGE='25V',
 VALUE='0.1UF',
 PRIM_FILE='W:/<user>/logical/q_cap/chips/chips.prt';

PART_NAME
 D0 'Q_LED_SMLF-LED_GREEN,19-213/GVA':;

SECTION_NUMBER 1
 '@SCM_LIB.SCM(SCH_1):PAGE47_I7@PURE_QUANTA.Q_LED(CHIPS)':
 C_PATH='@scm_lib.scm(sch_1):page47_i7@pure_quanta.q_led(chips)',
 P_PATH='@scm_lib.scm(sch_1):page47_i7@pure_quanta.q_led(chips)',
 PATH='I7',
 DRAWING='@SCM_LIB.SCM(SCH_1):PAGE47',
 PHYS_PAGE='47',
 XY='(3875,1400)',
 ROT='0',
 VER='1',
 PACK_TYPE='SMLF',
 LOCATION='D0',
 CDS_LIB='pure_quanta',
 CDS_PART_NAME='Q_LED_SMLF-LED_GREEN,19-213/GVA',
 MATERIAL='IC',
 MANUF_PN='19-213/GVC-AMNB/3T',
 COLOR='LED_GREEN',
 PRIM_FILE='W:/<user>/logical/q_led/chips/chips.prt';

PART_NAME
 D1 'Q_LED_SMLF-LED_GREEN,19-213/GVA':;

SECTION_NUMBER 1
 '@SCM_LIB.SCM(SCH_1):PAGE47_I9@PURE_QUANTA.Q_LED(CHIPS)':
 C_PATH='@scm_lib.scm(sch_1):page47_i9@pure_quanta.q_led(chips)',
 P_PATH='@scm_lib.scm(sch_1):page47_i9@pure_quanta.q_led(chips)',
 PATH='I9',
 DRAWING='@SCM_LIB.SCM(SCH_1):PAGE47',
 PHYS_PAGE='47',
 XY='(3875,1700)',
 ROT='0',
 VER='1',
 PACK_TYPE='SMLF',
 LOCATION='D1',
 CDS_LIB='pure_quanta',
 CDS_PART_NAME='Q_LED_SMLF-LED_GREEN,19-213/GVA',
 MATERIAL='IC',
 MANUF_PN='19-213/GVC-AMNB/3T',
 COLOR='LED_GREEN',
 PRIM_FILE='W:/<user>/logical/q_led/chips/chips.prt';

PART_NAME
 D2 'Q_LED_SMLF-LED_GREEN,19-213/GVA':;

SECTION_NUMBER 1
 '@SCM_LIB.SCM(SCH_1):PAGE47_I11@PURE_QUANTA.Q_LED(CHIPS)':
 C_PATH='@scm_lib.scm(sch_1):page47_i11@pure_quanta.q_led(chips)',
 P_PATH='@scm_lib.scm(sch_1):page47_i11@pure_quanta.q_led(chips)',
 PATH='I11',
 DRAWING='@SCM_LIB.SCM(SCH_1):PAGE47',
 PHYS_PAGE='47',
 XY='(3875,2000)',
 ROT='0',
 VER='1',
 PACK_TYPE='SMLF',
 LOCATION='D2',
 CDS_LIB='pure_quanta',
 CDS_PART_NAME='Q_LED_SMLF-LED_GREEN,19-213/GVA',
 MATERIAL='IC',
 MANUF_PN='19-213/GVC-AMNB/3T',
 COLOR='LED_GREEN',
 PRIM_FILE='W:/<user>/logical/q_led/chips/chips.prt';

PART_NAME
 D3 'Q_LED_SMLF-LED_GREEN,19-213/GVA':;

SECTION_NUMBER 1
 '@SCM_LIB.SCM(SCH_1):PAGE47_I13@PURE_QUANTA.Q_LED(CHIPS)':
 C_PATH='@scm_lib.scm(sch_1):page47_i13@pure_quanta.q_led(chips)',
 P_PATH='@scm_lib.scm(sch_1):page47_i13@pure_quanta.q_led(chips)',
 PATH='I13',
 DRAWING='@SCM_LIB.SCM(SCH_1):PAGE47',
 PHYS_PAGE='47',
 XY='(3875,2300)',
 ROT='0',
 VER='1',
 PACK_TYPE='SMLF',
 LOCATION='D3',
 CDS_LIB='pure_quanta',
 CDS_PART_NAME='Q_LED_SMLF-LED_GREEN,19-213/GVA',
 MATERIAL='IC',
 MANUF_PN='19-213/GVC-AMNB/3T',
 COLOR='LED_GREEN',
 PRIM_FILE='W:/<user>/logical/q_led/chips/chips.prt';

PART_NAME
 D4 'Q_LED_SMLF-LED_RED,19-217/R6C-A':;

SECTION_NUMBER 1
 '@SCM_LIB.SCM(SCH_1):PAGE47_I10@PURE_QUANTA.Q_LED(CHIPS)':
 C_PATH='@scm_lib.scm(sch_1):page47_i10@pure_quanta.q_led(chips)',
 P_PATH='@scm_lib.scm(sch_1):page47_i10@pure_quanta.q_led(chips)',
 PATH='I10',
 DRAWING='@SCM_LIB.SCM(SCH_1):PAGE47',
 PHYS_PAGE='47',
 XY='(3875,2600)',
 ROT='0',
 VER='1',
 PACK_TYPE='SMLF',
 LOCATION='D4',
 CDS_LIB='pure_quanta',
 CDS_PART_NAME='Q_LED_SMLF-LED_RED,19-217/R6C-A',
 MATERIAL='IC',
 MANUF_PN='19-217/R6C-P1Q2/3T',
 COLOR='LED_RED',
 PRIM_FILE='W:/<user>/logical/q_led/chips/chips.prt';

PART_NAME
 D5 'Q_LED_SMLF-LED_RED,19-217/R6C-A':;

SECTION_NUMBER 1
 '@SCM_LIB.SCM(SCH_1):PAGE47_I12@PURE_QUANTA.Q_LED(CHIPS)':
 C_PATH='@scm_lib.scm(sch_1):page47_i12@pure_quanta.q_led(chips)',
 P_PATH='@scm_lib.scm(sch_1):page47_i12@pure_quanta.q_led(chips)',
 PATH='I12',
 DRAWING='@SCM_LIB.SCM(SCH_1):PAGE47',
 PHYS_PAGE='47',
 XY='(3875,2900)',
 ROT='0',
 VER='1',
 PACK_TYPE='SMLF',
 LOCATION='D5',
 CDS_LIB='pure_quanta',
 CDS_PART_NAME='Q_LED_SMLF-LED_RED,19-217/R6C-A',
 MATERIAL='IC',
 MANUF_PN='19-217/R6C-P1Q2/3T',
 COLOR='LED_RED',
 PRIM_FILE='W:/<user>/logical/q_led/chips/chips.prt';

PART_NAME
 D6 'Q_LED_SMLF-LED_RED,19-217/R6C-A':;

SECTION_NUMBER 1
 '@SCM_LIB.SCM(SCH_1):PAGE47_I14@PURE_QUANTA.Q_LED(CHIPS)':
 C_PATH='@scm_lib.scm(sch_1):page47_i14@pure_quanta.q_led(chips)',
 P_PATH='@scm_lib.scm(sch_1):page47_i14@pure_quanta.q_led(chips)',
 PATH='I14',
 DRAWING='@SCM_LIB.SCM(SCH_1):PAGE47',
 PHYS_PAGE='47',
 XY='(3875,3200)',
 ROT='0',
 VER='1',
 PACK_TYPE='SMLF',
 LOCATION='D6',
 CDS_LIB='pure_quanta',
 CDS_PART_NAME='Q_LED_SMLF-LED_RED,19-217/R6C-A',
 MATERIAL='IC',
 MANUF_PN='19-217/R6C-P1Q2/3T',
 COLOR='LED_RED',
 PRIM_FILE='W:/<user>/logical/q_led/chips/chips.prt';

PART_NAME
 D7 'Q_LED_SMLF-LED_RED,19-217/R6C-A':;

SECTION_NUMBER 1
 '@SCM_LIB.SCM(SCH_1):PAGE47_I5@PURE_QUANTA.Q_LED(CHIPS)':
 C_PATH='@scm_lib.scm(sch_1):page47_i5@pure_quanta.q_led(chips)',
 P_PATH='@scm_lib.scm(sch_1):page47_i5@pure_quanta.q_led(chips)',
 PATH='I5',
 DRAWING='@SCM_LIB.SCM(SCH_1):PAGE47',
 PHYS_PAGE='47',
 XY='(3875,3500)',
 ROT='0',
 VER='1',
 PACK_TYPE='SMLF',
 LOCATION='D7',
 CDS_LIB='pure_quanta',
 CDS_PART_NAME='Q_LED_SMLF-LED_RED,19-217/R6C-A',
 MATERIAL='IC',
 MANUF_PN='19-217/R6C-P1Q2/3T',
 COLOR='LED_RED',
 PRIM_FILE='W:/<user>/logical/q_led/chips/chips.prt';

PART_NAME
 D8 'Q_LED_SMLF-LED_GREEN,19-213/GVA':;

SECTION_NUMBER 1
 '@SCM_LIB.SCM(SCH_1):PAGE13_I46@PURE_QUANTA.Q_LED(CHIPS)':
 C_PATH='@scm_lib.scm(sch_1):page13_i46@pure_quanta.q_led(chips)',
 P_PATH='@scm_lib.scm(sch_1):page13_i46@pure_quanta.q_led(chips)',
 PATH='I46',
 DRAWING='@SCM_LIB.SCM(SCH_1):PAGE13',
 PHYS_PAGE='13',
 XY='(825,-525)',
 ROT='0',
 VER='1',
 PACK_TYPE='SMLF',
 LOCATION='D8',
 CDS_LIB='pure_quanta',
 CDS_PART_NAME='Q_LED_SMLF-LED_GREEN,19-213/GVA',
 MATERIAL='IC',
 MANUF_PN='19-213/GVC-AMNB/3T',
 COLOR='LED_GREEN',
 PRIM_FILE='W:/<user>/logical/q_led/chips/chips.prt';

PART_NAME
 D9 'SCHOTTKY_AC-SS0530,SMLF,EMPTY,A':;

SECTION_NUMBER 1
 '@SCM_LIB.SCM(SCH_1):PAGE23_I42@PURE_QUANTA.SCHOTTKY_AC(CHIPS)':
 C_PATH='@scm_lib.scm(sch_1):page23_i42@pure_quanta.schottky_ac(chips)',
 P_PATH='@scm_lib.scm(sch_1):page23_i42@pure_quanta.schottky_ac(chips)',
 PATH='I42',
 DRAWING='@SCM_LIB.SCM(SCH_1):PAGE23',
 PART_TYPE='SMLF',
 PHYS_PAGE='23',
 XY='(-1900,4675)',
 ROT='0',
 VER='1',
 LOCATION='D9',
 CDS_LIB='pure_quanta',
 CDS_PART_NAME='SCHOTTKY_AC-SS0530,SMLF,EMPTY,A',
 MATERIAL='EMPTY',
 VALUE='SS0530',
 PRIM_FILE='W:/<user>/logical/schottky_ac/chips/chips.prt';

PART_NAME
 D10 'DIODE_BIDIRECTIONAL-UCLAMP0511A':;

SECTION_NUMBER 1
 '@SCM_LIB.SCM(SCH_1):PAGE50_I244@PURE_QUANTA.DIODE_BIDIRECTIONAL(CHIPS)':
 C_PATH='@scm_lib.scm(sch_1):page50_i244@pure_quanta.diode_bidirectional(chips)',
 P_PATH='@scm_lib.scm(sch_1):page50_i244@pure_quanta.diode_bidirectional(chips)',
 PATH='I244',
 DRAWING='@SCM_LIB.SCM(SCH_1):PAGE50',
 PART_TYPE='SMLF',
 PHYS_PAGE='50',
 XY='(4100,2225)',
 ROT='0',
 VER='1',
 CDS_LIB='pure_quanta',
 CDS_PART_NAME='DIODE_BIDIRECTIONAL-UCLAMP0511A',
 MATERIAL='IC',
 VALUE='UCLAMP0511T',
 PRIM_FILE='W:/<user>/logical/diode_bidirectional/chips/chips.prt';

PART_NAME
 D11 'SCHOTTKY_AC-SS0530,SMLF,IC,BCSA':;

SECTION_NUMBER 1
 '@SCM_LIB.SCM(SCH_1):PAGE23_I41@PURE_QUANTA.SCHOTTKY_AC(CHIPS)':
 C_PATH='@scm_lib.scm(sch_1):page23_i41@pure_quanta.schottky_ac(chips)',
 P_PATH='@scm_lib.scm(sch_1):page23_i41@pure_quanta.schottky_ac(chips)',
 PATH='I41',
 DRAWING='@SCM_LIB.SCM(SCH_1):PAGE23',
 PART_TYPE='SMLF',
 PHYS_PAGE='23',
 XY='(-1850,4275)',
 ROT='0',
 VER='1',
 LOCATION='D11',
 CDS_LIB='pure_quanta',
 CDS_PART_NAME='SCHOTTKY_AC-SS0530,SMLF,IC,BCSA',
 MATERIAL='IC',
 VALUE='SS0530',
 PRIM_FILE='W:/<user>/logical/schottky_ac/chips/chips.prt';

PART_NAME
 D12 'BZA462A-BZA462A,SMLF,EMPTY,BCZA':;

SECTION_NUMBER 1
 '@SCM_LIB.SCM(SCH_1):PAGE23_I74@PURE_QUANTA.BZA462A(CHIPS)':
 C_PATH='@scm_lib.scm(sch_1):page23_i74@pure_quanta.bza462a(chips)',
 P_PATH='@scm_lib.scm(sch_1):page23_i74@pure_quanta.bza462a(chips)',
 PATH='I74',
 DRAWING='@SCM_LIB.SCM(SCH_1):PAGE23',
 PART_TYPE='SMLF',
 PHYS_PAGE='23',
 XY='(6200,4200)',
 ROT='3',
 VER='1',
 LOCATION='D12',
 CDS_LIB='pure_quanta',
 CDS_PART_NAME='BZA462A-BZA462A,SMLF,EMPTY,BCZA',
 MATERIAL='EMPTY',
 VALUE='BZA462A',
 PRIM_FILE='W:/<user>/logical/bza462a/chips/chips.prt';

PART_NAME
 D13 'Q_LED_THLF-LED_YELLOW,LTL-R42FA':;

SECTION_NUMBER 1
 '@SCM_LIB.SCM(SCH_1):PAGE49_I97@PURE_QUANTA.Q_LED(CHIPS)':
 C_PATH='@scm_lib.scm(sch_1):page49_i97@pure_quanta.q_led(chips)',
 P_PATH='@scm_lib.scm(sch_1):page49_i97@pure_quanta.q_led(chips)',
 PATH='I97',
 DRAWING='@SCM_LIB.SCM(SCH_1):PAGE49',
 PHYS_PAGE='49',
 XY='(-4175,5250)',
 ROT='2',
 VER='1',
 PACK_TYPE='THLF',
 LOCATION='D13',
 CDS_LIB='pure_quanta',
 CDS_PART_NAME='Q_LED_THLF-LED_YELLOW,LTL-R42FA',
 MATERIAL='IC',
 MANUF_PN='LTL-R42FSFADH213T',
 COLOR='LED_YELLOW',
 PRIM_FILE='W:/<user>/logical/q_led/chips/chips.prt';

PART_NAME
 D14 'Q_LED_THLF-LED_BLUE,HV-312470/A':;

SECTION_NUMBER 1
 '@SCM_LIB.SCM(SCH_1):PAGE49_I94@PURE_QUANTA.Q_LED(CHIPS)':
 C_PATH='@scm_lib.scm(sch_1):page49_i94@pure_quanta.q_led(chips)',
 P_PATH='@scm_lib.scm(sch_1):page49_i94@pure_quanta.q_led(chips)',
 PATH='I94',
 DRAWING='@SCM_LIB.SCM(SCH_1):PAGE49',
 PHYS_PAGE='49',
 XY='(-6125,2900)',
 ROT='2',
 VER='1',
 PACK_TYPE='THLF',
 LOCATION='D14',
 CDS_LIB='pure_quanta',
 CDS_PART_NAME='Q_LED_THLF-LED_BLUE,HV-312470/A',
 MATERIAL='IC',
 MANUF_PN='HV-312470/260/SUBD-TR1',
 COLOR='LED_BLUE',
 PRIM_FILE='W:/<user>/logical/q_led/chips/chips.prt';

PART_NAME
 D15 'Q_LED_THLF-LED_BLUE,HV-312470/A':;

SECTION_NUMBER 1
 '@SCM_LIB.SCM(SCH_1):PAGE49_I95@PURE_QUANTA.Q_LED(CHIPS)':
 C_PATH='@scm_lib.scm(sch_1):page49_i95@pure_quanta.q_led(chips)',
 P_PATH='@scm_lib.scm(sch_1):page49_i95@pure_quanta.q_led(chips)',
 PATH='I95',
 DRAWING='@SCM_LIB.SCM(SCH_1):PAGE49',
 PHYS_PAGE='49',
 XY='(-6150,2450)',
 ROT='2',
 VER='1',
 PACK_TYPE='THLF',
 LOCATION='D15',
 CDS_LIB='pure_quanta',
 CDS_PART_NAME='Q_LED_THLF-LED_BLUE,HV-312470/A',
 MATERIAL='IC',
 MANUF_PN='HV-312470/260/SUBD-TR1',
 COLOR='LED_BLUE',
 PRIM_FILE='W:/<user>/logical/q_led/chips/chips.prt';

PART_NAME
 D16 'SCHOTTKY_12-SBA130Q,SMLF,EMPTYA':;

SECTION_NUMBER 1
 '@SCM_LIB.SCM(SCH_1):PAGE23_I161@PURE_QUANTA.SCHOTTKY_12(CHIPS)':
 C_PATH='@scm_lib.scm(sch_1):page23_i161@pure_quanta.schottky_12(chips)',
 P_PATH='@scm_lib.scm(sch_1):page23_i161@pure_quanta.schottky_12(chips)',
 PATH='I161',
 DRAWING='@SCM_LIB.SCM(SCH_1):PAGE23',
 PART_TYPE='SMLF',
 PHYS_PAGE='23',
 XY='(3425,-775)',
 ROT='0',
 VER='1',
 LOCATION='D16',
 CDS_LIB='pure_quanta',
 CDS_PART_NAME='SCHOTTKY_12-SBA130Q,SMLF,EMPTYA',
 MATERIAL='EMPTY',
 VALUE='SBA130Q',
 PRIM_FILE='W:/<user>/logical/schottky_12/chips/chips.prt';

PART_NAME
 D17 'Q_DIODE_SMLF-SDMK0340L-7-F,IC,A':;

SECTION_NUMBER 1
 '@SCM_LIB.SCM(SCH_1):PAGE22_I28@PURE_QUANTA.Q_DIODE(CHIPS)':
 C_PATH='@scm_lib.scm(sch_1):page22_i28@pure_quanta.q_diode(chips)',
 P_PATH='@scm_lib.scm(sch_1):page22_i28@pure_quanta.q_diode(chips)',
 PATH='I28',
 DRAWING='@SCM_LIB.SCM(SCH_1):PAGE22',
 PIN_NAMES_ROTATE='True',
 PHYS_PAGE='22',
 XY='(-1400,2775)',
 ROT='0',
 VER='1',
 PACK_TYPE='SMLF',
 LOCATION='D17',
 CDS_LIB='pure_quanta',
 CDS_PART_NAME='Q_DIODE_SMLF-SDMK0340L-7-F,IC,A',
 MATERIAL='IC',
 VALUE='SDMK0340L-7-F',
 PRIM_FILE='W:/<user>/logical/q_diode/chips/chips.prt';

PART_NAME
 D18 'Q_LED_SMLF-LED_BLUE,LTST-C281TA':;

SECTION_NUMBER 1
 '@SCM_LIB.SCM(SCH_1):PAGE49_I51@PURE_QUANTA.Q_LED(CHIPS)':
 C_PATH='@scm_lib.scm(sch_1):page49_i51@pure_quanta.q_led(chips)',
 P_PATH='@scm_lib.scm(sch_1):page49_i51@pure_quanta.q_led(chips)',
 PATH='I51',
 DRAWING='@SCM_LIB.SCM(SCH_1):PAGE49',
 PHYS_PAGE='49',
 XY='(-1075,2925)',
 ROT='2',
 VER='1',
 PACK_TYPE='SMLF',
 CDS_LIB='pure_quanta',
 CDS_PART_NAME='Q_LED_SMLF-LED_BLUE,LTST-C281TA',
 MATERIAL='IC',
 MANUF_PN='LTST-C281TBKT-5A',
 COLOR='LED_BLUE',
 PRIM_FILE='W:/<user>/logical/q_led/chips/chips.prt';

PART_NAME
 D19 'Q_LED_SMLF-LED_BLUE,LTST-C281TA':;

SECTION_NUMBER 1
 '@SCM_LIB.SCM(SCH_1):PAGE49_I50@PURE_QUANTA.Q_LED(CHIPS)':
 C_PATH='@scm_lib.scm(sch_1):page49_i50@pure_quanta.q_led(chips)',
 P_PATH='@scm_lib.scm(sch_1):page49_i50@pure_quanta.q_led(chips)',
 PATH='I50',
 DRAWING='@SCM_LIB.SCM(SCH_1):PAGE49',
 PHYS_PAGE='49',
 XY='(-1075,2450)',
 ROT='2',
 VER='1',
 PACK_TYPE='SMLF',
 CDS_LIB='pure_quanta',
 CDS_PART_NAME='Q_LED_SMLF-LED_BLUE,LTST-C281TA',
 MATERIAL='IC',
 MANUF_PN='LTST-C281TBKT-5A',
 COLOR='LED_BLUE',
 PRIM_FILE='W:/<user>/logical/q_led/chips/chips.prt';

PART_NAME
 D20 'SCHOTTKY_12-1N5819HW,SMLF,IC,BA':;

SECTION_NUMBER 1
 '@SCM_LIB.SCM(SCH_1):PAGE32_I144@PURE_QUANTA.SCHOTTKY_12(CHIPS)':
 C_PATH='@scm_lib.scm(sch_1):page32_i144@pure_quanta.schottky_12(chips)',
 P_PATH='@scm_lib.scm(sch_1):page32_i144@pure_quanta.schottky_12(chips)',
 PATH='I144',
 DRAWING='@SCM_LIB.SCM(SCH_1):PAGE32',
 PART_TYPE='SMLF',
 PHYS_PAGE='32',
 XY='(3850,4325)',
 ROT='2',
 VER='1',
 CDS_LIB='pure_quanta',
 CDS_PART_NAME='SCHOTTKY_12-1N5819HW,SMLF,IC,BA',
 MATERIAL='IC',
 VALUE='1N5819HW',
 PRIM_FILE='W:/<user>/logical/schottky_12/chips/chips.prt';

PART_NAME
 D21 'Q_LED_THLF-LED_BLUE,HV-312470/A':;

SECTION_NUMBER 1
 '@SCM_LIB.SCM(SCH_1):PAGE50_I294@PURE_QUANTA.Q_LED(CHIPS)':
 C_PATH='@scm_lib.scm(sch_1):page50_i294@pure_quanta.q_led(chips)',
 P_PATH='@scm_lib.scm(sch_1):page50_i294@pure_quanta.q_led(chips)',
 PATH='I294',
 DRAWING='@SCM_LIB.SCM(SCH_1):PAGE50',
 PHYS_PAGE='50',
 XY='(-1500,1625)',
 ROT='2',
 VER='1',
 PACK_TYPE='THLF',
 LOCATION='D21',
 CDS_LIB='pure_quanta',
 CDS_PART_NAME='Q_LED_THLF-LED_BLUE,HV-312470/A',
 MATERIAL='IC',
 MANUF_PN='HV-312470/260/SUBD-TR1',
 COLOR='LED_BLUE',
 PRIM_FILE='W:/<user>/logical/q_led/chips/chips.prt';

PART_NAME
 D22 'Q_LED_THLF-LED_BLUE,HV-312470/A':;

SECTION_NUMBER 1
 '@SCM_LIB.SCM(SCH_1):PAGE50_I295@PURE_QUANTA.Q_LED(CHIPS)':
 C_PATH='@scm_lib.scm(sch_1):page50_i295@pure_quanta.q_led(chips)',
 P_PATH='@scm_lib.scm(sch_1):page50_i295@pure_quanta.q_led(chips)',
 PATH='I295',
 DRAWING='@SCM_LIB.SCM(SCH_1):PAGE50',
 PHYS_PAGE='50',
 XY='(-550,100)',
 ROT='2',
 VER='1',
 PACK_TYPE='THLF',
 LOCATION='D22',
 CDS_LIB='pure_quanta',
 CDS_PART_NAME='Q_LED_THLF-LED_BLUE,HV-312470/A',
 MATERIAL='IC',
 MANUF_PN='HV-312470/260/SUBD-TR1',
 COLOR='LED_BLUE',
 PRIM_FILE='W:/<user>/logical/q_led/chips/chips.prt';

PART_NAME
 D23 'Q_DIODE_SMLF-SDMK0340L-7-F,EMPA':;

SECTION_NUMBER 1
 '@SCM_LIB.SCM(SCH_1):PAGE35_I150@PURE_QUANTA.Q_DIODE(CHIPS)':
 C_PATH='@scm_lib.scm(sch_1):page35_i150@pure_quanta.q_diode(chips)',
 P_PATH='@scm_lib.scm(sch_1):page35_i150@pure_quanta.q_diode(chips)',
 PATH='I150',
 DRAWING='@SCM_LIB.SCM(SCH_1):PAGE35',
 PIN_NAMES_ROTATE='True',
 PHYS_PAGE='35',
 XY='(-1825,3200)',
 ROT='2',
 VER='1',
 PACK_TYPE='SMLF',
 CDS_LIB='pure_quanta',
 CDS_PART_NAME='Q_DIODE_SMLF-SDMK0340L-7-F,EMPA',
 MATERIAL='EMPTY',
 VALUE='SDMK0340L-7-F',
 PRIM_FILE='W:/<user>/logical/q_diode/chips/chips.prt';

PART_NAME
 DB1 'TDR_3P_TH2-EMPTY,N_A':;

SECTION_NUMBER 1
 '@SCM_LIB.SCM(SCH_1):PAGE60_I1@PURE_QUANTA.TDR_3P(CHIPS)':
 C_PATH='@scm_lib.scm(sch_1):page60_i1@pure_quanta.tdr_3p(chips)',
 P_PATH='@scm_lib.scm(sch_1):page60_i1@pure_quanta.tdr_3p(chips)',
 PATH='I1',
 DRAWING='@SCM_LIB.SCM(SCH_1):PAGE60',
 SEC_TYPE='TH2',
 PHYS_PAGE='60',
 XY='(-8500,5700)',
 ROT='0',
 VER='2',
 PACK_TYPE='TH2',
 LOCATION='DB1',
 SEC='1',
 CDS_LIB='pure_quanta',
 CDS_PART_NAME='TDR_3P_TH2-EMPTY,N_A',
 MATERIAL='EMPTY',
 PRIM_FILE='W:/<user>/logical/tdr_3p/chips/chips.prt';

PART_NAME
 DB2 'TDR_3P_TH2-EMPTY,N_A':;

SECTION_NUMBER 1
 '@SCM_LIB.SCM(SCH_1):PAGE60_I11@PURE_QUANTA.TDR_3P(CHIPS)':
 C_PATH='@scm_lib.scm(sch_1):page60_i11@pure_quanta.tdr_3p(chips)',
 P_PATH='@scm_lib.scm(sch_1):page60_i11@pure_quanta.tdr_3p(chips)',
 PATH='I11',
 DRAWING='@SCM_LIB.SCM(SCH_1):PAGE60',
 SEC_TYPE='TH2',
 PHYS_PAGE='60',
 XY='(-8500,5225)',
 ROT='0',
 VER='2',
 PACK_TYPE='TH2',
 LOCATION='DB2',
 SEC='1',
 CDS_LIB='pure_quanta',
 CDS_PART_NAME='TDR_3P_TH2-EMPTY,N_A',
 MATERIAL='EMPTY',
 PRIM_FILE='W:/<user>/logical/tdr_3p/chips/chips.prt';

PART_NAME
 DB3 'TDR_3P_TH2-EMPTY,N_A':;

SECTION_NUMBER 1
 '@SCM_LIB.SCM(SCH_1):PAGE60_I9@PURE_QUANTA.TDR_3P(CHIPS)':
 C_PATH='@scm_lib.scm(sch_1):page60_i9@pure_quanta.tdr_3p(chips)',
 P_PATH='@scm_lib.scm(sch_1):page60_i9@pure_quanta.tdr_3p(chips)',
 PATH='I9',
 DRAWING='@SCM_LIB.SCM(SCH_1):PAGE60',
 SEC_TYPE='TH2',
 PHYS_PAGE='60',
 XY='(-8500,4750)',
 ROT='0',
 VER='2',
 PACK_TYPE='TH2',
 LOCATION='DB3',
 SEC='1',
 CDS_LIB='pure_quanta',
 CDS_PART_NAME='TDR_3P_TH2-EMPTY,N_A',
 MATERIAL='EMPTY',
 PRIM_FILE='W:/<user>/logical/tdr_3p/chips/chips.prt';

PART_NAME
 DB4 'TDR_3P_TH2-EMPTY,N_A':;

SECTION_NUMBER 1
 '@SCM_LIB.SCM(SCH_1):PAGE60_I7@PURE_QUANTA.TDR_3P(CHIPS)':
 C_PATH='@scm_lib.scm(sch_1):page60_i7@pure_quanta.tdr_3p(chips)',
 P_PATH='@scm_lib.scm(sch_1):page60_i7@pure_quanta.tdr_3p(chips)',
 PATH='I7',
 DRAWING='@SCM_LIB.SCM(SCH_1):PAGE60',
 SEC_TYPE='TH2',
 PHYS_PAGE='60',
 XY='(-8500,4275)',
 ROT='0',
 VER='2',
 PACK_TYPE='TH2',
 LOCATION='DB4',
 SEC='1',
 CDS_LIB='pure_quanta',
 CDS_PART_NAME='TDR_3P_TH2-EMPTY,N_A',
 MATERIAL='EMPTY',
 PRIM_FILE='W:/<user>/logical/tdr_3p/chips/chips.prt';

PART_NAME
 DB5 'TDR_3P_TH2-EMPTY,N_A':;

SECTION_NUMBER 1
 '@SCM_LIB.SCM(SCH_1):PAGE60_I5@PURE_QUANTA.TDR_3P(CHIPS)':
 C_PATH='@scm_lib.scm(sch_1):page60_i5@pure_quanta.tdr_3p(chips)',
 P_PATH='@scm_lib.scm(sch_1):page60_i5@pure_quanta.tdr_3p(chips)',
 PATH='I5',
 DRAWING='@SCM_LIB.SCM(SCH_1):PAGE60',
 SEC_TYPE='TH2',
 PHYS_PAGE='60',
 XY='(-8500,3800)',
 ROT='0',
 VER='2',
 PACK_TYPE='TH2',
 LOCATION='DB5',
 SEC='1',
 CDS_LIB='pure_quanta',
 CDS_PART_NAME='TDR_3P_TH2-EMPTY,N_A',
 MATERIAL='EMPTY',
 PRIM_FILE='W:/<user>/logical/tdr_3p/chips/chips.prt';

PART_NAME
 DB6 'TDR_3P_TH2-EMPTY,N_A':;

SECTION_NUMBER 1
 '@SCM_LIB.SCM(SCH_1):PAGE60_I3@PURE_QUANTA.TDR_3P(CHIPS)':
 C_PATH='@scm_lib.scm(sch_1):page60_i3@pure_quanta.tdr_3p(chips)',
 P_PATH='@scm_lib.scm(sch_1):page60_i3@pure_quanta.tdr_3p(chips)',
 PATH='I3',
 DRAWING='@SCM_LIB.SCM(SCH_1):PAGE60',
 SEC_TYPE='TH2',
 PHYS_PAGE='60',
 XY='(-8500,3325)',
 ROT='0',
 VER='2',
 PACK_TYPE='TH2',
 LOCATION='DB6',
 SEC='1',
 CDS_LIB='pure_quanta',
 CDS_PART_NAME='TDR_3P_TH2-EMPTY,N_A',
 MATERIAL='EMPTY',
 PRIM_FILE='W:/<user>/logical/tdr_3p/chips/chips.prt';

PART_NAME
 DM1 'DUMMY_SYMBOL-BMC_FLASH,MECH,EMA':;

SECTION_NUMBER 1
 '@SCM_LIB.SCM(SCH_1):PAGE59_I36@PURE_QUANTA.DUMMY_SYMBOL(CHIPS)':
 C_PATH='@scm_lib.scm(sch_1):page59_i36@pure_quanta.dummy_symbol(chips)',
 P_PATH='@scm_lib.scm(sch_1):page59_i36@pure_quanta.dummy_symbol(chips)',
 PATH='I36',
 DRAWING='@SCM_LIB.SCM(SCH_1):PAGE59',
 PIN_NAMES_ROTATE='True',
 PART_TYPE='MECH',
 PHYS_PAGE='59',
 XY='(-3200,3250)',
 ROT='0',
 VER='1',
 CDS_LIB='pure_quanta',
 CDS_PART_NAME='DUMMY_SYMBOL-BMC_FLASH,MECH,EMA',
 MATERIAL='EMPTY',
 VALUE='BMC_FLASH',
 PRIM_FILE='W:/<user>/logical/dummy_symbol/chips/chips.prt';

PART_NAME
 DM2 'DUMMY_SYMBOL-BMC_FLASH,MECH,EMA':;

SECTION_NUMBER 1
 '@SCM_LIB.SCM(SCH_1):PAGE59_I37@PURE_QUANTA.DUMMY_SYMBOL(CHIPS)':
 C_PATH='@scm_lib.scm(sch_1):page59_i37@pure_quanta.dummy_symbol(chips)',
 P_PATH='@scm_lib.scm(sch_1):page59_i37@pure_quanta.dummy_symbol(chips)',
 PATH='I37',
 DRAWING='@SCM_LIB.SCM(SCH_1):PAGE59',
 PIN_NAMES_ROTATE='True',
 PART_TYPE='MECH',
 PHYS_PAGE='59',
 XY='(-2675,3250)',
 ROT='0',
 VER='1',
 CDS_LIB='pure_quanta',
 CDS_PART_NAME='DUMMY_SYMBOL-BMC_FLASH,MECH,EMA',
 MATERIAL='EMPTY',
 VALUE='BMC_FLASH',
 PRIM_FILE='W:/<user>/logical/dummy_symbol/chips/chips.prt';

PART_NAME
 DM3 'DUMMY_SYMBOL-BIOS_FLASH,MECH,MA':;

SECTION_NUMBER 1
 '@SCM_LIB.SCM(SCH_1):PAGE59_I35@PURE_QUANTA.DUMMY_SYMBOL(CHIPS)':
 C_PATH='@scm_lib.scm(sch_1):page59_i35@pure_quanta.dummy_symbol(chips)',
 P_PATH='@scm_lib.scm(sch_1):page59_i35@pure_quanta.dummy_symbol(chips)',
 PATH='I35',
 DRAWING='@SCM_LIB.SCM(SCH_1):PAGE59',
 PIN_NAMES_ROTATE='True',
 PART_TYPE='MECH',
 PHYS_PAGE='59',
 XY='(-1600,3325)',
 ROT='0',
 VER='1',
 CDS_LIB='pure_quanta',
 CDS_PART_NAME='DUMMY_SYMBOL-BIOS_FLASH,MECH,MA',
 MATERIAL='MECH',
 VALUE='BIOS_FLASH',
 PRIM_FILE='W:/<user>/logical/dummy_symbol/chips/chips.prt';

PART_NAME
 DM7 'ME_DUMMY_SYMBOL-PB-E1_SMALL,MEA':;

SECTION_NUMBER -1
 '@SCM_LIB.SCM(SCH_1):PAGE59_I29@PURE_QUANTA.ME_DUMMY_SYMBOL(CHIPS)':
 C_PATH='@scm_lib.scm(sch_1):page59_i29@pure_quanta.me_dummy_symbol(chips)',
 P_PATH='@scm_lib.scm(sch_1):page59_i29@pure_quanta.me_dummy_symbol(chips)',
 PATH='I29',
 DRAWING='@SCM_LIB.SCM(SCH_1):PAGE59',
 PIN_TEXT_VISIBLE='True',
 PIN_NAMES_ROTATE='True',
 PART_TYPE='MECH',
 PHYS_PAGE='59',
 XY='(-350,4600)',
 ROT='0',
 VER='1',
 LOCATION='DM7',
 CDS_LIB='pure_quanta',
 CDS_PART_NAME='ME_DUMMY_SYMBOL-PB-E1_SMALL,MEA',
 MATERIAL='EMPTY',
 VALUE='PB-E1_SMALL',
 PRIM_FILE='W:/<user>/logical/me_dummy_symbol/chips/chips.prt';

PART_NAME
 FS1 'Q_FUSE_SMLF-1.1A/8V,EMPTY,DK11A':;

SECTION_NUMBER 1
 '@SCM_LIB.SCM(SCH_1):PAGE23_I153@PURE_QUANTA.Q_FUSE(CHIPS)':
 C_PATH='@scm_lib.scm(sch_1):page23_i153@pure_quanta.q_fuse(chips)',
 P_PATH='@scm_lib.scm(sch_1):page23_i153@pure_quanta.q_fuse(chips)',
 PATH='I153',
 DRAWING='@SCM_LIB.SCM(SCH_1):PAGE23',
 SEC_TYPE='SMLF',
 PHYS_PAGE='23',
 XY='(4400,-775)',
 ROT='0',
 VER='1',
 PACK_TYPE='SMLF',
 LOCATION='FS1',
 SEC='1',
 CDS_LIB='pure_quanta',
 CDS_PART_NAME='Q_FUSE_SMLF-1.1A/8V,EMPTY,DK11A',
 MATERIAL='EMPTY',
 VALUE='1.1A/8V',
 PRIM_FILE='W:/<user>/logical/q_fuse/chips/chips.prt';

PART_NAME
 GF1 'FCONN168_ME1016810202011_SCM-FA':;

SECTION_NUMBER 1
 '@SCM_LIB.SCM(SCH_1):PAGE10_I553@PURE_QUANTA.FCONN168_ME1016810202011_SCM(CHIPS)':
 C_PATH='@scm_lib.scm(sch_1):page10_i553@pure_quanta.fconn168_me1016810202011_sc~
m(chips)',
 P_PATH='@scm_lib.scm(sch_1):page10_i553@pure_quanta.fconn168_me1016810202011_sc~
m(chips)',
 PATH='I553',
 DRAWING='@SCM_LIB.SCM(SCH_1):PAGE10',
 PART_TYPE='SMLF',
 PHYS_PAGE='10',
 XY='(-8275,800)',
 ROT='0',
 VER='1',
 CDS_LIB='pure_quanta',
 CDS_PART_NAME='FCONN168_ME1016810202011_SCM-FA',
 MATERIAL='EMPTY',
 VALUE='FCONN168_ME1016810202011_SCM',
 PRIM_FILE='W:/<user>/logical/fconn168_me1016810202011_scm/chips/chips.prt';

PART_NAME
 H1 'HOLE_TH-EMPTY,HOLE1248':;

SECTION_NUMBER 1
 '@SCM_LIB.SCM(SCH_1):PAGE57_I49@PURE_QUANTA.HOLE(CHIPS)':
 C_PATH='@scm_lib.scm(sch_1):page57_i49@pure_quanta.hole(chips)',
 P_PATH='@scm_lib.scm(sch_1):page57_i49@pure_quanta.hole(chips)',
 PATH='I49',
 DRAWING='@SCM_LIB.SCM(SCH_1):PAGE57',
 PHYS_PAGE='57',
 XY='(500,1475)',
 ROT='0',
 VER='1',
 PACK_TYPE='TH',
 LOCATION='H1',
 CDS_LIB='pure_quanta',
 CDS_PART_NAME='HOLE_TH-EMPTY,HOLE1248',
 MATERIAL='EMPTY',
 PRIM_FILE='W:/<user>/logical/hole/chips/chips.prt';

PART_NAME
 H2 'HOLE_TH-EMPTY,HOLE1247':;

SECTION_NUMBER 1
 '@SCM_LIB.SCM(SCH_1):PAGE57_I45@PURE_QUANTA.HOLE(CHIPS)':
 C_PATH='@scm_lib.scm(sch_1):page57_i45@pure_quanta.hole(chips)',
 P_PATH='@scm_lib.scm(sch_1):page57_i45@pure_quanta.hole(chips)',
 PATH='I45',
 DRAWING='@SCM_LIB.SCM(SCH_1):PAGE57',
 PHYS_PAGE='57',
 XY='(525,650)',
 ROT='0',
 VER='1',
 PACK_TYPE='TH',
 CDS_LIB='pure_quanta',
 CDS_PART_NAME='HOLE_TH-EMPTY,HOLE1247',
 MATERIAL='EMPTY',
 PRIM_FILE='W:/<user>/logical/hole/chips/chips.prt';

PART_NAME
 H2B1 'HOLE_TH-EMPTY,DUMMY50':;

SECTION_NUMBER 1
 '@SCM_LIB.SCM(SCH_1):PAGE57_I14@PURE_QUANTA.HOLE(CHIPS)':
 C_PATH='@scm_lib.scm(sch_1):page57_i14@pure_quanta.hole(chips)',
 P_PATH='@scm_lib.scm(sch_1):page57_i14@pure_quanta.hole(chips)',
 PATH='I14',
 DRAWING='@SCM_LIB.SCM(SCH_1):PAGE57',
 PHYS_PAGE='57',
 XY='(2375,3575)',
 ROT='0',
 VER='1',
 PACK_TYPE='TH',
 LOCATION='H2B1',
 CDS_LIB='pure_quanta',
 CDS_PART_NAME='HOLE_TH-EMPTY,DUMMY50',
 MATERIAL='EMPTY',
 PRIM_FILE='W:/<user>/logical/hole/chips/chips.prt';

PART_NAME
 H2B2 'HOLE_TH-EMPTY,DUMMY50':;

SECTION_NUMBER 1
 '@SCM_LIB.SCM(SCH_1):PAGE57_I34@PURE_QUANTA.HOLE(CHIPS)':
 C_PATH='@scm_lib.scm(sch_1):page57_i34@pure_quanta.hole(chips)',
 P_PATH='@scm_lib.scm(sch_1):page57_i34@pure_quanta.hole(chips)',
 PATH='I34',
 DRAWING='@SCM_LIB.SCM(SCH_1):PAGE57',
 PHYS_PAGE='57',
 XY='(2375,3050)',
 ROT='0',
 VER='1',
 PACK_TYPE='TH',
 LOCATION='H2B2',
 CDS_LIB='pure_quanta',
 CDS_PART_NAME='HOLE_TH-EMPTY,DUMMY50',
 MATERIAL='EMPTY',
 PRIM_FILE='W:/<user>/logical/hole/chips/chips.prt';

PART_NAME
 H3 'HOLE_TH-EMPTY,HOLE620':;

SECTION_NUMBER 1
 '@SCM_LIB.SCM(SCH_1):PAGE57_I38@PURE_QUANTA.HOLE(CHIPS)':
 C_PATH='@scm_lib.scm(sch_1):page57_i38@pure_quanta.hole(chips)',
 P_PATH='@scm_lib.scm(sch_1):page57_i38@pure_quanta.hole(chips)',
 PATH='I38',
 DRAWING='@SCM_LIB.SCM(SCH_1):PAGE57',
 PHYS_PAGE='57',
 XY='(-1625,1425)',
 ROT='0',
 VER='1',
 PACK_TYPE='TH',
 CDS_LIB='pure_quanta',
 CDS_PART_NAME='HOLE_TH-EMPTY,HOLE620',
 MATERIAL='EMPTY',
 PRIM_FILE='W:/<user>/logical/hole/chips/chips.prt';

PART_NAME
 H4 'HOLE_TH-EMPTY,HOLE620':;

SECTION_NUMBER 1
 '@SCM_LIB.SCM(SCH_1):PAGE57_I40@PURE_QUANTA.HOLE(CHIPS)':
 C_PATH='@scm_lib.scm(sch_1):page57_i40@pure_quanta.hole(chips)',
 P_PATH='@scm_lib.scm(sch_1):page57_i40@pure_quanta.hole(chips)',
 PATH='I40',
 DRAWING='@SCM_LIB.SCM(SCH_1):PAGE57',
 PHYS_PAGE='57',
 XY='(-1625,550)',
 ROT='0',
 VER='1',
 PACK_TYPE='TH',
 CDS_LIB='pure_quanta',
 CDS_PART_NAME='HOLE_TH-EMPTY,HOLE620',
 MATERIAL='EMPTY',
 PRIM_FILE='W:/<user>/logical/hole/chips/chips.prt';

PART_NAME
 H5 'HOLE_TH-EMPTY,HOLE1211':;

SECTION_NUMBER 1
 '@SCM_LIB.SCM(SCH_1):PAGE57_I35@PURE_QUANTA.HOLE(CHIPS)':
 C_PATH='@scm_lib.scm(sch_1):page57_i35@pure_quanta.hole(chips)',
 P_PATH='@scm_lib.scm(sch_1):page57_i35@pure_quanta.hole(chips)',
 PATH='I35',
 DRAWING='@SCM_LIB.SCM(SCH_1):PAGE57',
 PHYS_PAGE='57',
 XY='(-1675,3600)',
 ROT='0',
 VER='1',
 PACK_TYPE='TH',
 LOCATION='H5',
 CDS_LIB='pure_quanta',
 CDS_PART_NAME='HOLE_TH-EMPTY,HOLE1211',
 MATERIAL='EMPTY',
 PRIM_FILE='W:/<user>/logical/hole/chips/chips.prt';

PART_NAME
 H6 'HOLE_TH-EMPTY,TMP-C_HOLE8':;

SECTION_NUMBER 1
 '@SCM_LIB.SCM(SCH_1):PAGE57_I50@PURE_QUANTA.HOLE(CHIPS)':
 C_PATH='@scm_lib.scm(sch_1):page57_i50@pure_quanta.hole(chips)',
 P_PATH='@scm_lib.scm(sch_1):page57_i50@pure_quanta.hole(chips)',
 PATH='I50',
 DRAWING='@SCM_LIB.SCM(SCH_1):PAGE57',
 PHYS_PAGE='57',
 XY='(525,3575)',
 ROT='0',
 VER='1',
 PACK_TYPE='TH',
 LOCATION='H6',
 CDS_LIB='pure_quanta',
 CDS_PART_NAME='HOLE_TH-EMPTY,TMP-C_HOLE8',
 MATERIAL='EMPTY',
 PRIM_FILE='W:/<user>/logical/hole/chips/chips.prt';

PART_NAME
 H7 'HOLE_TH-EMPTY,TMP-C_HOLE8':;

SECTION_NUMBER 1
 '@SCM_LIB.SCM(SCH_1):PAGE57_I51@PURE_QUANTA.HOLE(CHIPS)':
 C_PATH='@scm_lib.scm(sch_1):page57_i51@pure_quanta.hole(chips)',
 P_PATH='@scm_lib.scm(sch_1):page57_i51@pure_quanta.hole(chips)',
 PATH='I51',
 DRAWING='@SCM_LIB.SCM(SCH_1):PAGE57',
 PHYS_PAGE='57',
 XY='(550,3000)',
 ROT='0',
 VER='1',
 PACK_TYPE='TH',
 LOCATION='H7',
 CDS_LIB='pure_quanta',
 CDS_PART_NAME='HOLE_TH-EMPTY,TMP-C_HOLE8',
 MATERIAL='EMPTY',
 PRIM_FILE='W:/<user>/logical/hole/chips/chips.prt';

PART_NAME
 H9 'HOLE_TH-EMPTY,HOLE1211':;

SECTION_NUMBER 1
 '@SCM_LIB.SCM(SCH_1):PAGE57_I36@PURE_QUANTA.HOLE(CHIPS)':
 C_PATH='@scm_lib.scm(sch_1):page57_i36@pure_quanta.hole(chips)',
 P_PATH='@scm_lib.scm(sch_1):page57_i36@pure_quanta.hole(chips)',
 PATH='I36',
 DRAWING='@SCM_LIB.SCM(SCH_1):PAGE57',
 PHYS_PAGE='57',
 XY='(-1650,2975)',
 ROT='0',
 VER='1',
 PACK_TYPE='TH',
 LOCATION='H9',
 CDS_LIB='pure_quanta',
 CDS_PART_NAME='HOLE_TH-EMPTY,HOLE1211',
 MATERIAL='EMPTY',
 PRIM_FILE='W:/<user>/logical/hole/chips/chips.prt';

PART_NAME
 J1 'SCONN3_212H9103GBR1-SCONN3_212A':;

SECTION_NUMBER 1
 '@SCM_LIB.SCM(SCH_1):PAGE25_I169@PURE_QUANTA.SCONN3_212H9103GBR1(CHIPS)':
 C_PATH='@scm_lib.scm(sch_1):page25_i169@pure_quanta.sconn3_212h9103gbr1(chips)',
 P_PATH='@scm_lib.scm(sch_1):page25_i169@pure_quanta.sconn3_212h9103gbr1(chips)',
 PATH='I169',
 DRAWING='@SCM_LIB.SCM(SCH_1):PAGE25',
 PART_TYPE='SMLF',
 PHYS_PAGE='25',
 XY='(4500,1250)',
 ROT='0',
 VER='1',
 LOCATION='J1',
 CDS_LIB='pure_quanta',
 CDS_PART_NAME='SCONN3_212H9103GBR1-SCONN3_212B',
 MATERIAL='IO',
 VALUE='SCONN3_212-H91-03GBR1',
 PRIM_FILE='W:/<user>/logical/sconn3_212h9103gbr1/chips/chips.prt';

PART_NAME
 J2 'CONN9_GSB3111315HR-CONN9_GSB31A':;

SECTION_NUMBER 1
 '@SCM_LIB.SCM(SCH_1):PAGE29_I221@PURE_QUANTA.CONN9_GSB3111315HR(CHIPS)':
 C_PATH='@scm_lib.scm(sch_1):page29_i221@pure_quanta.conn9_gsb3111315hr(chips)',
 P_PATH='@scm_lib.scm(sch_1):page29_i221@pure_quanta.conn9_gsb3111315hr(chips)',
 PATH='I221',
 DRAWING='@SCM_LIB.SCM(SCH_1):PAGE29',
 PART_TYPE='THLF',
 PHYS_PAGE='29',
 XY='(4375,525)',
 ROT='0',
 VER='1',
 LOCATION='J2',
 CDS_LIB='pure_quanta',
 CDS_PART_NAME='CONN9_GSB3111315HR-CONN9_GSB31A',
 MATERIAL='IO',
 VALUE='CONN9_GSB3111315HR',
 PRIM_FILE='W:/<user>/logical/conn9_gsb3111315hr/chips/chips.prt';

PART_NAME
 J4 'SCONN67_NASA0S6730TS67-SCONN67A':;

SECTION_NUMBER 1
 '@SCM_LIB.SCM(SCH_1):PAGE21_I84@PURE_QUANTA.SCONN67_NASA0S6730TS67(CHIPS)':
 C_PATH='@scm_lib.scm(sch_1):page21_i84@pure_quanta.sconn67_nasa0s6730ts67(chips~
)',
 P_PATH='@scm_lib.scm(sch_1):page21_i84@pure_quanta.sconn67_nasa0s6730ts67(chips~
)',
 PATH='I84',
 DRAWING='@SCM_LIB.SCM(SCH_1):PAGE21',
 PART_TYPE='SMLF',
 PHYS_PAGE='21',
 XY='(1525,2575)',
 ROT='0',
 VER='1',
 CDS_LIB='pure_quanta',
 CDS_PART_NAME='SCONN67_NASA0S6730TS67-SCONN67A',
 MATERIAL='IO',
 VALUE='SCONN67_NASA0-S6730-TS67',
 PRIM_FILE='W:/<user>/logical/sconn67_nasa0s6730ts67/chips/chips.prt';

PART_NAME
 J5 'SCONN11_9192031111LF-SCONN11_9A':;

SECTION_NUMBER 1
 '@SCM_LIB.SCM(SCH_1):PAGE46_I56@PURE_QUANTA.SCONN11_9192031111LF(CHIPS)':
 C_PATH='@scm_lib.scm(sch_1):page46_i56@pure_quanta.sconn11_9192031111lf(chips)',
 P_PATH='@scm_lib.scm(sch_1):page46_i56@pure_quanta.sconn11_9192031111lf(chips)',
 PATH='I56',
 DRAWING='@SCM_LIB.SCM(SCH_1):PAGE46',
 PART_TYPE='SMLF',
 PHYS_PAGE='46',
 XY='(-7875,-2850)',
 ROT='0',
 VER='1',
 LOCATION='J5',
 CDS_LIB='pure_quanta',
 CDS_PART_NAME='SCONN11_9192031111LF-SCONN11_9A',
 MATERIAL='IO',
 VALUE='SCONN11_91920-31111LF',
 PRIM_FILE='W:/<user>/logical/sconn11_9192031111lf/chips/chips.prt';

PART_NAME
 J6 'SCONN3_21291035BR2-SCONN3_212-A':;

SECTION_NUMBER 1
 '@SCM_LIB.SCM(SCH_1):PAGE30_I184@PURE_QUANTA.SCONN3_21291035BR2(CHIPS)':
 C_PATH='@scm_lib.scm(sch_1):page30_i184@pure_quanta.sconn3_21291035br2(chips)',
 P_PATH='@scm_lib.scm(sch_1):page30_i184@pure_quanta.sconn3_21291035br2(chips)',
 PATH='I184',
 DRAWING='@SCM_LIB.SCM(SCH_1):PAGE30',
 SEC_TYPE='',
 PART_TYPE='SMLF',
 PHYS_PAGE='30',
 XY='(-2225,925)',
 ROT='2',
 VER='1',
 LOCATION='J6',
 SEC='1',
 CDS_LIB='pure_quanta',
 CDS_PART_NAME='SCONN3_21291035BR2-SCONN3_212-A',
 MATERIAL='EMPTY',
 VALUE='SCONN3_212-91-035BR2',
 PRIM_FILE='W:/<user>/logical/sconn3_21291035br2/chips/chips.prt';

PART_NAME
 J7 'CONN8_210HP1080BR1-CONN8_210-HA':;

SECTION_NUMBER 1
 '@SCM_LIB.SCM(SCH_1):PAGE32_I132@PURE_QUANTA.CONN8_210HP1080BR1(CHIPS)':
 C_PATH='@scm_lib.scm(sch_1):page32_i132@pure_quanta.conn8_210hp1080br1(chips)',
 P_PATH='@scm_lib.scm(sch_1):page32_i132@pure_quanta.conn8_210hp1080br1(chips)',
 PATH='I132',
 DRAWING='@SCM_LIB.SCM(SCH_1):PAGE32',
 PART_TYPE='THLF',
 PHYS_PAGE='32',
 XY='(2675,3350)',
 ROT='2',
 VER='1',
 LOCATION='J7',
 CDS_LIB='pure_quanta',
 CDS_PART_NAME='CONN8_210HP1080BR1-CONN8_210-HA',
 MATERIAL='IO',
 VALUE='CONN8_210-HP1-080BR1',
 PRIM_FILE='W:/<user>/logical/conn8_210hp1080br1/chips/chips.prt';

PART_NAME
 J8 'SCONN13_502280130CV01-SCONN13_A':;

SECTION_NUMBER 1
 '@SCM_LIB.SCM(SCH_1):PAGE23_I165@PURE_QUANTA.SCONN13_502280130CV01(CHIPS)':
 C_PATH='@scm_lib.scm(sch_1):page23_i165@pure_quanta.sconn13_502280130cv01(chips~
)',
 P_PATH='@scm_lib.scm(sch_1):page23_i165@pure_quanta.sconn13_502280130cv01(chips~
)',
 PATH='I165',
 DRAWING='@SCM_LIB.SCM(SCH_1):PAGE23',
 PART_TYPE='SMLF',
 PHYS_PAGE='23',
 XY='(6250,-550)',
 ROT='2',
 VER='1',
 LOCATION='J8',
 CDS_LIB='pure_quanta',
 CDS_PART_NAME='SCONN13_502280130CV01-SCONN13_A',
 MATERIAL='IO',
 VALUE='SCONN13_50228-0130C-V01',
 PRIM_FILE='W:/<user>/logical/sconn13_502280130cv01/chips/chips.prt';

PART_NAME
 J9 'PICOPROBE_BXA-DELTA-L 4.0,SMLFA':;

SECTION_NUMBER 1
 '@SCM_LIB.SCM(SCH_1):PAGE58_I55@PURE_QUANTA.PICOPROBE_BXA(CHIPS)':
 C_PATH='@scm_lib.scm(sch_1):page58_i55@pure_quanta.picoprobe_bxa(chips)',
 P_PATH='@scm_lib.scm(sch_1):page58_i55@pure_quanta.picoprobe_bxa(chips)',
 PATH='I55',
 DRAWING='@SCM_LIB.SCM(SCH_1):PAGE58',
 PART_TYPE='SMLF',
 PHYS_PAGE='58',
 XY='(-7675,3625)',
 ROT='0',
 VER='1',
 LOCATION='J9',
 CDS_LIB='pure_quanta',
 CDS_PART_NAME='PICOPROBE_BXA-DELTA-L 4.0,SMLFA',
 MATERIAL='EMPTY',
 VALUE='DELTA-L 4.0',
 PRIM_FILE='W:/<user>/logical/picoprobe_bxa/chips/chips.prt';

PART_NAME
 J10 'SCONN11_9192031111LF-SCONN11_9A':;

SECTION_NUMBER 1
 '@SCM_LIB.SCM(SCH_1):PAGE46_I113@PURE_QUANTA.SCONN11_9192031111LF(CHIPS)':
 C_PATH='@scm_lib.scm(sch_1):page46_i113@pure_quanta.sconn11_9192031111lf(chips)~
',
 P_PATH='@scm_lib.scm(sch_1):page46_i113@pure_quanta.sconn11_9192031111lf(chips)~
',
 PATH='I113',
 DRAWING='@SCM_LIB.SCM(SCH_1):PAGE46',
 PART_TYPE='SMLF',
 PHYS_PAGE='46',
 XY='(-7950,-5725)',
 ROT='0',
 VER='1',
 LOCATION='J10',
 CDS_LIB='pure_quanta',
 CDS_PART_NAME='SCONN11_9192031111LF-SCONN11_9A',
 MATERIAL='IO',
 VALUE='SCONN11_91920-31111LF',
 PRIM_FILE='W:/<user>/logical/sconn11_9192031111lf/chips/chips.prt';

PART_NAME
 J11 'PICOPROBE_BXA-DELTA-L 4.0,SMLFA':;

SECTION_NUMBER 1
 '@SCM_LIB.SCM(SCH_1):PAGE58_I57@PURE_QUANTA.PICOPROBE_BXA(CHIPS)':
 C_PATH='@scm_lib.scm(sch_1):page58_i57@pure_quanta.picoprobe_bxa(chips)',
 P_PATH='@scm_lib.scm(sch_1):page58_i57@pure_quanta.picoprobe_bxa(chips)',
 PATH='I57',
 DRAWING='@SCM_LIB.SCM(SCH_1):PAGE58',
 PART_TYPE='SMLF',
 PHYS_PAGE='58',
 XY='(-7675,2750)',
 ROT='0',
 VER='1',
 LOCATION='J11',
 CDS_LIB='pure_quanta',
 CDS_PART_NAME='PICOPROBE_BXA-DELTA-L 4.0,SMLFA',
 MATERIAL='EMPTY',
 VALUE='DELTA-L 4.0',
 PRIM_FILE='W:/<user>/logical/picoprobe_bxa/chips/chips.prt';

PART_NAME
 J12 'PICOPROBE_BXA-DELTA-L 4.0,SMLFA':;

SECTION_NUMBER 1
 '@SCM_LIB.SCM(SCH_1):PAGE58_I64@PURE_QUANTA.PICOPROBE_BXA(CHIPS)':
 C_PATH='@scm_lib.scm(sch_1):page58_i64@pure_quanta.picoprobe_bxa(chips)',
 P_PATH='@scm_lib.scm(sch_1):page58_i64@pure_quanta.picoprobe_bxa(chips)',
 PATH='I64',
 DRAWING='@SCM_LIB.SCM(SCH_1):PAGE58',
 PART_TYPE='SMLF',
 PHYS_PAGE='58',
 XY='(-5000,3675)',
 ROT='4',
 VER='1',
 LOCATION='J12',
 CDS_LIB='pure_quanta',
 CDS_PART_NAME='PICOPROBE_BXA-DELTA-L 4.0,SMLFA',
 MATERIAL='EMPTY',
 VALUE='DELTA-L 4.0',
 PRIM_FILE='W:/<user>/logical/picoprobe_bxa/chips/chips.prt';

PART_NAME
 J13 'SCONN3_212H9103GBR1-SCONN3_212B':;

SECTION_NUMBER 1
 '@SCM_LIB.SCM(SCH_1):PAGE31_I61@PURE_QUANTA.SCONN3_212H9103GBR1(CHIPS)':
 C_PATH='@scm_lib.scm(sch_1):page31_i61@pure_quanta.sconn3_212h9103gbr1(chips)',
 P_PATH='@scm_lib.scm(sch_1):page31_i61@pure_quanta.sconn3_212h9103gbr1(chips)',
 PATH='I61',
 DRAWING='@SCM_LIB.SCM(SCH_1):PAGE31',
 PART_TYPE='SMLF',
 PHYS_PAGE='31',
 XY='(-1450,2025)',
 ROT='0',
 VER='1',
 LOCATION='J13',
 CDS_LIB='pure_quanta',
 CDS_PART_NAME='SCONN3_212H9103GBR1-SCONN3_212A',
 MATERIAL='EMPTY',
 VALUE='SCONN3_212-H91-03GBR1',
 PRIM_FILE='W:/<user>/logical/sconn3_212h9103gbr1/chips/chips.prt';

PART_NAME
 J14 'CONN8_TSW10407FD-CONN8_TSW-104A':;

SECTION_NUMBER 1
 '@SCM_LIB.SCM(SCH_1):PAGE26_I71@PURE_QUANTA.CONN8_TSW10407FD(CHIPS)':
 C_PATH='@scm_lib.scm(sch_1):page26_i71@pure_quanta.conn8_tsw10407fd(chips)',
 P_PATH='@scm_lib.scm(sch_1):page26_i71@pure_quanta.conn8_tsw10407fd(chips)',
 PATH='I71',
 DRAWING='@SCM_LIB.SCM(SCH_1):PAGE26',
 PART_TYPE='THLF',
 PHYS_PAGE='26',
 XY='(175,2975)',
 ROT='0',
 VER='1',
 LOCATION='J14',
 CDS_LIB='pure_quanta',
 CDS_PART_NAME='CONN8_TSW10407FD-CONN8_TSW-104A',
 MATERIAL='EMPTY',
 VALUE='CONN8_TSW-104-07-F-D',
 PRIM_FILE='W:/<user>/logical/conn8_tsw10407fd/chips/chips.prt';

PART_NAME
 J16 'PICOPROBE_BXA-DELTA-L 4.0,SMLFA':;

SECTION_NUMBER 1
 '@SCM_LIB.SCM(SCH_1):PAGE58_I58@PURE_QUANTA.PICOPROBE_BXA(CHIPS)':
 C_PATH='@scm_lib.scm(sch_1):page58_i58@pure_quanta.picoprobe_bxa(chips)',
 P_PATH='@scm_lib.scm(sch_1):page58_i58@pure_quanta.picoprobe_bxa(chips)',
 PATH='I58',
 DRAWING='@SCM_LIB.SCM(SCH_1):PAGE58',
 PART_TYPE='SMLF',
 PHYS_PAGE='58',
 XY='(-3500,3575)',
 ROT='0',
 VER='1',
 LOCATION='J16',
 CDS_LIB='pure_quanta',
 CDS_PART_NAME='PICOPROBE_BXA-DELTA-L 4.0,SMLFA',
 MATERIAL='EMPTY',
 VALUE='DELTA-L 4.0',
 PRIM_FILE='W:/<user>/logical/picoprobe_bxa/chips/chips.prt';

PART_NAME
 J17 'PICOPROBE_BXA-DELTA-L 4.0,SMLFA':;

SECTION_NUMBER 1
 '@SCM_LIB.SCM(SCH_1):PAGE58_I59@PURE_QUANTA.PICOPROBE_BXA(CHIPS)':
 C_PATH='@scm_lib.scm(sch_1):page58_i59@pure_quanta.picoprobe_bxa(chips)',
 P_PATH='@scm_lib.scm(sch_1):page58_i59@pure_quanta.picoprobe_bxa(chips)',
 PATH='I59',
 DRAWING='@SCM_LIB.SCM(SCH_1):PAGE58',
 PART_TYPE='SMLF',
 PHYS_PAGE='58',
 XY='(-3500,2650)',
 ROT='0',
 VER='1',
 LOCATION='J17',
 CDS_LIB='pure_quanta',
 CDS_PART_NAME='PICOPROBE_BXA-DELTA-L 4.0,SMLFA',
 MATERIAL='EMPTY',
 VALUE='DELTA-L 4.0',
 PRIM_FILE='W:/<user>/logical/picoprobe_bxa/chips/chips.prt';

PART_NAME
 J19 'PICOPROBE_BXA-DELTA-L 4.0,SMLFA':;

SECTION_NUMBER 1
 '@SCM_LIB.SCM(SCH_1):PAGE58_I71@PURE_QUANTA.PICOPROBE_BXA(CHIPS)':
 C_PATH='@scm_lib.scm(sch_1):page58_i71@pure_quanta.picoprobe_bxa(chips)',
 P_PATH='@scm_lib.scm(sch_1):page58_i71@pure_quanta.picoprobe_bxa(chips)',
 PATH='I71',
 DRAWING='@SCM_LIB.SCM(SCH_1):PAGE58',
 PART_TYPE='SMLF',
 PHYS_PAGE='58',
 XY='(-825,3625)',
 ROT='4',
 VER='1',
 LOCATION='J19',
 CDS_LIB='pure_quanta',
 CDS_PART_NAME='PICOPROBE_BXA-DELTA-L 4.0,SMLFA',
 MATERIAL='EMPTY',
 VALUE='DELTA-L 4.0',
 PRIM_FILE='W:/<user>/logical/picoprobe_bxa/chips/chips.prt';

PART_NAME
 J20 'PICOPROBE_BXA-DELTA-L 4.0,SMLFA':;

SECTION_NUMBER 1
 '@SCM_LIB.SCM(SCH_1):PAGE58_I70@PURE_QUANTA.PICOPROBE_BXA(CHIPS)':
 C_PATH='@scm_lib.scm(sch_1):page58_i70@pure_quanta.picoprobe_bxa(chips)',
 P_PATH='@scm_lib.scm(sch_1):page58_i70@pure_quanta.picoprobe_bxa(chips)',
 PATH='I70',
 DRAWING='@SCM_LIB.SCM(SCH_1):PAGE58',
 PART_TYPE='SMLF',
 PHYS_PAGE='58',
 XY='(-825,2700)',
 ROT='4',
 VER='1',
 LOCATION='J20',
 CDS_LIB='pure_quanta',
 CDS_PART_NAME='PICOPROBE_BXA-DELTA-L 4.0,SMLFA',
 MATERIAL='EMPTY',
 VALUE='DELTA-L 4.0',
 PRIM_FILE='W:/<user>/logical/picoprobe_bxa/chips/chips.prt';

PART_NAME
 J22 'PICOPROBE_BXA-DELTA-L 4.0,SMLFA':;

SECTION_NUMBER 1
 '@SCM_LIB.SCM(SCH_1):PAGE58_I66@PURE_QUANTA.PICOPROBE_BXA(CHIPS)':
 C_PATH='@scm_lib.scm(sch_1):page58_i66@pure_quanta.picoprobe_bxa(chips)',
 P_PATH='@scm_lib.scm(sch_1):page58_i66@pure_quanta.picoprobe_bxa(chips)',
 PATH='I66',
 DRAWING='@SCM_LIB.SCM(SCH_1):PAGE58',
 PART_TYPE='SMLF',
 PHYS_PAGE='58',
 XY='(-4925,600)',
 ROT='4',
 VER='1',
 LOCATION='J22',
 CDS_LIB='pure_quanta',
 CDS_PART_NAME='PICOPROBE_BXA-DELTA-L 4.0,SMLFA',
 MATERIAL='EMPTY',
 VALUE='DELTA-L 4.0',
 PRIM_FILE='W:/<user>/logical/picoprobe_bxa/chips/chips.prt';

PART_NAME
 J23 'PICOPROBE_BXA-DELTA-L 4.0,SMLFA':;

SECTION_NUMBER 1
 '@SCM_LIB.SCM(SCH_1):PAGE58_I69@PURE_QUANTA.PICOPROBE_BXA(CHIPS)':
 C_PATH='@scm_lib.scm(sch_1):page58_i69@pure_quanta.picoprobe_bxa(chips)',
 P_PATH='@scm_lib.scm(sch_1):page58_i69@pure_quanta.picoprobe_bxa(chips)',
 PATH='I69',
 DRAWING='@SCM_LIB.SCM(SCH_1):PAGE58',
 PART_TYPE='SMLF',
 PHYS_PAGE='58',
 XY='(-625,550)',
 ROT='4',
 VER='1',
 LOCATION='J23',
 CDS_LIB='pure_quanta',
 CDS_PART_NAME='PICOPROBE_BXA-DELTA-L 4.0,SMLFA',
 MATERIAL='EMPTY',
 VALUE='DELTA-L 4.0',
 PRIM_FILE='W:/<user>/logical/picoprobe_bxa/chips/chips.prt';

PART_NAME
 J24 'PICOPROBE_BXA-DELTA-L 4.0,SMLFA':;

SECTION_NUMBER 1
 '@SCM_LIB.SCM(SCH_1):PAGE58_I68@PURE_QUANTA.PICOPROBE_BXA(CHIPS)':
 C_PATH='@scm_lib.scm(sch_1):page58_i68@pure_quanta.picoprobe_bxa(chips)',
 P_PATH='@scm_lib.scm(sch_1):page58_i68@pure_quanta.picoprobe_bxa(chips)',
 PATH='I68',
 DRAWING='@SCM_LIB.SCM(SCH_1):PAGE58',
 PART_TYPE='SMLF',
 PHYS_PAGE='58',
 XY='(-625,-375)',
 ROT='4',
 VER='1',
 LOCATION='J24',
 CDS_LIB='pure_quanta',
 CDS_PART_NAME='PICOPROBE_BXA-DELTA-L 4.0,SMLFA',
 MATERIAL='EMPTY',
 VALUE='DELTA-L 4.0',
 PRIM_FILE='W:/<user>/logical/picoprobe_bxa/chips/chips.prt';

PART_NAME
 J25 'PICOPROBE_BXA-DELTA-L 4.0,SMLFA':;

SECTION_NUMBER 1
 '@SCM_LIB.SCM(SCH_1):PAGE58_I60@PURE_QUANTA.PICOPROBE_BXA(CHIPS)':
 C_PATH='@scm_lib.scm(sch_1):page58_i60@pure_quanta.picoprobe_bxa(chips)',
 P_PATH='@scm_lib.scm(sch_1):page58_i60@pure_quanta.picoprobe_bxa(chips)',
 PATH='I60',
 DRAWING='@SCM_LIB.SCM(SCH_1):PAGE58',
 PART_TYPE='SMLF',
 PHYS_PAGE='58',
 XY='(-7600,550)',
 ROT='0',
 VER='1',
 LOCATION='J25',
 CDS_LIB='pure_quanta',
 CDS_PART_NAME='PICOPROBE_BXA-DELTA-L 4.0,SMLFA',
 MATERIAL='EMPTY',
 VALUE='DELTA-L 4.0',
 PRIM_FILE='W:/<user>/logical/picoprobe_bxa/chips/chips.prt';

PART_NAME
 J26 'PICOPROBE_BXA-DELTA-L 4.0,SMLFA':;

SECTION_NUMBER 1
 '@SCM_LIB.SCM(SCH_1):PAGE58_I62@PURE_QUANTA.PICOPROBE_BXA(CHIPS)':
 C_PATH='@scm_lib.scm(sch_1):page58_i62@pure_quanta.picoprobe_bxa(chips)',
 P_PATH='@scm_lib.scm(sch_1):page58_i62@pure_quanta.picoprobe_bxa(chips)',
 PATH='I62',
 DRAWING='@SCM_LIB.SCM(SCH_1):PAGE58',
 PART_TYPE='SMLF',
 PHYS_PAGE='58',
 XY='(-3300,500)',
 ROT='0',
 VER='1',
 LOCATION='J26',
 CDS_LIB='pure_quanta',
 CDS_PART_NAME='PICOPROBE_BXA-DELTA-L 4.0,SMLFA',
 MATERIAL='EMPTY',
 VALUE='DELTA-L 4.0',
 PRIM_FILE='W:/<user>/logical/picoprobe_bxa/chips/chips.prt';

PART_NAME
 J27 'PICOPROBE_BXA-DELTA-L 4.0,SMLFA':;

SECTION_NUMBER 1
 '@SCM_LIB.SCM(SCH_1):PAGE58_I63@PURE_QUANTA.PICOPROBE_BXA(CHIPS)':
 C_PATH='@scm_lib.scm(sch_1):page58_i63@pure_quanta.picoprobe_bxa(chips)',
 P_PATH='@scm_lib.scm(sch_1):page58_i63@pure_quanta.picoprobe_bxa(chips)',
 PATH='I63',
 DRAWING='@SCM_LIB.SCM(SCH_1):PAGE58',
 PART_TYPE='SMLF',
 PHYS_PAGE='58',
 XY='(-3300,-425)',
 ROT='0',
 VER='1',
 LOCATION='J27',
 CDS_LIB='pure_quanta',
 CDS_PART_NAME='PICOPROBE_BXA-DELTA-L 4.0,SMLFA',
 MATERIAL='EMPTY',
 VALUE='DELTA-L 4.0',
 PRIM_FILE='W:/<user>/logical/picoprobe_bxa/chips/chips.prt';

PART_NAME
 J28 'PICOPROBE_BXA-DELTA-L 4.0,SMLFA':;

SECTION_NUMBER 1
 '@SCM_LIB.SCM(SCH_1):PAGE58_I61@PURE_QUANTA.PICOPROBE_BXA(CHIPS)':
 C_PATH='@scm_lib.scm(sch_1):page58_i61@pure_quanta.picoprobe_bxa(chips)',
 P_PATH='@scm_lib.scm(sch_1):page58_i61@pure_quanta.picoprobe_bxa(chips)',
 PATH='I61',
 DRAWING='@SCM_LIB.SCM(SCH_1):PAGE58',
 PART_TYPE='SMLF',
 PHYS_PAGE='58',
 XY='(-7575,-375)',
 ROT='0',
 VER='1',
 LOCATION='J28',
 CDS_LIB='pure_quanta',
 CDS_PART_NAME='PICOPROBE_BXA-DELTA-L 4.0,SMLFA',
 MATERIAL='EMPTY',
 VALUE='DELTA-L 4.0',
 PRIM_FILE='W:/<user>/logical/picoprobe_bxa/chips/chips.prt';

PART_NAME
 J29 'PICOPROBE_BXA-DELTA-L 4.0,SMLFA':;

SECTION_NUMBER 1
 '@SCM_LIB.SCM(SCH_1):PAGE58_I65@PURE_QUANTA.PICOPROBE_BXA(CHIPS)':
 C_PATH='@scm_lib.scm(sch_1):page58_i65@pure_quanta.picoprobe_bxa(chips)',
 P_PATH='@scm_lib.scm(sch_1):page58_i65@pure_quanta.picoprobe_bxa(chips)',
 PATH='I65',
 DRAWING='@SCM_LIB.SCM(SCH_1):PAGE58',
 PART_TYPE='SMLF',
 PHYS_PAGE='58',
 XY='(-5000,2800)',
 ROT='4',
 VER='1',
 LOCATION='J29',
 CDS_LIB='pure_quanta',
 CDS_PART_NAME='PICOPROBE_BXA-DELTA-L 4.0,SMLFA',
 MATERIAL='EMPTY',
 VALUE='DELTA-L 4.0',
 PRIM_FILE='W:/<user>/logical/picoprobe_bxa/chips/chips.prt';

PART_NAME
 J30 'PICOPROBE_BXA-DELTA-L 4.0,SMLFA':;

SECTION_NUMBER 1
 '@SCM_LIB.SCM(SCH_1):PAGE58_I67@PURE_QUANTA.PICOPROBE_BXA(CHIPS)':
 C_PATH='@scm_lib.scm(sch_1):page58_i67@pure_quanta.picoprobe_bxa(chips)',
 P_PATH='@scm_lib.scm(sch_1):page58_i67@pure_quanta.picoprobe_bxa(chips)',
 PATH='I67',
 DRAWING='@SCM_LIB.SCM(SCH_1):PAGE58',
 PART_TYPE='SMLF',
 PHYS_PAGE='58',
 XY='(-4900,-325)',
 ROT='4',
 VER='1',
 LOCATION='J30',
 CDS_LIB='pure_quanta',
 CDS_PART_NAME='PICOPROBE_BXA-DELTA-L 4.0,SMLFA',
 MATERIAL='EMPTY',
 VALUE='DELTA-L 4.0',
 PRIM_FILE='W:/<user>/logical/picoprobe_bxa/chips/chips.prt';

PART_NAME
 J40 'SCONN16_ACASPI006P06-SCONN16_AA':;

SECTION_NUMBER 1
 '@SCM_LIB.SCM(SCH_1):PAGE45_I53@PURE_QUANTA.SCONN16_ACASPI006P06(CHIPS)':
 C_PATH='@scm_lib.scm(sch_1):page45_i53@pure_quanta.sconn16_acaspi006p06(chips)',
 P_PATH='@scm_lib.scm(sch_1):page45_i53@pure_quanta.sconn16_acaspi006p06(chips)',
 PATH='I53',
 DRAWING='@SCM_LIB.SCM(SCH_1):PAGE45',
 PART_TYPE='SMLF',
 PHYS_PAGE='45',
 XY='(1375,2050)',
 ROT='0',
 VER='1',
 LOCATION='J40',
 CDS_LIB='pure_quanta',
 CDS_PART_NAME='SCONN16_ACASPI006P06-SCONN16_AA',
 MATERIAL='IO',
 VALUE='SCONN16_ACA-SPI-006-P06',
 PRIM_FILE='W:/<user>/logical/sconn16_acaspi006p06/chips/chips.prt';

PART_NAME
 L2 'Q_INDUCTOR_SMLF-BLM18PG121SN1DA':;

SECTION_NUMBER 1
 '@SCM_LIB.SCM(SCH_1):PAGE17_I272@PURE_QUANTA.Q_INDUCTOR(CHIPS)':
 C_PATH='@scm_lib.scm(sch_1):page17_i272@pure_quanta.q_inductor(chips)',
 P_PATH='@scm_lib.scm(sch_1):page17_i272@pure_quanta.q_inductor(chips)',
 PATH='I272',
 DRAWING='@SCM_LIB.SCM(SCH_1):PAGE17',
 PHYS_PAGE='17',
 XY='(-125,650)',
 ROT='6',
 VER='1',
 PACK_TYPE='SMLF',
 LOCATION='L2',
 CDS_LIB='pure_quanta',
 CDS_PART_NAME='Q_INDUCTOR_SMLF-BLM18PG121SN1DA',
 MATERIAL='IND',
 VALUE='BLM18PG121SN1D/2000MA',
 PRIM_FILE='W:/<user>/logical/q_inductor/chips/chips.prt';

PART_NAME
 L3 'Q_INDUCTOR_SMLF-BLM18PG121SN1DA':;

SECTION_NUMBER 1
 '@SCM_LIB.SCM(SCH_1):PAGE15_I65@PURE_QUANTA.Q_INDUCTOR(CHIPS)':
 C_PATH='@scm_lib.scm(sch_1):page15_i65@pure_quanta.q_inductor(chips)',
 P_PATH='@scm_lib.scm(sch_1):page15_i65@pure_quanta.q_inductor(chips)',
 PATH='I65',
 DRAWING='@SCM_LIB.SCM(SCH_1):PAGE15',
 PHYS_PAGE='15',
 XY='(3500,850)',
 ROT='0',
 VER='1',
 PACK_TYPE='SMLF',
 LOCATION='L3',
 CDS_LIB='pure_quanta',
 CDS_PART_NAME='Q_INDUCTOR_SMLF-BLM18PG121SN1DA',
 MATERIAL='IND',
 VALUE='BLM18PG121SN1D/2000MA',
 PRIM_FILE='W:/<user>/logical/q_inductor/chips/chips.prt';

PART_NAME
 L4 'Q_INDUCTOR_SMLF-BLM18PG121SN1DA':;

SECTION_NUMBER 1
 '@SCM_LIB.SCM(SCH_1):PAGE15_I82@PURE_QUANTA.Q_INDUCTOR(CHIPS)':
 C_PATH='@scm_lib.scm(sch_1):page15_i82@pure_quanta.q_inductor(chips)',
 P_PATH='@scm_lib.scm(sch_1):page15_i82@pure_quanta.q_inductor(chips)',
 PATH='I82',
 DRAWING='@SCM_LIB.SCM(SCH_1):PAGE15',
 PHYS_PAGE='15',
 XY='(5000,825)',
 ROT='0',
 VER='1',
 PACK_TYPE='SMLF',
 LOCATION='L4',
 CDS_LIB='pure_quanta',
 CDS_PART_NAME='Q_INDUCTOR_SMLF-BLM18PG121SN1DA',
 MATERIAL='IND',
 VALUE='BLM18PG121SN1D/2000MA',
 PRIM_FILE='W:/<user>/logical/q_inductor/chips/chips.prt';

PART_NAME
 L5 'Q_INDUCTOR_SMLF-BLM18PG121SN1DA':;

SECTION_NUMBER 1
 '@SCM_LIB.SCM(SCH_1):PAGE17_I120@PURE_QUANTA.Q_INDUCTOR(CHIPS)':
 C_PATH='@scm_lib.scm(sch_1):page17_i120@pure_quanta.q_inductor(chips)',
 P_PATH='@scm_lib.scm(sch_1):page17_i120@pure_quanta.q_inductor(chips)',
 PATH='I120',
 DRAWING='@SCM_LIB.SCM(SCH_1):PAGE17',
 PHYS_PAGE='17',
 XY='(-1425,4075)',
 ROT='0',
 VER='1',
 PACK_TYPE='SMLF',
 LOCATION='L5',
 CDS_LIB='pure_quanta',
 CDS_PART_NAME='Q_INDUCTOR_SMLF-BLM18PG121SN1DA',
 MATERIAL='IND',
 VALUE='BLM18PG121SN1D/2000MA',
 PRIM_FILE='W:/<user>/logical/q_inductor/chips/chips.prt';

PART_NAME
 L6 'Q_INDUCTOR_SMLF-BLM18PG121SN1DA':;

SECTION_NUMBER 1
 '@SCM_LIB.SCM(SCH_1):PAGE17_I124@PURE_QUANTA.Q_INDUCTOR(CHIPS)':
 C_PATH='@scm_lib.scm(sch_1):page17_i124@pure_quanta.q_inductor(chips)',
 P_PATH='@scm_lib.scm(sch_1):page17_i124@pure_quanta.q_inductor(chips)',
 PATH='I124',
 DRAWING='@SCM_LIB.SCM(SCH_1):PAGE17',
 PHYS_PAGE='17',
 XY='(-1400,3200)',
 ROT='0',
 VER='1',
 PACK_TYPE='SMLF',
 LOCATION='L6',
 CDS_LIB='pure_quanta',
 CDS_PART_NAME='Q_INDUCTOR_SMLF-BLM18PG121SN1DA',
 MATERIAL='IND',
 VALUE='BLM18PG121SN1D/2000MA',
 PRIM_FILE='W:/<user>/logical/q_inductor/chips/chips.prt';

PART_NAME
 L7 'Q_INDUCTOR_SMLF-BLM18PG121SN1DA':;

SECTION_NUMBER 1
 '@SCM_LIB.SCM(SCH_1):PAGE17_I146@PURE_QUANTA.Q_INDUCTOR(CHIPS)':
 C_PATH='@scm_lib.scm(sch_1):page17_i146@pure_quanta.q_inductor(chips)',
 P_PATH='@scm_lib.scm(sch_1):page17_i146@pure_quanta.q_inductor(chips)',
 PATH='I146',
 DRAWING='@SCM_LIB.SCM(SCH_1):PAGE17',
 PHYS_PAGE='17',
 XY='(-1400,950)',
 ROT='0',
 VER='1',
 PACK_TYPE='SMLF',
 LOCATION='L7',
 CDS_LIB='pure_quanta',
 CDS_PART_NAME='Q_INDUCTOR_SMLF-BLM18PG121SN1DA',
 MATERIAL='IND',
 VALUE='BLM18PG121SN1D/2000MA',
 PRIM_FILE='W:/<user>/logical/q_inductor/chips/chips.prt';

PART_NAME
 L8 'Q_INDUCTOR_SMLF-BLM18PG121SN1DA':;

SECTION_NUMBER 1
 '@SCM_LIB.SCM(SCH_1):PAGE16_I29@PURE_QUANTA.Q_INDUCTOR(CHIPS)':
 C_PATH='@scm_lib.scm(sch_1):page16_i29@pure_quanta.q_inductor(chips)',
 P_PATH='@scm_lib.scm(sch_1):page16_i29@pure_quanta.q_inductor(chips)',
 PATH='I29',
 DRAWING='@SCM_LIB.SCM(SCH_1):PAGE16',
 PHYS_PAGE='16',
 XY='(-2750,2900)',
 ROT='0',
 VER='1',
 PACK_TYPE='SMLF',
 LOCATION='L8',
 CDS_LIB='pure_quanta',
 CDS_PART_NAME='Q_INDUCTOR_SMLF-BLM18PG121SN1DA',
 MATERIAL='IND',
 VALUE='BLM18PG121SN1D/2000MA',
 PRIM_FILE='W:/<user>/logical/q_inductor/chips/chips.prt';

PART_NAME
 L9 'Q_INDUCTOR_SMLF-BLM18PG121SN1DB':;

SECTION_NUMBER 1
 '@SCM_LIB.SCM(SCH_1):PAGE17_I142@PURE_QUANTA.Q_INDUCTOR(CHIPS)':
 C_PATH='@scm_lib.scm(sch_1):page17_i142@pure_quanta.q_inductor(chips)',
 P_PATH='@scm_lib.scm(sch_1):page17_i142@pure_quanta.q_inductor(chips)',
 PATH='I142',
 DRAWING='@SCM_LIB.SCM(SCH_1):PAGE17',
 PHYS_PAGE='17',
 XY='(-125,1075)',
 ROT='0',
 VER='1',
 PACK_TYPE='SMLF',
 LOCATION='L9',
 CDS_LIB='pure_quanta',
 CDS_PART_NAME='Q_INDUCTOR_SMLF-BLM18PG121SN1DB',
 MATERIAL='EMPTY',
 VALUE='BLM18PG121SN1D/2000MA',
 PRIM_FILE='W:/<user>/logical/q_inductor/chips/chips.prt';

PART_NAME
 L10 'Q_INDUCTOR_SMLF-BLM18PG121SN1DA':;

SECTION_NUMBER 1
 '@SCM_LIB.SCM(SCH_1):PAGE16_I24@PURE_QUANTA.Q_INDUCTOR(CHIPS)':
 C_PATH='@scm_lib.scm(sch_1):page16_i24@pure_quanta.q_inductor(chips)',
 P_PATH='@scm_lib.scm(sch_1):page16_i24@pure_quanta.q_inductor(chips)',
 PATH='I24',
 DRAWING='@SCM_LIB.SCM(SCH_1):PAGE16',
 PHYS_PAGE='16',
 XY='(-2050,2275)',
 ROT='0',
 VER='1',
 PACK_TYPE='SMLF',
 LOCATION='L10',
 CDS_LIB='pure_quanta',
 CDS_PART_NAME='Q_INDUCTOR_SMLF-BLM18PG121SN1DA',
 MATERIAL='IND',
 VALUE='BLM18PG121SN1D/2000MA',
 PRIM_FILE='W:/<user>/logical/q_inductor/chips/chips.prt';

PART_NAME
 L11 'Q_INDUCTOR_SMLF-BLM18PG121SN1DA':;

SECTION_NUMBER 1
 '@SCM_LIB.SCM(SCH_1):PAGE16_I47@PURE_QUANTA.Q_INDUCTOR(CHIPS)':
 C_PATH='@scm_lib.scm(sch_1):page16_i47@pure_quanta.q_inductor(chips)',
 P_PATH='@scm_lib.scm(sch_1):page16_i47@pure_quanta.q_inductor(chips)',
 PATH='I47',
 DRAWING='@SCM_LIB.SCM(SCH_1):PAGE16',
 PHYS_PAGE='16',
 XY='(-1900,1000)',
 ROT='0',
 VER='1',
 PACK_TYPE='SMLF',
 LOCATION='L11',
 CDS_LIB='pure_quanta',
 CDS_PART_NAME='Q_INDUCTOR_SMLF-BLM18PG121SN1DA',
 MATERIAL='IND',
 VALUE='BLM18PG121SN1D/2000MA',
 PRIM_FILE='W:/<user>/logical/q_inductor/chips/chips.prt';

PART_NAME
 L12 'Q_INDUCTOR_SMLF-BLM18PG121SN1DA':;

SECTION_NUMBER 1
 '@SCM_LIB.SCM(SCH_1):PAGE16_I99@PURE_QUANTA.Q_INDUCTOR(CHIPS)':
 C_PATH='@scm_lib.scm(sch_1):page16_i99@pure_quanta.q_inductor(chips)',
 P_PATH='@scm_lib.scm(sch_1):page16_i99@pure_quanta.q_inductor(chips)',
 PATH='I99',
 DRAWING='@SCM_LIB.SCM(SCH_1):PAGE16',
 PHYS_PAGE='16',
 XY='(-1100,4625)',
 ROT='0',
 VER='1',
 PACK_TYPE='SMLF',
 LOCATION='L12',
 CDS_LIB='pure_quanta',
 CDS_PART_NAME='Q_INDUCTOR_SMLF-BLM18PG121SN1DA',
 MATERIAL='IND',
 VALUE='BLM18PG121SN1D/2000MA',
 PRIM_FILE='W:/<user>/logical/q_inductor/chips/chips.prt';

PART_NAME
 L13 'Q_INDUCTOR_SMLF-BLM18PG121SN1DA':;

SECTION_NUMBER 1
 '@SCM_LIB.SCM(SCH_1):PAGE17_I158@PURE_QUANTA.Q_INDUCTOR(CHIPS)':
 C_PATH='@scm_lib.scm(sch_1):page17_i158@pure_quanta.q_inductor(chips)',
 P_PATH='@scm_lib.scm(sch_1):page17_i158@pure_quanta.q_inductor(chips)',
 PATH='I158',
 DRAWING='@SCM_LIB.SCM(SCH_1):PAGE17',
 PHYS_PAGE='17',
 XY='(-1475,-100)',
 ROT='0',
 VER='1',
 PACK_TYPE='SMLF',
 LOCATION='L13',
 CDS_LIB='pure_quanta',
 CDS_PART_NAME='Q_INDUCTOR_SMLF-BLM18PG121SN1DA',
 MATERIAL='IND',
 VALUE='BLM18PG121SN1D/2000MA',
 PRIM_FILE='W:/<user>/logical/q_inductor/chips/chips.prt';

PART_NAME
 L14 'Q_INDUCTOR_SMLF-BLM18PG121SN1DA':;

SECTION_NUMBER 1
 '@SCM_LIB.SCM(SCH_1):PAGE17_I154@PURE_QUANTA.Q_INDUCTOR(CHIPS)':
 C_PATH='@scm_lib.scm(sch_1):page17_i154@pure_quanta.q_inductor(chips)',
 P_PATH='@scm_lib.scm(sch_1):page17_i154@pure_quanta.q_inductor(chips)',
 PATH='I154',
 DRAWING='@SCM_LIB.SCM(SCH_1):PAGE17',
 PHYS_PAGE='17',
 XY='(-150,-50)',
 ROT='0',
 VER='1',
 PACK_TYPE='SMLF',
 LOCATION='L14',
 CDS_LIB='pure_quanta',
 CDS_PART_NAME='Q_INDUCTOR_SMLF-BLM18PG121SN1DA',
 MATERIAL='IND',
 VALUE='BLM18PG121SN1D/2000MA',
 PRIM_FILE='W:/<user>/logical/q_inductor/chips/chips.prt';

PART_NAME
 L15 'Q_INDUCTOR_SMLF-BLM18PG121SN1DA':;

SECTION_NUMBER 1
 '@SCM_LIB.SCM(SCH_1):PAGE17_I170@PURE_QUANTA.Q_INDUCTOR(CHIPS)':
 C_PATH='@scm_lib.scm(sch_1):page17_i170@pure_quanta.q_inductor(chips)',
 P_PATH='@scm_lib.scm(sch_1):page17_i170@pure_quanta.q_inductor(chips)',
 PATH='I170',
 DRAWING='@SCM_LIB.SCM(SCH_1):PAGE17',
 PHYS_PAGE='17',
 XY='(1750,2150)',
 ROT='0',
 VER='1',
 PACK_TYPE='SMLF',
 LOCATION='L15',
 CDS_LIB='pure_quanta',
 CDS_PART_NAME='Q_INDUCTOR_SMLF-BLM18PG121SN1DA',
 MATERIAL='IND',
 VALUE='BLM18PG121SN1D/2000MA',
 PRIM_FILE='W:/<user>/logical/q_inductor/chips/chips.prt';

PART_NAME
 L16 'Q_INDUCTOR_SMLF-BLM18PG121SN1DA':;

SECTION_NUMBER 1
 '@SCM_LIB.SCM(SCH_1):PAGE17_I166@PURE_QUANTA.Q_INDUCTOR(CHIPS)':
 C_PATH='@scm_lib.scm(sch_1):page17_i166@pure_quanta.q_inductor(chips)',
 P_PATH='@scm_lib.scm(sch_1):page17_i166@pure_quanta.q_inductor(chips)',
 PATH='I166',
 DRAWING='@SCM_LIB.SCM(SCH_1):PAGE17',
 PHYS_PAGE='17',
 XY='(3125,2200)',
 ROT='0',
 VER='1',
 PACK_TYPE='SMLF',
 LOCATION='L16',
 CDS_LIB='pure_quanta',
 CDS_PART_NAME='Q_INDUCTOR_SMLF-BLM18PG121SN1DA',
 MATERIAL='IND',
 VALUE='BLM18PG121SN1D/2000MA',
 PRIM_FILE='W:/<user>/logical/q_inductor/chips/chips.prt';

PART_NAME
 L17 'Q_INDUCTOR_SMLF-BLM18EG121SN1DA':;

SECTION_NUMBER 1
 '@SCM_LIB.SCM(SCH_1):PAGE17_I176@PURE_QUANTA.Q_INDUCTOR(CHIPS)':
 C_PATH='@scm_lib.scm(sch_1):page17_i176@pure_quanta.q_inductor(chips)',
 P_PATH='@scm_lib.scm(sch_1):page17_i176@pure_quanta.q_inductor(chips)',
 PATH='I176',
 DRAWING='@SCM_LIB.SCM(SCH_1):PAGE17',
 PHYS_PAGE='17',
 XY='(2325,450)',
 ROT='2',
 VER='1',
 PACK_TYPE='SMLF',
 LOCATION='L17',
 CDS_LIB='pure_quanta',
 CDS_PART_NAME='Q_INDUCTOR_SMLF-BLM18EG121SN1DA',
 MATERIAL='IND',
 VALUE='BLM18EG121SN1D/2A',
 PRIM_FILE='W:/<user>/logical/q_inductor/chips/chips.prt';

PART_NAME
 L19 'Q_INDUCTOR_SMLF-BLM18EG121SN1DA':;

SECTION_NUMBER 1
 '@SCM_LIB.SCM(SCH_1):PAGE41_I107@PURE_QUANTA.Q_INDUCTOR(CHIPS)':
 C_PATH='@scm_lib.scm(sch_1):page41_i107@pure_quanta.q_inductor(chips)',
 P_PATH='@scm_lib.scm(sch_1):page41_i107@pure_quanta.q_inductor(chips)',
 PATH='I107',
 DRAWING='@SCM_LIB.SCM(SCH_1):PAGE41',
 PHYS_PAGE='41',
 XY='(-5550,2200)',
 ROT='0',
 VER='1',
 PACK_TYPE='SMLF',
 CDS_LIB='pure_quanta',
 CDS_PART_NAME='Q_INDUCTOR_SMLF-BLM18EG121SN1DA',
 MATERIAL='IND',
 VALUE='BLM18EG121SN1D/2A',
 PRIM_FILE='W:/<user>/logical/q_inductor/chips/chips.prt';

PART_NAME
 L21 'Q_INDUCTOR4P_12-67/320MA,320MAA':;

SECTION_NUMBER 1
 '@SCM_LIB.SCM(SCH_1):PAGE29_I123@PURE_QUANTA.Q_INDUCTOR4P_12(CHIPS)':
 C_PATH='@scm_lib.scm(sch_1):page29_i123@pure_quanta.q_inductor4p_12(chips)',
 P_PATH='@scm_lib.scm(sch_1):page29_i123@pure_quanta.q_inductor4p_12(chips)',
 PATH='I123',
 DRAWING='@SCM_LIB.SCM(SCH_1):PAGE29',
 CURRENT_AMP='320MA',
 PART_TYPE='SMLF',
 PHYS_PAGE='29',
 XY='(-850,3825)',
 ROT='2',
 VER='1',
 LOCATION='L21',
 CDS_LIB='pure_quanta',
 CDS_PART_NAME='Q_INDUCTOR4P_12-67/320MA,320MAA',
 MATERIAL='EMPTY',
 VALUE='67/320MA',
 PRIM_FILE='W:/<user>/logical/q_inductor4p_12/chips/chips.prt';

PART_NAME
 L22 'Q_INDUCTOR4P_12-67/320MA,320MAA':;

SECTION_NUMBER 1
 '@SCM_LIB.SCM(SCH_1):PAGE29_I113@PURE_QUANTA.Q_INDUCTOR4P_12(CHIPS)':
 C_PATH='@scm_lib.scm(sch_1):page29_i113@pure_quanta.q_inductor4p_12(chips)',
 P_PATH='@scm_lib.scm(sch_1):page29_i113@pure_quanta.q_inductor4p_12(chips)',
 PATH='I113',
 DRAWING='@SCM_LIB.SCM(SCH_1):PAGE29',
 CURRENT_AMP='320MA',
 PART_TYPE='SMLF',
 PHYS_PAGE='29',
 XY='(-875,2500)',
 ROT='2',
 VER='1',
 LOCATION='L22',
 CDS_LIB='pure_quanta',
 CDS_PART_NAME='Q_INDUCTOR4P_12-67/320MA,320MAA',
 MATERIAL='EMPTY',
 VALUE='67/320MA',
 PRIM_FILE='W:/<user>/logical/q_inductor4p_12/chips/chips.prt';

PART_NAME
 L23 'Q_INDUCTOR4P_12-67/320MA,320MAA':;

SECTION_NUMBER 1
 '@SCM_LIB.SCM(SCH_1):PAGE29_I102@PURE_QUANTA.Q_INDUCTOR4P_12(CHIPS)':
 C_PATH='@scm_lib.scm(sch_1):page29_i102@pure_quanta.q_inductor4p_12(chips)',
 P_PATH='@scm_lib.scm(sch_1):page29_i102@pure_quanta.q_inductor4p_12(chips)',
 PATH='I102',
 DRAWING='@SCM_LIB.SCM(SCH_1):PAGE29',
 CURRENT_AMP='320MA',
 PART_TYPE='SMLF',
 PHYS_PAGE='29',
 XY='(-2400,1675)',
 ROT='6',
 VER='1',
 LOCATION='L23',
 CDS_LIB='pure_quanta',
 CDS_PART_NAME='Q_INDUCTOR4P_12-67/320MA,320MAA',
 MATERIAL='EMPTY',
 VALUE='67/320MA',
 PRIM_FILE='W:/<user>/logical/q_inductor4p_12/chips/chips.prt';

PART_NAME
 L28 'Q_INDUCTOR_SMLF-BLM18BB470/500A':;

SECTION_NUMBER 1
 '@SCM_LIB.SCM(SCH_1):PAGE23_I166@PURE_QUANTA.Q_INDUCTOR(CHIPS)':
 C_PATH='@scm_lib.scm(sch_1):page23_i166@pure_quanta.q_inductor(chips)',
 P_PATH='@scm_lib.scm(sch_1):page23_i166@pure_quanta.q_inductor(chips)',
 PATH='I166',
 DRAWING='@SCM_LIB.SCM(SCH_1):PAGE23',
 PHYS_PAGE='23',
 XY='(-75,2025)',
 ROT='0',
 VER='1',
 PACK_TYPE='SMLF',
 LOCATION='L28',
 CDS_LIB='pure_quanta',
 CDS_PART_NAME='Q_INDUCTOR_SMLF-BLM18BB470/500A',
 MATERIAL='IND',
 VALUE='BLM18BB470/500MA',
 PRIM_FILE='W:/<user>/logical/q_inductor/chips/chips.prt';

PART_NAME
 L29 'Q_INDUCTOR_SMLF-BLM18BB470/500A':;

SECTION_NUMBER 1
 '@SCM_LIB.SCM(SCH_1):PAGE23_I167@PURE_QUANTA.Q_INDUCTOR(CHIPS)':
 C_PATH='@scm_lib.scm(sch_1):page23_i167@pure_quanta.q_inductor(chips)',
 P_PATH='@scm_lib.scm(sch_1):page23_i167@pure_quanta.q_inductor(chips)',
 PATH='I167',
 DRAWING='@SCM_LIB.SCM(SCH_1):PAGE23',
 PHYS_PAGE='23',
 XY='(-75,1725)',
 ROT='0',
 VER='1',
 PACK_TYPE='SMLF',
 LOCATION='L29',
 CDS_LIB='pure_quanta',
 CDS_PART_NAME='Q_INDUCTOR_SMLF-BLM18BB470/500A',
 MATERIAL='IND',
 VALUE='BLM18BB470/500MA',
 PRIM_FILE='W:/<user>/logical/q_inductor/chips/chips.prt';

PART_NAME
 L30 'Q_INDUCTOR_SMLF-BLM18BB470/500A':;

SECTION_NUMBER 1
 '@SCM_LIB.SCM(SCH_1):PAGE23_I168@PURE_QUANTA.Q_INDUCTOR(CHIPS)':
 C_PATH='@scm_lib.scm(sch_1):page23_i168@pure_quanta.q_inductor(chips)',
 P_PATH='@scm_lib.scm(sch_1):page23_i168@pure_quanta.q_inductor(chips)',
 PATH='I168',
 DRAWING='@SCM_LIB.SCM(SCH_1):PAGE23',
 PHYS_PAGE='23',
 XY='(-75,1425)',
 ROT='0',
 VER='1',
 PACK_TYPE='SMLF',
 LOCATION='L30',
 CDS_LIB='pure_quanta',
 CDS_PART_NAME='Q_INDUCTOR_SMLF-BLM18BB470/500A',
 MATERIAL='IND',
 VALUE='BLM18BB470/500MA',
 PRIM_FILE='W:/<user>/logical/q_inductor/chips/chips.prt';

PART_NAME
 ME1 'ME_DUMMY_SYMBOL-QUANTA_LOGO_7XA':;

SECTION_NUMBER -1
 '@SCM_LIB.SCM(SCH_1):PAGE59_I27@PURE_QUANTA.ME_DUMMY_SYMBOL(CHIPS)':
 C_PATH='@scm_lib.scm(sch_1):page59_i27@pure_quanta.me_dummy_symbol(chips)',
 P_PATH='@scm_lib.scm(sch_1):page59_i27@pure_quanta.me_dummy_symbol(chips)',
 PATH='I27',
 DRAWING='@SCM_LIB.SCM(SCH_1):PAGE59',
 PIN_TEXT_VISIBLE='True',
 PIN_NAMES_ROTATE='True',
 PART_TYPE='MECH',
 PHYS_PAGE='59',
 XY='(-3125,4675)',
 ROT='0',
 VER='1',
 CDS_LIB='pure_quanta',
 CDS_PART_NAME='ME_DUMMY_SYMBOL-QUANTA_LOGO_7XA',
 MATERIAL='EMPTY',
 VALUE='QUANTA_LOGO_7X26',
 PRIM_FILE='W:/<user>/logical/me_dummy_symbol/chips/chips.prt';

PART_NAME
 ME2 'ME_DUMMY_SYMBOL-WEEE,MECH,EMPTA':;

SECTION_NUMBER -1
 '@SCM_LIB.SCM(SCH_1):PAGE59_I28@PURE_QUANTA.ME_DUMMY_SYMBOL(CHIPS)':
 C_PATH='@scm_lib.scm(sch_1):page59_i28@pure_quanta.me_dummy_symbol(chips)',
 P_PATH='@scm_lib.scm(sch_1):page59_i28@pure_quanta.me_dummy_symbol(chips)',
 PATH='I28',
 DRAWING='@SCM_LIB.SCM(SCH_1):PAGE59',
 PIN_TEXT_VISIBLE='True',
 PIN_NAMES_ROTATE='True',
 PART_TYPE='MECH',
 PHYS_PAGE='59',
 XY='(-1875,4650)',
 ROT='0',
 VER='1',
 CDS_LIB='pure_quanta',
 CDS_PART_NAME='ME_DUMMY_SYMBOL-WEEE,MECH,EMPTA',
 MATERIAL='EMPTY',
 VALUE='WEEE',
 PRIM_FILE='W:/<user>/logical/me_dummy_symbol/chips/chips.prt';

PART_NAME
 ME4 'ME_DUMMY_SYMBOL-SNLABEL_7X7,MEA':;

SECTION_NUMBER -1
 '@SCM_LIB.SCM(SCH_1):PAGE59_I34@PURE_QUANTA.ME_DUMMY_SYMBOL(CHIPS)':
 C_PATH='@scm_lib.scm(sch_1):page59_i34@pure_quanta.me_dummy_symbol(chips)',
 P_PATH='@scm_lib.scm(sch_1):page59_i34@pure_quanta.me_dummy_symbol(chips)',
 PATH='I34',
 DRAWING='@SCM_LIB.SCM(SCH_1):PAGE59',
 PIN_TEXT_VISIBLE='True',
 PIN_NAMES_ROTATE='True',
 PART_TYPE='MECH',
 PHYS_PAGE='59',
 XY='(5150,1975)',
 ROT='0',
 VER='1',
 CDS_LIB='pure_quanta',
 CDS_PART_NAME='ME_DUMMY_SYMBOL-SNLABEL_7X7,MEA',
 MATERIAL='EMPTY',
 VALUE='SNLABEL_7X7',
 PRIM_FILE='W:/<user>/logical/me_dummy_symbol/chips/chips.prt';

PART_NAME
 OSC1 'OSC4_7X25000018-25MHZ,SMLF,MISA':;

SECTION_NUMBER 1
 '@SCM_LIB.SCM(SCH_1):PAGE15_I39@PURE_QUANTA.OSC4_7X25000018(CHIPS)':
 C_PATH='@scm_lib.scm(sch_1):page15_i39@pure_quanta.osc4_7x25000018(chips)',
 P_PATH='@scm_lib.scm(sch_1):page15_i39@pure_quanta.osc4_7x25000018(chips)',
 PATH='I39',
 DRAWING='@SCM_LIB.SCM(SCH_1):PAGE15',
 PIN_NAMES_ROTATE='True',
 PART_TYPE='SMLF',
 PHYS_PAGE='15',
 XY='(575,450)',
 ROT='0',
 VER='1',
 LOCATION='OSC1',
 CDS_LIB='pure_quanta',
 CDS_PART_NAME='OSC4_7X25000018-25MHZ,SMLF,MISA',
 MATERIAL='MISC',
 VALUE='25MHZ',
 PRIM_FILE='W:/<user>/logical/osc4_7x25000018/chips/chips.prt';

PART_NAME
 OSC2 'OSC4_7X25000018-25MHZ,SMLF,MISA':;

SECTION_NUMBER 1
 '@SCM_LIB.SCM(SCH_1):PAGE34_I127@PURE_QUANTA.OSC4_7X25000018(CHIPS)':
 C_PATH='@scm_lib.scm(sch_1):page34_i127@pure_quanta.osc4_7x25000018(chips)',
 P_PATH='@scm_lib.scm(sch_1):page34_i127@pure_quanta.osc4_7x25000018(chips)',
 PATH='I127',
 DRAWING='@SCM_LIB.SCM(SCH_1):PAGE34',
 PIN_NAMES_ROTATE='True',
 PART_TYPE='SMLF',
 PHYS_PAGE='34',
 XY='(-3225,775)',
 ROT='0',
 VER='1',
 LOCATION='OSC2',
 CDS_LIB='pure_quanta',
 CDS_PART_NAME='OSC4_7X25000018-25MHZ,SMLF,MISA',
 MATERIAL='MISC',
 VALUE='25MHZ',
 PRIM_FILE='W:/<user>/logical/osc4_7x25000018/chips/chips.prt';

PART_NAME
 PC205 'Q_CAP_0402-0.1UF,25V,10%,X7R,CA':;

SECTION_NUMBER 1
 '@SCM_LIB.SCM(SCH_1):PAGE51_I1@PURE_QUANTA.Q_CAP(CHIPS)':
 C_PATH='@scm_lib.scm(sch_1):page51_i1@pure_quanta.q_cap(chips)',
 P_PATH='@scm_lib.scm(sch_1):page51_i1@pure_quanta.q_cap(chips)',
 PATH='I1',
 DRAWING='@SCM_LIB.SCM(SCH_1):PAGE51',
 SEC_TYPE='0402',
 PHYS_PAGE='51',
 XY='(-2525,500)',
 ROT='0',
 VER='1',
 PACK_TYPE='0402',
 LOCATION='PC205',
 SEC='1',
 CDS_LIB='pure_quanta',
 CDS_PART_NAME='Q_CAP_0402-0.1UF,25V,10%,X7R,CA',
 TOLERANCE='10%',
 MATERIAL='X7R',
 VOLTAGE='25V',
 VALUE='0.1UF',
 PRIM_FILE='W:/<user>/logical/q_cap/chips/chips.prt';

PART_NAME
 PC206 'Q_CAP_C0805-22UF,16V,20%,X6S,CA':;

SECTION_NUMBER 1
 '@SCM_LIB.SCM(SCH_1):PAGE51_I47@PURE_QUANTA.Q_CAP(CHIPS)':
 C_PATH='@scm_lib.scm(sch_1):page51_i47@pure_quanta.q_cap(chips)',
 P_PATH='@scm_lib.scm(sch_1):page51_i47@pure_quanta.q_cap(chips)',
 PATH='I47',
 DRAWING='@SCM_LIB.SCM(SCH_1):PAGE51',
 SEC_TYPE='C0805',
 PHYS_PAGE='51',
 XY='(-1025,1400)',
 ROT='0',
 VER='1',
 PACK_TYPE='C0805',
 LOCATION='PC206',
 SEC='1',
 CDS_LIB='pure_quanta',
 CDS_PART_NAME='Q_CAP_C0805-22UF,16V,20%,X6S,CA',
 TOLERANCE='20%',
 MATERIAL='X6S',
 VOLTAGE='16V',
 VALUE='22UF',
 PRIM_FILE='W:/<user>/logical/q_cap/chips/chips.prt';

PART_NAME
 PC207 'Q_CAP_C0805-22UF,16V,20%,X6S,CA':;

SECTION_NUMBER 1
 '@SCM_LIB.SCM(SCH_1):PAGE51_I48@PURE_QUANTA.Q_CAP(CHIPS)':
 C_PATH='@scm_lib.scm(sch_1):page51_i48@pure_quanta.q_cap(chips)',
 P_PATH='@scm_lib.scm(sch_1):page51_i48@pure_quanta.q_cap(chips)',
 PATH='I48',
 DRAWING='@SCM_LIB.SCM(SCH_1):PAGE51',
 SEC_TYPE='C0805',
 PHYS_PAGE='51',
 XY='(-650,1400)',
 ROT='0',
 VER='1',
 PACK_TYPE='C0805',
 LOCATION='PC207',
 SEC='1',
 CDS_LIB='pure_quanta',
 CDS_PART_NAME='Q_CAP_C0805-22UF,16V,20%,X6S,CA',
 TOLERANCE='20%',
 MATERIAL='X6S',
 VOLTAGE='16V',
 VALUE='22UF',
 PRIM_FILE='W:/<user>/logical/q_cap/chips/chips.prt';

PART_NAME
 PC208 'Q_CAP_C0402-1UF,25V,10%,X6S,CHA':;

SECTION_NUMBER 1
 '@SCM_LIB.SCM(SCH_1):PAGE51_I13@PURE_QUANTA.Q_CAP(CHIPS)':
 C_PATH='@scm_lib.scm(sch_1):page51_i13@pure_quanta.q_cap(chips)',
 P_PATH='@scm_lib.scm(sch_1):page51_i13@pure_quanta.q_cap(chips)',
 PATH='I13',
 DRAWING='@SCM_LIB.SCM(SCH_1):PAGE51',
 SEC_TYPE='C0402',
 PHYS_PAGE='51',
 XY='(-650,25)',
 ROT='0',
 VER='1',
 PACK_TYPE='C0402',
 LOCATION='PC208',
 SEC='1',
 CDS_LIB='pure_quanta',
 CDS_PART_NAME='Q_CAP_C0402-1UF,25V,10%,X6S,CHA',
 TOLERANCE='10%',
 MATERIAL='X6S',
 VOLTAGE='25V',
 VALUE='1UF',
 PRIM_FILE='W:/<user>/logical/q_cap/chips/chips.prt';

PART_NAME
 PC210 'Q_CAP_0402-0.1UF,25V,10%,X7R,CA':;

SECTION_NUMBER 1
 '@SCM_LIB.SCM(SCH_1):PAGE51_I45@PURE_QUANTA.Q_CAP(CHIPS)':
 C_PATH='@scm_lib.scm(sch_1):page51_i45@pure_quanta.q_cap(chips)',
 P_PATH='@scm_lib.scm(sch_1):page51_i45@pure_quanta.q_cap(chips)',
 PATH='I45',
 DRAWING='@SCM_LIB.SCM(SCH_1):PAGE51',
 SEC_TYPE='0402',
 PHYS_PAGE='51',
 XY='(-350,1400)',
 ROT='0',
 VER='1',
 PACK_TYPE='0402',
 LOCATION='PC210',
 SEC='1',
 CDS_LIB='pure_quanta',
 CDS_PART_NAME='Q_CAP_0402-0.1UF,25V,10%,X7R,CA',
 TOLERANCE='10%',
 MATERIAL='X7R',
 VOLTAGE='25V',
 VALUE='0.1UF',
 PRIM_FILE='W:/<user>/logical/q_cap/chips/chips.prt';

PART_NAME
 PC212 'Q_CAP_0402-0.1UF,25V,10%,X7R,CA':;

SECTION_NUMBER 1
 '@SCM_LIB.SCM(SCH_1):PAGE51_I31@PURE_QUANTA.Q_CAP(CHIPS)':
 C_PATH='@scm_lib.scm(sch_1):page51_i31@pure_quanta.q_cap(chips)',
 P_PATH='@scm_lib.scm(sch_1):page51_i31@pure_quanta.q_cap(chips)',
 PATH='I31',
 DRAWING='@SCM_LIB.SCM(SCH_1):PAGE51',
 SEC_TYPE='0402',
 PHYS_PAGE='51',
 XY='(3725,425)',
 ROT='0',
 VER='1',
 PACK_TYPE='0402',
 LOCATION='PC212',
 SEC='1',
 CDS_LIB='pure_quanta',
 CDS_PART_NAME='Q_CAP_0402-0.1UF,25V,10%,X7R,CA',
 TOLERANCE='10%',
 MATERIAL='X7R',
 VOLTAGE='25V',
 VALUE='0.1UF',
 PRIM_FILE='W:/<user>/logical/q_cap/chips/chips.prt';

PART_NAME
 PC213 'Q_CAP_C0805-22UF,10V,20%,X6S,CA':;

SECTION_NUMBER 1
 '@SCM_LIB.SCM(SCH_1):PAGE51_I32@PURE_QUANTA.Q_CAP(CHIPS)':
 C_PATH='@scm_lib.scm(sch_1):page51_i32@pure_quanta.q_cap(chips)',
 P_PATH='@scm_lib.scm(sch_1):page51_i32@pure_quanta.q_cap(chips)',
 PATH='I32',
 DRAWING='@SCM_LIB.SCM(SCH_1):PAGE51',
 PHYS_PAGE='51',
 XY='(4150,425)',
 ROT='0',
 VER='1',
 PACK_TYPE='C0805',
 LOCATION='PC213',
 CDS_LIB='pure_quanta',
 CDS_PART_NAME='Q_CAP_C0805-22UF,10V,20%,X6S,CA',
 TOLERANCE='20%',
 MATERIAL='X6S',
 VOLTAGE='10V',
 VALUE='22UF',
 PRIM_FILE='W:/<user>/logical/q_cap/chips/chips.prt';

PART_NAME
 PC214 'Q_CAP_C0805-22UF,10V,20%,X6S,CA':;

SECTION_NUMBER 1
 '@SCM_LIB.SCM(SCH_1):PAGE51_I33@PURE_QUANTA.Q_CAP(CHIPS)':
 C_PATH='@scm_lib.scm(sch_1):page51_i33@pure_quanta.q_cap(chips)',
 P_PATH='@scm_lib.scm(sch_1):page51_i33@pure_quanta.q_cap(chips)',
 PATH='I33',
 DRAWING='@SCM_LIB.SCM(SCH_1):PAGE51',
 PHYS_PAGE='51',
 XY='(4500,425)',
 ROT='0',
 VER='1',
 PACK_TYPE='C0805',
 LOCATION='PC214',
 CDS_LIB='pure_quanta',
 CDS_PART_NAME='Q_CAP_C0805-22UF,10V,20%,X6S,CA',
 TOLERANCE='20%',
 MATERIAL='X6S',
 VOLTAGE='10V',
 VALUE='22UF',
 PRIM_FILE='W:/<user>/logical/q_cap/chips/chips.prt';

PART_NAME
 PC215 'Q_CAP_C0805-22UF,10V,20%,X6S,CA':;

SECTION_NUMBER 1
 '@SCM_LIB.SCM(SCH_1):PAGE51_I36@PURE_QUANTA.Q_CAP(CHIPS)':
 C_PATH='@scm_lib.scm(sch_1):page51_i36@pure_quanta.q_cap(chips)',
 P_PATH='@scm_lib.scm(sch_1):page51_i36@pure_quanta.q_cap(chips)',
 PATH='I36',
 DRAWING='@SCM_LIB.SCM(SCH_1):PAGE51',
 PHYS_PAGE='51',
 XY='(4825,425)',
 ROT='0',
 VER='1',
 PACK_TYPE='C0805',
 LOCATION='PC215',
 CDS_LIB='pure_quanta',
 CDS_PART_NAME='Q_CAP_C0805-22UF,10V,20%,X6S,CA',
 TOLERANCE='20%',
 MATERIAL='X6S',
 VOLTAGE='10V',
 VALUE='22UF',
 PRIM_FILE='W:/<user>/logical/q_cap/chips/chips.prt';

PART_NAME
 PC216 'Q_CAP_0402-0.22UF,16V,10%,X7R,A':;

SECTION_NUMBER 1
 '@SCM_LIB.SCM(SCH_1):PAGE51_I23@PURE_QUANTA.Q_CAP(CHIPS)':
 C_PATH='@scm_lib.scm(sch_1):page51_i23@pure_quanta.q_cap(chips)',
 P_PATH='@scm_lib.scm(sch_1):page51_i23@pure_quanta.q_cap(chips)',
 PATH='I23',
 DRAWING='@SCM_LIB.SCM(SCH_1):PAGE51',
 SEC_TYPE='0402',
 PHYS_PAGE='51',
 XY='(1975,825)',
 ROT='0',
 VER='1',
 PACK_TYPE='0402',
 LOCATION='PC216',
 SEC='1',
 CDS_LIB='pure_quanta',
 CDS_PART_NAME='Q_CAP_0402-0.22UF,16V,10%,X7R,A',
 TOLERANCE='10%',
 MATERIAL='X7R',
 VOLTAGE='16V',
 VALUE='0.22UF',
 PRIM_FILE='W:/<user>/logical/q_cap/chips/chips.prt';

PART_NAME
 PC217 'Q_CAP_C0805-22UF,10V,20%,X6S,CA':;

SECTION_NUMBER 1
 '@SCM_LIB.SCM(SCH_1):PAGE51_I37@PURE_QUANTA.Q_CAP(CHIPS)':
 C_PATH='@scm_lib.scm(sch_1):page51_i37@pure_quanta.q_cap(chips)',
 P_PATH='@scm_lib.scm(sch_1):page51_i37@pure_quanta.q_cap(chips)',
 PATH='I37',
 DRAWING='@SCM_LIB.SCM(SCH_1):PAGE51',
 PHYS_PAGE='51',
 XY='(5175,425)',
 ROT='0',
 VER='1',
 PACK_TYPE='C0805',
 LOCATION='PC217',
 CDS_LIB='pure_quanta',
 CDS_PART_NAME='Q_CAP_C0805-22UF,10V,20%,X6S,CA',
 TOLERANCE='20%',
 MATERIAL='X6S',
 VOLTAGE='10V',
 VALUE='22UF',
 PRIM_FILE='W:/<user>/logical/q_cap/chips/chips.prt';

PART_NAME
 PC218 'Q_CAP_C0805-22UF,16V,20%,X6S,CA':;

SECTION_NUMBER 1
 '@SCM_LIB.SCM(SCH_1):PAGE52_I81@PURE_QUANTA.Q_CAP(CHIPS)':
 C_PATH='@scm_lib.scm(sch_1):page52_i81@pure_quanta.q_cap(chips)',
 P_PATH='@scm_lib.scm(sch_1):page52_i81@pure_quanta.q_cap(chips)',
 PATH='I81',
 DRAWING='@SCM_LIB.SCM(SCH_1):PAGE52',
 SEC_TYPE='C0805',
 PHYS_PAGE='52',
 XY='(-1725,2050)',
 ROT='0',
 VER='1',
 PACK_TYPE='C0805',
 LOCATION='PC218',
 SEC='1',
 CDS_LIB='pure_quanta',
 CDS_PART_NAME='Q_CAP_C0805-22UF,16V,20%,X6S,CA',
 TOLERANCE='20%',
 MATERIAL='X6S',
 VOLTAGE='16V',
 VALUE='22UF',
 PRIM_FILE='W:/<user>/logical/q_cap/chips/chips.prt';

PART_NAME
 PC219 'Q_CAP_C0805-22UF,16V,20%,X6S,CA':;

SECTION_NUMBER 1
 '@SCM_LIB.SCM(SCH_1):PAGE52_I80@PURE_QUANTA.Q_CAP(CHIPS)':
 C_PATH='@scm_lib.scm(sch_1):page52_i80@pure_quanta.q_cap(chips)',
 P_PATH='@scm_lib.scm(sch_1):page52_i80@pure_quanta.q_cap(chips)',
 PATH='I80',
 DRAWING='@SCM_LIB.SCM(SCH_1):PAGE52',
 SEC_TYPE='C0805',
 PHYS_PAGE='52',
 XY='(-2125,2050)',
 ROT='0',
 VER='1',
 PACK_TYPE='C0805',
 LOCATION='PC219',
 SEC='1',
 CDS_LIB='pure_quanta',
 CDS_PART_NAME='Q_CAP_C0805-22UF,16V,20%,X6S,CA',
 TOLERANCE='20%',
 MATERIAL='X6S',
 VOLTAGE='16V',
 VALUE='22UF',
 PRIM_FILE='W:/<user>/logical/q_cap/chips/chips.prt';

PART_NAME
 PC221 'Q_CAP_C0402-1UF,25V,10%,X6S,CHA':;

SECTION_NUMBER 1
 '@SCM_LIB.SCM(SCH_1):PAGE52_I9@PURE_QUANTA.Q_CAP(CHIPS)':
 C_PATH='@scm_lib.scm(sch_1):page52_i9@pure_quanta.q_cap(chips)',
 P_PATH='@scm_lib.scm(sch_1):page52_i9@pure_quanta.q_cap(chips)',
 PATH='I9',
 DRAWING='@SCM_LIB.SCM(SCH_1):PAGE52',
 SEC_TYPE='C0402',
 PHYS_PAGE='52',
 XY='(-1600,500)',
 ROT='0',
 VER='1',
 PACK_TYPE='C0402',
 LOCATION='PC221',
 SEC='1',
 CDS_LIB='pure_quanta',
 CDS_PART_NAME='Q_CAP_C0402-1UF,25V,10%,X6S,CHA',
 TOLERANCE='10%',
 MATERIAL='X6S',
 VOLTAGE='25V',
 VALUE='1UF',
 PRIM_FILE='W:/<user>/logical/q_cap/chips/chips.prt';

PART_NAME
 PC223 'Q_CAP_0402-0.1UF,25V,10%,X7R,CA':;

SECTION_NUMBER 1
 '@SCM_LIB.SCM(SCH_1):PAGE52_I11@PURE_QUANTA.Q_CAP(CHIPS)':
 C_PATH='@scm_lib.scm(sch_1):page52_i11@pure_quanta.q_cap(chips)',
 P_PATH='@scm_lib.scm(sch_1):page52_i11@pure_quanta.q_cap(chips)',
 PATH='I11',
 DRAWING='@SCM_LIB.SCM(SCH_1):PAGE52',
 SEC_TYPE='0402',
 PHYS_PAGE='52',
 XY='(-1175,2050)',
 ROT='0',
 VER='1',
 PACK_TYPE='0402',
 LOCATION='PC223',
 SEC='1',
 CDS_LIB='pure_quanta',
 CDS_PART_NAME='Q_CAP_0402-0.1UF,25V,10%,X7R,CA',
 TOLERANCE='10%',
 MATERIAL='X7R',
 VOLTAGE='25V',
 VALUE='0.1UF',
 PRIM_FILE='W:/<user>/logical/q_cap/chips/chips.prt';

PART_NAME
 PC224 'Q_CAP_0402-0.22UF,16V,10%,X7R,A':;

SECTION_NUMBER 1
 '@SCM_LIB.SCM(SCH_1):PAGE52_I15@PURE_QUANTA.Q_CAP(CHIPS)':
 C_PATH='@scm_lib.scm(sch_1):page52_i15@pure_quanta.q_cap(chips)',
 P_PATH='@scm_lib.scm(sch_1):page52_i15@pure_quanta.q_cap(chips)',
 PATH='I15',
 DRAWING='@SCM_LIB.SCM(SCH_1):PAGE52',
 SEC_TYPE='0402',
 PHYS_PAGE='52',
 XY='(1350,1475)',
 ROT='0',
 VER='1',
 PACK_TYPE='0402',
 LOCATION='PC224',
 SEC='1',
 CDS_LIB='pure_quanta',
 CDS_PART_NAME='Q_CAP_0402-0.22UF,16V,10%,X7R,A',
 TOLERANCE='10%',
 MATERIAL='X7R',
 VOLTAGE='16V',
 VALUE='0.22UF',
 PRIM_FILE='W:/<user>/logical/q_cap/chips/chips.prt';

PART_NAME
 PC225 'Q_CAP_0402-0.1UF,25V,10%,X7R,CA':;

SECTION_NUMBER 1
 '@SCM_LIB.SCM(SCH_1):PAGE52_I23@PURE_QUANTA.Q_CAP(CHIPS)':
 C_PATH='@scm_lib.scm(sch_1):page52_i23@pure_quanta.q_cap(chips)',
 P_PATH='@scm_lib.scm(sch_1):page52_i23@pure_quanta.q_cap(chips)',
 PATH='I23',
 DRAWING='@SCM_LIB.SCM(SCH_1):PAGE52',
 SEC_TYPE='0402',
 PHYS_PAGE='52',
 XY='(3175,1075)',
 ROT='0',
 VER='1',
 PACK_TYPE='0402',
 LOCATION='PC225',
 SEC='1',
 CDS_LIB='pure_quanta',
 CDS_PART_NAME='Q_CAP_0402-0.1UF,25V,10%,X7R,CA',
 TOLERANCE='10%',
 MATERIAL='X7R',
 VOLTAGE='25V',
 VALUE='0.1UF',
 PRIM_FILE='W:/<user>/logical/q_cap/chips/chips.prt';

PART_NAME
 PC226 'Q_CAP_C0805-22UF,10V,20%,X6S,CA':;

SECTION_NUMBER 1
 '@SCM_LIB.SCM(SCH_1):PAGE52_I35@PURE_QUANTA.Q_CAP(CHIPS)':
 C_PATH='@scm_lib.scm(sch_1):page52_i35@pure_quanta.q_cap(chips)',
 P_PATH='@scm_lib.scm(sch_1):page52_i35@pure_quanta.q_cap(chips)',
 PATH='I35',
 DRAWING='@SCM_LIB.SCM(SCH_1):PAGE52',
 PHYS_PAGE='52',
 XY='(3650,1075)',
 ROT='0',
 VER='1',
 PACK_TYPE='C0805',
 LOCATION='PC226',
 CDS_LIB='pure_quanta',
 CDS_PART_NAME='Q_CAP_C0805-22UF,10V,20%,X6S,CA',
 TOLERANCE='20%',
 MATERIAL='X6S',
 VOLTAGE='10V',
 VALUE='22UF',
 PRIM_FILE='W:/<user>/logical/q_cap/chips/chips.prt';

PART_NAME
 PC227 'Q_CAP_C0805-22UF,10V,20%,X6S,CA':;

SECTION_NUMBER 1
 '@SCM_LIB.SCM(SCH_1):PAGE52_I36@PURE_QUANTA.Q_CAP(CHIPS)':
 C_PATH='@scm_lib.scm(sch_1):page52_i36@pure_quanta.q_cap(chips)',
 P_PATH='@scm_lib.scm(sch_1):page52_i36@pure_quanta.q_cap(chips)',
 PATH='I36',
 DRAWING='@SCM_LIB.SCM(SCH_1):PAGE52',
 PHYS_PAGE='52',
 XY='(4000,1075)',
 ROT='0',
 VER='1',
 PACK_TYPE='C0805',
 LOCATION='PC227',
 CDS_LIB='pure_quanta',
 CDS_PART_NAME='Q_CAP_C0805-22UF,10V,20%,X6S,CA',
 TOLERANCE='20%',
 MATERIAL='X6S',
 VOLTAGE='10V',
 VALUE='22UF',
 PRIM_FILE='W:/<user>/logical/q_cap/chips/chips.prt';

PART_NAME
 PC228 'Q_CAP_C0805-22UF,10V,20%,X6S,CA':;

SECTION_NUMBER 1
 '@SCM_LIB.SCM(SCH_1):PAGE52_I37@PURE_QUANTA.Q_CAP(CHIPS)':
 C_PATH='@scm_lib.scm(sch_1):page52_i37@pure_quanta.q_cap(chips)',
 P_PATH='@scm_lib.scm(sch_1):page52_i37@pure_quanta.q_cap(chips)',
 PATH='I37',
 DRAWING='@SCM_LIB.SCM(SCH_1):PAGE52',
 PHYS_PAGE='52',
 XY='(4325,1075)',
 ROT='0',
 VER='1',
 PACK_TYPE='C0805',
 LOCATION='PC228',
 CDS_LIB='pure_quanta',
 CDS_PART_NAME='Q_CAP_C0805-22UF,10V,20%,X6S,CA',
 TOLERANCE='20%',
 MATERIAL='X6S',
 VOLTAGE='10V',
 VALUE='22UF',
 PRIM_FILE='W:/<user>/logical/q_cap/chips/chips.prt';

PART_NAME
 PC229 'Q_CAP_C0805-22UF,10V,20%,X6S,CA':;

SECTION_NUMBER 1
 '@SCM_LIB.SCM(SCH_1):PAGE52_I38@PURE_QUANTA.Q_CAP(CHIPS)':
 C_PATH='@scm_lib.scm(sch_1):page52_i38@pure_quanta.q_cap(chips)',
 P_PATH='@scm_lib.scm(sch_1):page52_i38@pure_quanta.q_cap(chips)',
 PATH='I38',
 DRAWING='@SCM_LIB.SCM(SCH_1):PAGE52',
 PHYS_PAGE='52',
 XY='(4650,1075)',
 ROT='0',
 VER='1',
 PACK_TYPE='C0805',
 LOCATION='PC229',
 CDS_LIB='pure_quanta',
 CDS_PART_NAME='Q_CAP_C0805-22UF,10V,20%,X6S,CA',
 TOLERANCE='20%',
 MATERIAL='X6S',
 VOLTAGE='10V',
 VALUE='22UF',
 PRIM_FILE='W:/<user>/logical/q_cap/chips/chips.prt';

PART_NAME
 PC239 'Q_CAP_0402-100PF,50V,5%,NPO,CHA':;

SECTION_NUMBER 1
 '@SCM_LIB.SCM(SCH_1):PAGE52_I91@PURE_QUANTA.Q_CAP(CHIPS)':
 C_PATH='@scm_lib.scm(sch_1):page52_i91@pure_quanta.q_cap(chips)',
 P_PATH='@scm_lib.scm(sch_1):page52_i91@pure_quanta.q_cap(chips)',
 PATH='I91',
 DRAWING='@SCM_LIB.SCM(SCH_1):PAGE52',
 PHYS_PAGE='52',
 XY='(3200,125)',
 ROT='0',
 VER='2',
 PACK_TYPE='0402',
 LOCATION='PC239',
 CDS_LIB='pure_quanta',
 CDS_PART_NAME='Q_CAP_0402-100PF,50V,5%,NPO,CHA',
 TOLERANCE='5%',
 MATERIAL='NPO',
 VOLTAGE='50V',
 VALUE='100PF',
 PRIM_FILE='W:/<user>/logical/q_cap/chips/chips.prt';

PART_NAME
 PC250 'Q_CAP_C0402-1UF,25V,10%,X6S,CHA':;

SECTION_NUMBER 1
 '@SCM_LIB.SCM(SCH_1):PAGE55_I7@PURE_QUANTA.Q_CAP(CHIPS)':
 C_PATH='@scm_lib.scm(sch_1):page55_i7@pure_quanta.q_cap(chips)',
 P_PATH='@scm_lib.scm(sch_1):page55_i7@pure_quanta.q_cap(chips)',
 PATH='I7',
 DRAWING='@SCM_LIB.SCM(SCH_1):PAGE55',
 SEC_TYPE='C0402',
 PHYS_PAGE='55',
 XY='(-3575,-225)',
 ROT='0',
 VER='1',
 PACK_TYPE='C0402',
 LOCATION='PC250',
 SEC='1',
 CDS_LIB='pure_quanta',
 CDS_PART_NAME='Q_CAP_C0402-1UF,25V,10%,X6S,CHA',
 TOLERANCE='10%',
 MATERIAL='X6S',
 VOLTAGE='25V',
 VALUE='1UF',
 PRIM_FILE='W:/<user>/logical/q_cap/chips/chips.prt';

PART_NAME
 PC251 'Q_CAP_C0805-10UF,25V,10%,X6S,CA':;

SECTION_NUMBER 1
 '@SCM_LIB.SCM(SCH_1):PAGE55_I43@PURE_QUANTA.Q_CAP(CHIPS)':
 C_PATH='@scm_lib.scm(sch_1):page55_i43@pure_quanta.q_cap(chips)',
 P_PATH='@scm_lib.scm(sch_1):page55_i43@pure_quanta.q_cap(chips)',
 PATH='I43',
 DRAWING='@SCM_LIB.SCM(SCH_1):PAGE55',
 PHYS_PAGE='55',
 XY='(-1725,1300)',
 ROT='0',
 VER='1',
 PACK_TYPE='C0805',
 LOCATION='PC251',
 CDS_LIB='pure_quanta',
 CDS_PART_NAME='Q_CAP_C0805-10UF,25V,10%,X6S,CA',
 TOLERANCE='10%',
 MATERIAL='X6S',
 VOLTAGE='25V',
 VALUE='10UF',
 PRIM_FILE='W:/<user>/logical/q_cap/chips/chips.prt';

PART_NAME
 PC252 'Q_CAP_C0805-10UF,25V,10%,X6S,CA':;

SECTION_NUMBER 1
 '@SCM_LIB.SCM(SCH_1):PAGE55_I42@PURE_QUANTA.Q_CAP(CHIPS)':
 C_PATH='@scm_lib.scm(sch_1):page55_i42@pure_quanta.q_cap(chips)',
 P_PATH='@scm_lib.scm(sch_1):page55_i42@pure_quanta.q_cap(chips)',
 PATH='I42',
 DRAWING='@SCM_LIB.SCM(SCH_1):PAGE55',
 PHYS_PAGE='55',
 XY='(-2125,1300)',
 ROT='0',
 VER='1',
 PACK_TYPE='C0805',
 LOCATION='PC252',
 CDS_LIB='pure_quanta',
 CDS_PART_NAME='Q_CAP_C0805-10UF,25V,10%,X6S,CA',
 TOLERANCE='10%',
 MATERIAL='X6S',
 VOLTAGE='25V',
 VALUE='10UF',
 PRIM_FILE='W:/<user>/logical/q_cap/chips/chips.prt';

PART_NAME
 PC253 'Q_CAP_0402-0.1UF,25V,10%,X7R,CA':;

SECTION_NUMBER 1
 '@SCM_LIB.SCM(SCH_1):PAGE55_I16@PURE_QUANTA.Q_CAP(CHIPS)':
 C_PATH='@scm_lib.scm(sch_1):page55_i16@pure_quanta.q_cap(chips)',
 P_PATH='@scm_lib.scm(sch_1):page55_i16@pure_quanta.q_cap(chips)',
 PATH='I16',
 DRAWING='@SCM_LIB.SCM(SCH_1):PAGE55',
 SEC_TYPE='0402',
 PHYS_PAGE='55',
 XY='(-1175,1300)',
 ROT='0',
 VER='1',
 PACK_TYPE='0402',
 LOCATION='PC253',
 SEC='1',
 CDS_LIB='pure_quanta',
 CDS_PART_NAME='Q_CAP_0402-0.1UF,25V,10%,X7R,CA',
 TOLERANCE='10%',
 MATERIAL='X7R',
 VOLTAGE='25V',
 VALUE='0.1UF',
 PRIM_FILE='W:/<user>/logical/q_cap/chips/chips.prt';

PART_NAME
 PC254 'Q_CAP_0402-0.22UF,16V,10%,X7R,A':;

SECTION_NUMBER 1
 '@SCM_LIB.SCM(SCH_1):PAGE55_I19@PURE_QUANTA.Q_CAP(CHIPS)':
 C_PATH='@scm_lib.scm(sch_1):page55_i19@pure_quanta.q_cap(chips)',
 P_PATH='@scm_lib.scm(sch_1):page55_i19@pure_quanta.q_cap(chips)',
 PATH='I19',
 DRAWING='@SCM_LIB.SCM(SCH_1):PAGE55',
 SEC_TYPE='0402',
 PHYS_PAGE='55',
 XY='(875,725)',
 ROT='0',
 VER='1',
 PACK_TYPE='0402',
 LOCATION='PC254',
 SEC='1',
 CDS_LIB='pure_quanta',
 CDS_PART_NAME='Q_CAP_0402-0.22UF,16V,10%,X7R,A',
 TOLERANCE='10%',
 MATERIAL='X7R',
 VOLTAGE='16V',
 VALUE='0.22UF',
 PRIM_FILE='W:/<user>/logical/q_cap/chips/chips.prt';

PART_NAME
 PC255 'Q_CAP_0402-0.1UF,25V,10%,X7R,CA':;

SECTION_NUMBER 1
 '@SCM_LIB.SCM(SCH_1):PAGE55_I23@PURE_QUANTA.Q_CAP(CHIPS)':
 C_PATH='@scm_lib.scm(sch_1):page55_i23@pure_quanta.q_cap(chips)',
 P_PATH='@scm_lib.scm(sch_1):page55_i23@pure_quanta.q_cap(chips)',
 PATH='I23',
 DRAWING='@SCM_LIB.SCM(SCH_1):PAGE55',
 SEC_TYPE='0402',
 PHYS_PAGE='55',
 XY='(2625,325)',
 ROT='0',
 VER='1',
 PACK_TYPE='0402',
 LOCATION='PC255',
 SEC='1',
 CDS_LIB='pure_quanta',
 CDS_PART_NAME='Q_CAP_0402-0.1UF,25V,10%,X7R,CA',
 TOLERANCE='10%',
 MATERIAL='X7R',
 VOLTAGE='25V',
 VALUE='0.1UF',
 PRIM_FILE='W:/<user>/logical/q_cap/chips/chips.prt';

PART_NAME
 PC256 'Q_CAP_0805-22UF,4V,20%,X6S,TMPA':;

SECTION_NUMBER 1
 '@SCM_LIB.SCM(SCH_1):PAGE55_I24@PURE_QUANTA.Q_CAP(CHIPS)':
 C_PATH='@scm_lib.scm(sch_1):page55_i24@pure_quanta.q_cap(chips)',
 P_PATH='@scm_lib.scm(sch_1):page55_i24@pure_quanta.q_cap(chips)',
 PATH='I24',
 DRAWING='@SCM_LIB.SCM(SCH_1):PAGE55',
 SEC_TYPE='0805',
 PHYS_PAGE='55',
 XY='(3175,325)',
 ROT='0',
 VER='1',
 PACK_TYPE='0805',
 LOCATION='PC256',
 SEC='1',
 CDS_LIB='pure_quanta',
 CDS_PART_NAME='Q_CAP_0805-22UF,4V,20%,X6S,TMPA',
 TOLERANCE='20%',
 MATERIAL='X6S',
 VOLTAGE='4V',
 VALUE='22UF',
 PRIM_FILE='W:/<user>/logical/q_cap/chips/chips.prt';

PART_NAME
 PC257 'Q_CAP_0805-22UF,4V,20%,X6S,TMPA':;

SECTION_NUMBER 1
 '@SCM_LIB.SCM(SCH_1):PAGE55_I25@PURE_QUANTA.Q_CAP(CHIPS)':
 C_PATH='@scm_lib.scm(sch_1):page55_i25@pure_quanta.q_cap(chips)',
 P_PATH='@scm_lib.scm(sch_1):page55_i25@pure_quanta.q_cap(chips)',
 PATH='I25',
 DRAWING='@SCM_LIB.SCM(SCH_1):PAGE55',
 SEC_TYPE='0805',
 PHYS_PAGE='55',
 XY='(3425,325)',
 ROT='0',
 VER='1',
 PACK_TYPE='0805',
 LOCATION='PC257',
 SEC='1',
 CDS_LIB='pure_quanta',
 CDS_PART_NAME='Q_CAP_0805-22UF,4V,20%,X6S,TMPA',
 TOLERANCE='20%',
 MATERIAL='X6S',
 VOLTAGE='4V',
 VALUE='22UF',
 PRIM_FILE='W:/<user>/logical/q_cap/chips/chips.prt';

PART_NAME
 PC258 'Q_CAP_0805-22UF,4V,20%,X6S,TMPA':;

SECTION_NUMBER 1
 '@SCM_LIB.SCM(SCH_1):PAGE55_I28@PURE_QUANTA.Q_CAP(CHIPS)':
 C_PATH='@scm_lib.scm(sch_1):page55_i28@pure_quanta.q_cap(chips)',
 P_PATH='@scm_lib.scm(sch_1):page55_i28@pure_quanta.q_cap(chips)',
 PATH='I28',
 DRAWING='@SCM_LIB.SCM(SCH_1):PAGE55',
 SEC_TYPE='0805',
 PHYS_PAGE='55',
 XY='(3675,325)',
 ROT='0',
 VER='1',
 PACK_TYPE='0805',
 LOCATION='PC258',
 SEC='1',
 CDS_LIB='pure_quanta',
 CDS_PART_NAME='Q_CAP_0805-22UF,4V,20%,X6S,TMPA',
 TOLERANCE='20%',
 MATERIAL='X6S',
 VOLTAGE='4V',
 VALUE='22UF',
 PRIM_FILE='W:/<user>/logical/q_cap/chips/chips.prt';

PART_NAME
 PC259 'Q_CAP_0805-22UF,4V,20%,X6S,TMPA':;

SECTION_NUMBER 1
 '@SCM_LIB.SCM(SCH_1):PAGE55_I29@PURE_QUANTA.Q_CAP(CHIPS)':
 C_PATH='@scm_lib.scm(sch_1):page55_i29@pure_quanta.q_cap(chips)',
 P_PATH='@scm_lib.scm(sch_1):page55_i29@pure_quanta.q_cap(chips)',
 PATH='I29',
 DRAWING='@SCM_LIB.SCM(SCH_1):PAGE55',
 SEC_TYPE='0805',
 PHYS_PAGE='55',
 XY='(3925,325)',
 ROT='0',
 VER='1',
 PACK_TYPE='0805',
 LOCATION='PC259',
 SEC='1',
 CDS_LIB='pure_quanta',
 CDS_PART_NAME='Q_CAP_0805-22UF,4V,20%,X6S,TMPA',
 TOLERANCE='20%',
 MATERIAL='X6S',
 VOLTAGE='4V',
 VALUE='22UF',
 PRIM_FILE='W:/<user>/logical/q_cap/chips/chips.prt';

PART_NAME
 PC260 'Q_CAP_C0402-1UF,25V,10%,X6S,CHA':;

SECTION_NUMBER 1
 '@SCM_LIB.SCM(SCH_1):PAGE56_I7@PURE_QUANTA.Q_CAP(CHIPS)':
 C_PATH='@scm_lib.scm(sch_1):page56_i7@pure_quanta.q_cap(chips)',
 P_PATH='@scm_lib.scm(sch_1):page56_i7@pure_quanta.q_cap(chips)',
 PATH='I7',
 DRAWING='@SCM_LIB.SCM(SCH_1):PAGE56',
 SEC_TYPE='C0402',
 PHYS_PAGE='56',
 XY='(-4025,-500)',
 ROT='0',
 VER='1',
 PACK_TYPE='C0402',
 LOCATION='PC260',
 SEC='1',
 CDS_LIB='pure_quanta',
 CDS_PART_NAME='Q_CAP_C0402-1UF,25V,10%,X6S,CHA',
 TOLERANCE='10%',
 MATERIAL='X6S',
 VOLTAGE='25V',
 VALUE='1UF',
 PRIM_FILE='W:/<user>/logical/q_cap/chips/chips.prt';

PART_NAME
 PC261 'Q_CAP_C0805-10UF,25V,10%,X6S,CA':;

SECTION_NUMBER 1
 '@SCM_LIB.SCM(SCH_1):PAGE56_I44@PURE_QUANTA.Q_CAP(CHIPS)':
 C_PATH='@scm_lib.scm(sch_1):page56_i44@pure_quanta.q_cap(chips)',
 P_PATH='@scm_lib.scm(sch_1):page56_i44@pure_quanta.q_cap(chips)',
 PATH='I44',
 DRAWING='@SCM_LIB.SCM(SCH_1):PAGE56',
 PHYS_PAGE='56',
 XY='(-3575,1050)',
 ROT='0',
 VER='1',
 PACK_TYPE='C0805',
 LOCATION='PC261',
 CDS_LIB='pure_quanta',
 CDS_PART_NAME='Q_CAP_C0805-10UF,25V,10%,X6S,CA',
 TOLERANCE='10%',
 MATERIAL='X6S',
 VOLTAGE='25V',
 VALUE='10UF',
 PRIM_FILE='W:/<user>/logical/q_cap/chips/chips.prt';

PART_NAME
 PC262 'Q_CAP_C0805-10UF,25V,10%,X6S,CA':;

SECTION_NUMBER 1
 '@SCM_LIB.SCM(SCH_1):PAGE56_I43@PURE_QUANTA.Q_CAP(CHIPS)':
 C_PATH='@scm_lib.scm(sch_1):page56_i43@pure_quanta.q_cap(chips)',
 P_PATH='@scm_lib.scm(sch_1):page56_i43@pure_quanta.q_cap(chips)',
 PATH='I43',
 DRAWING='@SCM_LIB.SCM(SCH_1):PAGE56',
 PHYS_PAGE='56',
 XY='(-3975,1050)',
 ROT='0',
 VER='1',
 PACK_TYPE='C0805',
 LOCATION='PC262',
 CDS_LIB='pure_quanta',
 CDS_PART_NAME='Q_CAP_C0805-10UF,25V,10%,X6S,CA',
 TOLERANCE='10%',
 MATERIAL='X6S',
 VOLTAGE='25V',
 VALUE='10UF',
 PRIM_FILE='W:/<user>/logical/q_cap/chips/chips.prt';

PART_NAME
 PC263 'Q_CAP_0402-0.1UF,25V,10%,X7R,CA':;

SECTION_NUMBER 1
 '@SCM_LIB.SCM(SCH_1):PAGE56_I16@PURE_QUANTA.Q_CAP(CHIPS)':
 C_PATH='@scm_lib.scm(sch_1):page56_i16@pure_quanta.q_cap(chips)',
 P_PATH='@scm_lib.scm(sch_1):page56_i16@pure_quanta.q_cap(chips)',
 PATH='I16',
 DRAWING='@SCM_LIB.SCM(SCH_1):PAGE56',
 SEC_TYPE='0402',
 PHYS_PAGE='56',
 XY='(-3025,1050)',
 ROT='0',
 VER='1',
 PACK_TYPE='0402',
 LOCATION='PC263',
 SEC='1',
 CDS_LIB='pure_quanta',
 CDS_PART_NAME='Q_CAP_0402-0.1UF,25V,10%,X7R,CA',
 TOLERANCE='10%',
 MATERIAL='X7R',
 VOLTAGE='25V',
 VALUE='0.1UF',
 PRIM_FILE='W:/<user>/logical/q_cap/chips/chips.prt';

PART_NAME
 PC264 'Q_CAP_0402-0.22UF,16V,10%,X7R,A':;

SECTION_NUMBER 1
 '@SCM_LIB.SCM(SCH_1):PAGE56_I19@PURE_QUANTA.Q_CAP(CHIPS)':
 C_PATH='@scm_lib.scm(sch_1):page56_i19@pure_quanta.q_cap(chips)',
 P_PATH='@scm_lib.scm(sch_1):page56_i19@pure_quanta.q_cap(chips)',
 PATH='I19',
 DRAWING='@SCM_LIB.SCM(SCH_1):PAGE56',
 SEC_TYPE='0402',
 PHYS_PAGE='56',
 XY='(-975,475)',
 ROT='0',
 VER='1',
 PACK_TYPE='0402',
 LOCATION='PC264',
 SEC='1',
 CDS_LIB='pure_quanta',
 CDS_PART_NAME='Q_CAP_0402-0.22UF,16V,10%,X7R,A',
 TOLERANCE='10%',
 MATERIAL='X7R',
 VOLTAGE='16V',
 VALUE='0.22UF',
 PRIM_FILE='W:/<user>/logical/q_cap/chips/chips.prt';

PART_NAME
 PC266 'Q_CAP_0402-0.1UF,25V,10%,X7R,CA':;

SECTION_NUMBER 1
 '@SCM_LIB.SCM(SCH_1):PAGE56_I23@PURE_QUANTA.Q_CAP(CHIPS)':
 C_PATH='@scm_lib.scm(sch_1):page56_i23@pure_quanta.q_cap(chips)',
 P_PATH='@scm_lib.scm(sch_1):page56_i23@pure_quanta.q_cap(chips)',
 PATH='I23',
 DRAWING='@SCM_LIB.SCM(SCH_1):PAGE56',
 SEC_TYPE='0402',
 PHYS_PAGE='56',
 XY='(775,75)',
 ROT='0',
 VER='1',
 PACK_TYPE='0402',
 LOCATION='PC266',
 SEC='1',
 CDS_LIB='pure_quanta',
 CDS_PART_NAME='Q_CAP_0402-0.1UF,25V,10%,X7R,CA',
 TOLERANCE='10%',
 MATERIAL='X7R',
 VOLTAGE='25V',
 VALUE='0.1UF',
 PRIM_FILE='W:/<user>/logical/q_cap/chips/chips.prt';

PART_NAME
 PC267 'Q_CAP_0805-22UF,4V,20%,X6S,TMPA':;

SECTION_NUMBER 1
 '@SCM_LIB.SCM(SCH_1):PAGE56_I24@PURE_QUANTA.Q_CAP(CHIPS)':
 C_PATH='@scm_lib.scm(sch_1):page56_i24@pure_quanta.q_cap(chips)',
 P_PATH='@scm_lib.scm(sch_1):page56_i24@pure_quanta.q_cap(chips)',
 PATH='I24',
 DRAWING='@SCM_LIB.SCM(SCH_1):PAGE56',
 SEC_TYPE='0805',
 PHYS_PAGE='56',
 XY='(1325,75)',
 ROT='0',
 VER='1',
 PACK_TYPE='0805',
 LOCATION='PC267',
 SEC='1',
 CDS_LIB='pure_quanta',
 CDS_PART_NAME='Q_CAP_0805-22UF,4V,20%,X6S,TMPA',
 TOLERANCE='20%',
 MATERIAL='X6S',
 VOLTAGE='4V',
 VALUE='22UF',
 PRIM_FILE='W:/<user>/logical/q_cap/chips/chips.prt';

PART_NAME
 PC268 'Q_CAP_0805-22UF,4V,20%,X6S,TMPA':;

SECTION_NUMBER 1
 '@SCM_LIB.SCM(SCH_1):PAGE56_I25@PURE_QUANTA.Q_CAP(CHIPS)':
 C_PATH='@scm_lib.scm(sch_1):page56_i25@pure_quanta.q_cap(chips)',
 P_PATH='@scm_lib.scm(sch_1):page56_i25@pure_quanta.q_cap(chips)',
 PATH='I25',
 DRAWING='@SCM_LIB.SCM(SCH_1):PAGE56',
 SEC_TYPE='0805',
 PHYS_PAGE='56',
 XY='(1575,75)',
 ROT='0',
 VER='1',
 PACK_TYPE='0805',
 LOCATION='PC268',
 SEC='1',
 CDS_LIB='pure_quanta',
 CDS_PART_NAME='Q_CAP_0805-22UF,4V,20%,X6S,TMPA',
 TOLERANCE='20%',
 MATERIAL='X6S',
 VOLTAGE='4V',
 VALUE='22UF',
 PRIM_FILE='W:/<user>/logical/q_cap/chips/chips.prt';

PART_NAME
 PC269 'Q_CAP_0805-22UF,4V,20%,X6S,TMPA':;

SECTION_NUMBER 1
 '@SCM_LIB.SCM(SCH_1):PAGE56_I28@PURE_QUANTA.Q_CAP(CHIPS)':
 C_PATH='@scm_lib.scm(sch_1):page56_i28@pure_quanta.q_cap(chips)',
 P_PATH='@scm_lib.scm(sch_1):page56_i28@pure_quanta.q_cap(chips)',
 PATH='I28',
 DRAWING='@SCM_LIB.SCM(SCH_1):PAGE56',
 SEC_TYPE='0805',
 PHYS_PAGE='56',
 XY='(1825,75)',
 ROT='0',
 VER='1',
 PACK_TYPE='0805',
 LOCATION='PC269',
 SEC='1',
 CDS_LIB='pure_quanta',
 CDS_PART_NAME='Q_CAP_0805-22UF,4V,20%,X6S,TMPA',
 TOLERANCE='20%',
 MATERIAL='X6S',
 VOLTAGE='4V',
 VALUE='22UF',
 PRIM_FILE='W:/<user>/logical/q_cap/chips/chips.prt';

PART_NAME
 PC270 'Q_CAP_0805-22UF,4V,20%,X6S,TMPA':;

SECTION_NUMBER 1
 '@SCM_LIB.SCM(SCH_1):PAGE56_I29@PURE_QUANTA.Q_CAP(CHIPS)':
 C_PATH='@scm_lib.scm(sch_1):page56_i29@pure_quanta.q_cap(chips)',
 P_PATH='@scm_lib.scm(sch_1):page56_i29@pure_quanta.q_cap(chips)',
 PATH='I29',
 DRAWING='@SCM_LIB.SCM(SCH_1):PAGE56',
 SEC_TYPE='0805',
 PHYS_PAGE='56',
 XY='(2075,75)',
 ROT='0',
 VER='1',
 PACK_TYPE='0805',
 LOCATION='PC270',
 SEC='1',
 CDS_LIB='pure_quanta',
 CDS_PART_NAME='Q_CAP_0805-22UF,4V,20%,X6S,TMPA',
 TOLERANCE='20%',
 MATERIAL='X6S',
 VOLTAGE='4V',
 VALUE='22UF',
 PRIM_FILE='W:/<user>/logical/q_cap/chips/chips.prt';

PART_NAME
 PC271 'Q_CAP_0402-0.1UF,25V,10%,X7R,CA':;

SECTION_NUMBER 1
 '@SCM_LIB.SCM(SCH_1):PAGE51_I22@PURE_QUANTA.Q_CAP(CHIPS)':
 C_PATH='@scm_lib.scm(sch_1):page51_i22@pure_quanta.q_cap(chips)',
 P_PATH='@scm_lib.scm(sch_1):page51_i22@pure_quanta.q_cap(chips)',
 PATH='I22',
 DRAWING='@SCM_LIB.SCM(SCH_1):PAGE51',
 PHYS_PAGE='51',
 XY='(1750,-275)',
 ROT='0',
 VER='1',
 PACK_TYPE='0402',
 LOCATION='PC271',
 CDS_LIB='pure_quanta',
 CDS_PART_NAME='Q_CAP_0402-0.1UF,25V,10%,X7R,CA',
 TOLERANCE='10%',
 MATERIAL='X7R',
 VOLTAGE='25V',
 VALUE='0.1UF',
 PRIM_FILE='W:/<user>/logical/q_cap/chips/chips.prt';

PART_NAME
 PC272 'Q_CAP_C0402-68PF,50V,5%,COG,CHA':;

SECTION_NUMBER 1
 '@SCM_LIB.SCM(SCH_1):PAGE51_I27@PURE_QUANTA.Q_CAP(CHIPS)':
 C_PATH='@scm_lib.scm(sch_1):page51_i27@pure_quanta.q_cap(chips)',
 P_PATH='@scm_lib.scm(sch_1):page51_i27@pure_quanta.q_cap(chips)',
 PATH='I27',
 DRAWING='@SCM_LIB.SCM(SCH_1):PAGE51',
 PHYS_PAGE='51',
 XY='(4100,-500)',
 ROT='0',
 VER='2',
 PACK_TYPE='C0402',
 LOCATION='PC272',
 CDS_LIB='pure_quanta',
 CDS_PART_NAME='Q_CAP_C0402-68PF,50V,5%,COG,CHA',
 TOLERANCE='5%',
 MATERIAL='COG',
 VOLTAGE='50V',
 VALUE='68PF',
 PRIM_FILE='W:/<user>/logical/q_cap/chips/chips.prt';

PART_NAME
 PC273 'Q_CAP_0402-3300PF,50V,10%,X7R,A':;

SECTION_NUMBER 1
 '@SCM_LIB.SCM(SCH_1):PAGE52_I86@PURE_QUANTA.Q_CAP(CHIPS)':
 C_PATH='@scm_lib.scm(sch_1):page52_i86@pure_quanta.q_cap(chips)',
 P_PATH='@scm_lib.scm(sch_1):page52_i86@pure_quanta.q_cap(chips)',
 PATH='I86',
 DRAWING='@SCM_LIB.SCM(SCH_1):PAGE52',
 PHYS_PAGE='52',
 XY='(800,150)',
 ROT='0',
 VER='1',
 PACK_TYPE='0402',
 LOCATION='PC273',
 CDS_LIB='pure_quanta',
 CDS_PART_NAME='Q_CAP_0402-3300PF,50V,10%,X7R,A',
 TOLERANCE='10%',
 MATERIAL='X7R',
 VOLTAGE='50V',
 VALUE='3300PF',
 PRIM_FILE='W:/<user>/logical/q_cap/chips/chips.prt';

PART_NAME
 PL4 'Q_INDUCTOR_SMLF-BLM18SN220TN1DA':;

SECTION_NUMBER 1
 '@SCM_LIB.SCM(SCH_1):PAGE51_I39@PURE_QUANTA.Q_INDUCTOR(CHIPS)':
 C_PATH='@scm_lib.scm(sch_1):page51_i39@pure_quanta.q_inductor(chips)',
 P_PATH='@scm_lib.scm(sch_1):page51_i39@pure_quanta.q_inductor(chips)',
 PATH='I39',
 DRAWING='@SCM_LIB.SCM(SCH_1):PAGE51',
 PHYS_PAGE='51',
 XY='(-1775,1675)',
 ROT='0',
 VER='1',
 PACK_TYPE='SMLF',
 LOCATION='PL4',
 CDS_LIB='pure_quanta',
 CDS_PART_NAME='Q_INDUCTOR_SMLF-BLM18SN220TN1DA',
 MATERIAL='IND',
 VALUE='BLM18SN220TN1D/8000MA',
 PRIM_FILE='W:/<user>/logical/q_inductor/chips/chips.prt';

PART_NAME
 PL19 'Q_INDUCTOR_SMLF-BLM18SN220TN1DA':;

SECTION_NUMBER 1
 '@SCM_LIB.SCM(SCH_1):PAGE52_I32@PURE_QUANTA.Q_INDUCTOR(CHIPS)':
 C_PATH='@scm_lib.scm(sch_1):page52_i32@pure_quanta.q_inductor(chips)',
 P_PATH='@scm_lib.scm(sch_1):page52_i32@pure_quanta.q_inductor(chips)',
 PATH='I32',
 DRAWING='@SCM_LIB.SCM(SCH_1):PAGE52',
 PHYS_PAGE='52',
 XY='(-2925,2325)',
 ROT='0',
 VER='1',
 PACK_TYPE='SMLF',
 LOCATION='PL19',
 CDS_LIB='pure_quanta',
 CDS_PART_NAME='Q_INDUCTOR_SMLF-BLM18SN220TN1DA',
 MATERIAL='IND',
 VALUE='BLM18SN220TN1D/8000MA',
 PRIM_FILE='W:/<user>/logical/q_inductor/chips/chips.prt';

PART_NAME
 PL29 'Q_INDUCTOR_SMLF-BLM18SN220TN1DA':;

SECTION_NUMBER 1
 '@SCM_LIB.SCM(SCH_1):PAGE55_I31@PURE_QUANTA.Q_INDUCTOR(CHIPS)':
 C_PATH='@scm_lib.scm(sch_1):page55_i31@pure_quanta.q_inductor(chips)',
 P_PATH='@scm_lib.scm(sch_1):page55_i31@pure_quanta.q_inductor(chips)',
 PATH='I31',
 DRAWING='@SCM_LIB.SCM(SCH_1):PAGE55',
 PHYS_PAGE='55',
 XY='(-2775,1575)',
 ROT='0',
 VER='1',
 PACK_TYPE='SMLF',
 LOCATION='PL29',
 CDS_LIB='pure_quanta',
 CDS_PART_NAME='Q_INDUCTOR_SMLF-BLM18SN220TN1DA',
 MATERIAL='IND',
 VALUE='BLM18SN220TN1D/8000MA',
 PRIM_FILE='W:/<user>/logical/q_inductor/chips/chips.prt';

PART_NAME
 PL31 'Q_INDUCTOR_SMLF-1UH,IND,CV-10BA':;

SECTION_NUMBER 1
 '@SCM_LIB.SCM(SCH_1):PAGE55_I21@PURE_QUANTA.Q_INDUCTOR(CHIPS)':
 C_PATH='@scm_lib.scm(sch_1):page55_i21@pure_quanta.q_inductor(chips)',
 P_PATH='@scm_lib.scm(sch_1):page55_i21@pure_quanta.q_inductor(chips)',
 PATH='I21',
 DRAWING='@SCM_LIB.SCM(SCH_1):PAGE55',
 DCR='DCR=9MOHM',
 PHYS_PAGE='55',
 XY='(2125,600)',
 ROT='0',
 VER='1',
 PACK_TYPE='SMLF',
 LOCATION='PL31',
 CDS_LIB='pure_quanta',
 CDS_PART_NAME='Q_INDUCTOR_SMLF-1UH,IND,CV-10BA',
 MATERIAL='IND',
 VALUE='1UH',
 PRIM_FILE='W:/<user>/logical/q_inductor/chips/chips.prt';

PART_NAME
 PL32 'Q_INDUCTOR_SMLF-BLM18SN220TN1DA':;

SECTION_NUMBER 1
 '@SCM_LIB.SCM(SCH_1):PAGE56_I34@PURE_QUANTA.Q_INDUCTOR(CHIPS)':
 C_PATH='@scm_lib.scm(sch_1):page56_i34@pure_quanta.q_inductor(chips)',
 P_PATH='@scm_lib.scm(sch_1):page56_i34@pure_quanta.q_inductor(chips)',
 PATH='I34',
 DRAWING='@SCM_LIB.SCM(SCH_1):PAGE56',
 PHYS_PAGE='56',
 XY='(-4650,1325)',
 ROT='0',
 VER='1',
 PACK_TYPE='SMLF',
 LOCATION='PL32',
 CDS_LIB='pure_quanta',
 CDS_PART_NAME='Q_INDUCTOR_SMLF-BLM18SN220TN1DA',
 MATERIAL='IND',
 VALUE='BLM18SN220TN1D/8000MA',
 PRIM_FILE='W:/<user>/logical/q_inductor/chips/chips.prt';

PART_NAME
 PL33 'Q_INDUCTOR_SMLF-1UH,IND,CV-10BA':;

SECTION_NUMBER 1
 '@SCM_LIB.SCM(SCH_1):PAGE56_I37@PURE_QUANTA.Q_INDUCTOR(CHIPS)':
 C_PATH='@scm_lib.scm(sch_1):page56_i37@pure_quanta.q_inductor(chips)',
 P_PATH='@scm_lib.scm(sch_1):page56_i37@pure_quanta.q_inductor(chips)',
 PATH='I37',
 DRAWING='@SCM_LIB.SCM(SCH_1):PAGE56',
 DCR='DCR=9MOHM',
 PHYS_PAGE='56',
 XY='(275,350)',
 ROT='0',
 VER='1',
 PACK_TYPE='SMLF',
 LOCATION='PL33',
 CDS_LIB='pure_quanta',
 CDS_PART_NAME='Q_INDUCTOR_SMLF-1UH,IND,CV-10BA',
 MATERIAL='IND',
 VALUE='1UH',
 PRIM_FILE='W:/<user>/logical/q_inductor/chips/chips.prt';

PART_NAME
 PL34 'Q_INDUCTOR_SMLF-4.7UH,IND,CV-4A':;

SECTION_NUMBER 1
 '@SCM_LIB.SCM(SCH_1):PAGE51_I28@PURE_QUANTA.Q_INDUCTOR(CHIPS)':
 C_PATH='@scm_lib.scm(sch_1):page51_i28@pure_quanta.q_inductor(chips)',
 P_PATH='@scm_lib.scm(sch_1):page51_i28@pure_quanta.q_inductor(chips)',
 PATH='I28',
 DRAWING='@SCM_LIB.SCM(SCH_1):PAGE51',
 R3='ISAT=13A',
 R1='DCR=13.2MOHM',
 PHYS_PAGE='51',
 XY='(3250,700)',
 ROT='0',
 VER='1',
 PACK_TYPE='SMLF',
 LOCATION='PL34',
 CDS_LIB='pure_quanta',
 CDS_PART_NAME='Q_INDUCTOR_SMLF-4.7UH,IND,CV-4A',
 MATERIAL='IND',
 VALUE='4.7UH',
 PRIM_FILE='W:/<user>/logical/q_inductor/chips/chips.prt';

PART_NAME
 PL35 'Q_INDUCTOR_SMLF-3.3UH/6A,IND,CA':;

SECTION_NUMBER 1
 '@SCM_LIB.SCM(SCH_1):PAGE52_I92@PURE_QUANTA.Q_INDUCTOR(CHIPS)':
 C_PATH='@scm_lib.scm(sch_1):page52_i92@pure_quanta.q_inductor(chips)',
 P_PATH='@scm_lib.scm(sch_1):page52_i92@pure_quanta.q_inductor(chips)',
 PATH='I92',
 DRAWING='@SCM_LIB.SCM(SCH_1):PAGE52',
 PHYS_PAGE='52',
 XY='(1850,1350)',
 ROT='0',
 VER='1',
 PACK_TYPE='SMLF',
 LOCATION='PL35',
 CDS_LIB='pure_quanta',
 CDS_PART_NAME='Q_INDUCTOR_SMLF-3.3UH/6A,IND,CA',
 MATERIAL='IND',
 VALUE='3.3UH/6A',
 PRIM_FILE='W:/<user>/logical/q_inductor/chips/chips.prt';

PART_NAME
 PR193 'Q_RES_0402LF-0,5%,1/16W,CHIP,CA':;

SECTION_NUMBER 1
 '@SCM_LIB.SCM(SCH_1):PAGE56_I47@PURE_QUANTA.Q_RES(CHIPS)':
 C_PATH='@scm_lib.scm(sch_1):page56_i47@pure_quanta.q_res(chips)',
 P_PATH='@scm_lib.scm(sch_1):page56_i47@pure_quanta.q_res(chips)',
 PATH='I47',
 DRAWING='@SCM_LIB.SCM(SCH_1):PAGE56',
 PHYS_PAGE='56',
 XY='(-3100,-1475)',
 ROT='0',
 VER='1',
 PACK_TYPE='0402LF',
 LOCATION='PR193',
 CDS_LIB='pure_quanta',
 CDS_PART_NAME='Q_RES_0402LF-0,5%,1/16W,CHIP,CA',
 WATTAGE='1/16W',
 TOLERANCE='5%',
 MATERIAL='CHIP',
 VALUE='0',
 PRIM_FILE='W:/<user>/logical/q_res/chips/chips.prt';

PART_NAME
 PR205 'Q_RES_0402LF-0,5%,1/16W,EMPTY,A':;

SECTION_NUMBER 1
 '@SCM_LIB.SCM(SCH_1):PAGE56_I48@PURE_QUANTA.Q_RES(CHIPS)':
 C_PATH='@scm_lib.scm(sch_1):page56_i48@pure_quanta.q_res(chips)',
 P_PATH='@scm_lib.scm(sch_1):page56_i48@pure_quanta.q_res(chips)',
 PATH='I48',
 DRAWING='@SCM_LIB.SCM(SCH_1):PAGE56',
 PHYS_PAGE='56',
 XY='(-3100,-1800)',
 ROT='0',
 VER='1',
 PACK_TYPE='0402LF',
 LOCATION='PR205',
 CDS_LIB='pure_quanta',
 CDS_PART_NAME='Q_RES_0402LF-0,5%,1/16W,EMPTY,A',
 WATTAGE='1/16W',
 TOLERANCE='5%',
 MATERIAL='EMPTY',
 VALUE='0',
 PRIM_FILE='W:/<user>/logical/q_res/chips/chips.prt';

PART_NAME
 PR241 'Q_RES_0402LF-10K,1%,1/16W,CHIPA':;

SECTION_NUMBER 1
 '@SCM_LIB.SCM(SCH_1):PAGE51_I21@PURE_QUANTA.Q_RES(CHIPS)':
 C_PATH='@scm_lib.scm(sch_1):page51_i21@pure_quanta.q_res(chips)',
 P_PATH='@scm_lib.scm(sch_1):page51_i21@pure_quanta.q_res(chips)',
 PATH='I21',
 DRAWING='@SCM_LIB.SCM(SCH_1):PAGE51',
 SEC_TYPE='0402LF',
 PHYS_PAGE='51',
 XY='(2825,1450)',
 ROT='0',
 VER='2',
 PACK_TYPE='0402LF',
 LOCATION='PR241',
 SEC='1',
 CDS_LIB='pure_quanta',
 CDS_PART_NAME='Q_RES_0402LF-10K,1%,1/16W,CHIPA',
 WATTAGE='1/16W',
 TOLERANCE='1%',
 MATERIAL='CHIP',
 VALUE='10K',
 PRIM_FILE='W:/<user>/logical/q_res/chips/chips.prt';

PART_NAME
 PR242 'Q_RES_0402LF-10K,1%,1/16W,CHIPA':;

SECTION_NUMBER 1
 '@SCM_LIB.SCM(SCH_1):PAGE52_I13@PURE_QUANTA.Q_RES(CHIPS)':
 C_PATH='@scm_lib.scm(sch_1):page52_i13@pure_quanta.q_res(chips)',
 P_PATH='@scm_lib.scm(sch_1):page52_i13@pure_quanta.q_res(chips)',
 PATH='I13',
 DRAWING='@SCM_LIB.SCM(SCH_1):PAGE52',
 SEC_TYPE='0402LF',
 PHYS_PAGE='52',
 XY='(325,2075)',
 ROT='0',
 VER='2',
 PACK_TYPE='0402LF',
 LOCATION='PR242',
 SEC='1',
 CDS_LIB='pure_quanta',
 CDS_PART_NAME='Q_RES_0402LF-10K,1%,1/16W,CHIPA',
 WATTAGE='1/16W',
 TOLERANCE='1%',
 MATERIAL='CHIP',
 VALUE='10K',
 PRIM_FILE='W:/<user>/logical/q_res/chips/chips.prt';

PART_NAME
 PR245 'Q_RES_0402LF-100K,1%,1/16W,EMPA':;

SECTION_NUMBER 1
 '@SCM_LIB.SCM(SCH_1):PAGE51_I43@PURE_QUANTA.Q_RES(CHIPS)':
 C_PATH='@scm_lib.scm(sch_1):page51_i43@pure_quanta.q_res(chips)',
 P_PATH='@scm_lib.scm(sch_1):page51_i43@pure_quanta.q_res(chips)',
 PATH='I43',
 DRAWING='@SCM_LIB.SCM(SCH_1):PAGE51',
 PHYS_PAGE='51',
 XY='(2400,1000)',
 ROT='0',
 VER='2',
 PACK_TYPE='0402LF',
 LOCATION='PR245',
 CDS_LIB='pure_quanta',
 CDS_PART_NAME='Q_RES_0402LF-100K,1%,1/16W,EMPA',
 WATTAGE='1/16W',
 TOLERANCE='1%',
 MATERIAL='EMPTY',
 VALUE='100K',
 PRIM_FILE='W:/<user>/logical/q_res/chips/chips.prt';

PART_NAME
 PR274 'Q_RES_0402LF-0,5%,1/16W,CHIP,CA':;

SECTION_NUMBER 1
 '@SCM_LIB.SCM(SCH_1):PAGE55_I45@PURE_QUANTA.Q_RES(CHIPS)':
 C_PATH='@scm_lib.scm(sch_1):page55_i45@pure_quanta.q_res(chips)',
 P_PATH='@scm_lib.scm(sch_1):page55_i45@pure_quanta.q_res(chips)',
 PATH='I45',
 DRAWING='@SCM_LIB.SCM(SCH_1):PAGE55',
 PHYS_PAGE='55',
 XY='(-1350,-1225)',
 ROT='0',
 VER='1',
 PACK_TYPE='0402LF',
 LOCATION='PR274',
 CDS_LIB='pure_quanta',
 CDS_PART_NAME='Q_RES_0402LF-0,5%,1/16W,CHIP,CA',
 WATTAGE='1/16W',
 TOLERANCE='5%',
 MATERIAL='CHIP',
 VALUE='0',
 PRIM_FILE='W:/<user>/logical/q_res/chips/chips.prt';

PART_NAME
 PR275 'Q_RES_0402LF-0,5%,1/16W,EMPTY,A':;

SECTION_NUMBER 1
 '@SCM_LIB.SCM(SCH_1):PAGE55_I48@PURE_QUANTA.Q_RES(CHIPS)':
 C_PATH='@scm_lib.scm(sch_1):page55_i48@pure_quanta.q_res(chips)',
 P_PATH='@scm_lib.scm(sch_1):page55_i48@pure_quanta.q_res(chips)',
 PATH='I48',
 DRAWING='@SCM_LIB.SCM(SCH_1):PAGE55',
 PHYS_PAGE='55',
 XY='(-1350,-1550)',
 ROT='0',
 VER='1',
 PACK_TYPE='0402LF',
 LOCATION='PR275',
 CDS_LIB='pure_quanta',
 CDS_PART_NAME='Q_RES_0402LF-0,5%,1/16W,EMPTY,A',
 WATTAGE='1/16W',
 TOLERANCE='5%',
 MATERIAL='EMPTY',
 VALUE='0',
 PRIM_FILE='W:/<user>/logical/q_res/chips/chips.prt';

PART_NAME
 PR276 'Q_RES_0402LF-5.49K,1%,1/16W,CHA':;

SECTION_NUMBER 1
 '@SCM_LIB.SCM(SCH_1):PAGE52_I87@PURE_QUANTA.Q_RES(CHIPS)':
 C_PATH='@scm_lib.scm(sch_1):page52_i87@pure_quanta.q_res(chips)',
 P_PATH='@scm_lib.scm(sch_1):page52_i87@pure_quanta.q_res(chips)',
 PATH='I87',
 DRAWING='@SCM_LIB.SCM(SCH_1):PAGE52',
 SEC_TYPE='0402LF',
 PHYS_PAGE='52',
 XY='(-1200,150)',
 ROT='6',
 VER='2',
 PACK_TYPE='0402LF',
 LOCATION='PR276',
 SEC='1',
 CDS_LIB='pure_quanta',
 CDS_PART_NAME='Q_RES_0402LF-5.49K,1%,1/16W,CHA',
 WATTAGE='1/16W',
 TOLERANCE='1%',
 MATERIAL='CHIP',
 VALUE='5.49K',
 PRIM_FILE='W:/<user>/logical/q_res/chips/chips.prt';

PART_NAME
 PR496 'Q_RES_0402LF-150K,1%,1/16W,CHIA':;

SECTION_NUMBER 1
 '@SCM_LIB.SCM(SCH_1):PAGE55_I6@PURE_QUANTA.Q_RES(CHIPS)':
 C_PATH='@scm_lib.scm(sch_1):page55_i6@pure_quanta.q_res(chips)',
 P_PATH='@scm_lib.scm(sch_1):page55_i6@pure_quanta.q_res(chips)',
 PATH='I6',
 DRAWING='@SCM_LIB.SCM(SCH_1):PAGE55',
 SEC_TYPE='0402LF',
 PHYS_PAGE='55',
 XY='(-1050,-600)',
 ROT='0',
 VER='2',
 PACK_TYPE='0402LF',
 LOCATION='PR496',
 SEC='1',
 CDS_LIB='pure_quanta',
 CDS_PART_NAME='Q_RES_0402LF-150K,1%,1/16W,CHIA',
 WATTAGE='1/16W',
 TOLERANCE='1%',
 MATERIAL='CHIP',
 VALUE='150K',
 PRIM_FILE='W:/<user>/logical/q_res/chips/chips.prt';

PART_NAME
 PR498 'Q_RES_0402LF-10K,1%,1/16W,CHIPA':;

SECTION_NUMBER 1
 '@SCM_LIB.SCM(SCH_1):PAGE55_I18@PURE_QUANTA.Q_RES(CHIPS)':
 C_PATH='@scm_lib.scm(sch_1):page55_i18@pure_quanta.q_res(chips)',
 P_PATH='@scm_lib.scm(sch_1):page55_i18@pure_quanta.q_res(chips)',
 PATH='I18',
 DRAWING='@SCM_LIB.SCM(SCH_1):PAGE55',
 SEC_TYPE='0402LF',
 PHYS_PAGE='55',
 XY='(500,1350)',
 ROT='0',
 VER='2',
 PACK_TYPE='0402LF',
 LOCATION='PR498',
 SEC='1',
 CDS_LIB='pure_quanta',
 CDS_PART_NAME='Q_RES_0402LF-10K,1%,1/16W,CHIPA',
 WATTAGE='1/16W',
 TOLERANCE='1%',
 MATERIAL='CHIP',
 VALUE='10K',
 PRIM_FILE='W:/<user>/logical/q_res/chips/chips.prt';

PART_NAME
 PR500 'Q_RES_0402LF-10K,1%,1/16W,CHIPA':;

SECTION_NUMBER 1
 '@SCM_LIB.SCM(SCH_1):PAGE56_I18@PURE_QUANTA.Q_RES(CHIPS)':
 C_PATH='@scm_lib.scm(sch_1):page56_i18@pure_quanta.q_res(chips)',
 P_PATH='@scm_lib.scm(sch_1):page56_i18@pure_quanta.q_res(chips)',
 PATH='I18',
 DRAWING='@SCM_LIB.SCM(SCH_1):PAGE56',
 SEC_TYPE='0402LF',
 PHYS_PAGE='56',
 XY='(-1350,1100)',
 ROT='0',
 VER='2',
 PACK_TYPE='0402LF',
 LOCATION='PR500',
 SEC='1',
 CDS_LIB='pure_quanta',
 CDS_PART_NAME='Q_RES_0402LF-10K,1%,1/16W,CHIPA',
 WATTAGE='1/16W',
 TOLERANCE='1%',
 MATERIAL='CHIP',
 VALUE='10K',
 PRIM_FILE='W:/<user>/logical/q_res/chips/chips.prt';

PART_NAME
 PR521 'Q_RES_0402LF-681K,1%,1/16W,CHIA':;

SECTION_NUMBER 1
 '@SCM_LIB.SCM(SCH_1):PAGE51_I4@PURE_QUANTA.Q_RES(CHIPS)':
 C_PATH='@scm_lib.scm(sch_1):page51_i4@pure_quanta.q_res(chips)',
 P_PATH='@scm_lib.scm(sch_1):page51_i4@pure_quanta.q_res(chips)',
 PATH='I4',
 DRAWING='@SCM_LIB.SCM(SCH_1):PAGE51',
 PHYS_PAGE='51',
 XY='(-2325,900)',
 ROT='0',
 VER='2',
 PACK_TYPE='0402LF',
 LOCATION='PR521',
 CDS_LIB='pure_quanta',
 CDS_PART_NAME='Q_RES_0402LF-681K,1%,1/16W,CHIA',
 WATTAGE='1/16W',
 TOLERANCE='1%',
 MATERIAL='CHIP',
 VALUE='681K',
 PRIM_FILE='W:/<user>/logical/q_res/chips/chips.prt';

PART_NAME
 PR522 'Q_RES_0402LF-100K,1%,1/16W,CHIA':;

SECTION_NUMBER 1
 '@SCM_LIB.SCM(SCH_1):PAGE51_I3@PURE_QUANTA.Q_RES(CHIPS)':
 C_PATH='@scm_lib.scm(sch_1):page51_i3@pure_quanta.q_res(chips)',
 P_PATH='@scm_lib.scm(sch_1):page51_i3@pure_quanta.q_res(chips)',
 PATH='I3',
 DRAWING='@SCM_LIB.SCM(SCH_1):PAGE51',
 PHYS_PAGE='51',
 XY='(-2075,500)',
 ROT='0',
 VER='2',
 PACK_TYPE='0402LF',
 LOCATION='PR522',
 CDS_LIB='pure_quanta',
 CDS_PART_NAME='Q_RES_0402LF-100K,1%,1/16W,CHIA',
 WATTAGE='1/16W',
 TOLERANCE='1%',
 MATERIAL='CHIP',
 VALUE='100K',
 PRIM_FILE='W:/<user>/logical/q_res/chips/chips.prt';

PART_NAME
 PR525 'Q_RES_0402LF-20.5K,1%,1/16W,CHA':;

SECTION_NUMBER 1
 '@SCM_LIB.SCM(SCH_1):PAGE51_I9@PURE_QUANTA.Q_RES(CHIPS)':
 C_PATH='@scm_lib.scm(sch_1):page51_i9@pure_quanta.q_res(chips)',
 P_PATH='@scm_lib.scm(sch_1):page51_i9@pure_quanta.q_res(chips)',
 PATH='I9',
 DRAWING='@SCM_LIB.SCM(SCH_1):PAGE51',
 SEC_TYPE='0402LF',
 PHYS_PAGE='51',
 XY='(-25,-450)',
 ROT='0',
 VER='2',
 PACK_TYPE='0402LF',
 LOCATION='PR525',
 SEC='1',
 CDS_LIB='pure_quanta',
 CDS_PART_NAME='Q_RES_0402LF-20.5K,1%,1/16W,CHA',
 WATTAGE='1/16W',
 TOLERANCE='1%',
 MATERIAL='CHIP',
 VALUE='20.5K',
 PRIM_FILE='W:/<user>/logical/q_res/chips/chips.prt';

PART_NAME
 PR526 'Q_RES_0402LF-12.4K,1%,1/16W,CHA':;

SECTION_NUMBER 1
 '@SCM_LIB.SCM(SCH_1):PAGE51_I26@PURE_QUANTA.Q_RES(CHIPS)':
 C_PATH='@scm_lib.scm(sch_1):page51_i26@pure_quanta.q_res(chips)',
 P_PATH='@scm_lib.scm(sch_1):page51_i26@pure_quanta.q_res(chips)',
 PATH='I26',
 DRAWING='@SCM_LIB.SCM(SCH_1):PAGE51',
 PHYS_PAGE='51',
 XY='(2850,-325)',
 ROT='0',
 VER='2',
 PACK_TYPE='0402LF',
 LOCATION='PR526',
 CDS_LIB='pure_quanta',
 CDS_PART_NAME='Q_RES_0402LF-12.4K,1%,1/16W,CHA',
 WATTAGE='1/16W',
 TOLERANCE='1%',
 MATERIAL='CHIP',
 VALUE='12.4K',
 PRIM_FILE='W:/<user>/logical/q_res/chips/chips.prt';

PART_NAME
 PR527 'Q_RES_0402LF-91K,1%,1/16W,CHIPA':;

SECTION_NUMBER 1
 '@SCM_LIB.SCM(SCH_1):PAGE51_I30@PURE_QUANTA.Q_RES(CHIPS)':
 C_PATH='@scm_lib.scm(sch_1):page51_i30@pure_quanta.q_res(chips)',
 P_PATH='@scm_lib.scm(sch_1):page51_i30@pure_quanta.q_res(chips)',
 PATH='I30',
 DRAWING='@SCM_LIB.SCM(SCH_1):PAGE51',
 PHYS_PAGE='51',
 XY='(4100,-150)',
 ROT='0',
 VER='1',
 PACK_TYPE='0402LF',
 LOCATION='PR527',
 CDS_LIB='pure_quanta',
 CDS_PART_NAME='Q_RES_0402LF-91K,1%,1/16W,CHIPA',
 WATTAGE='1/16W',
 TOLERANCE='1%',
 MATERIAL='CHIP',
 VALUE='91K',
 PRIM_FILE='W:/<user>/logical/q_res/chips/chips.prt';

PART_NAME
 PR530 'Q_RES_0402LF-12.4K,1%,1/16W,CHA':;

SECTION_NUMBER 1
 '@SCM_LIB.SCM(SCH_1):PAGE52_I17@PURE_QUANTA.Q_RES(CHIPS)':
 C_PATH='@scm_lib.scm(sch_1):page52_i17@pure_quanta.q_res(chips)',
 P_PATH='@scm_lib.scm(sch_1):page52_i17@pure_quanta.q_res(chips)',
 PATH='I17',
 DRAWING='@SCM_LIB.SCM(SCH_1):PAGE52',
 PHYS_PAGE='52',
 XY='(1300,75)',
 ROT='6',
 VER='2',
 PACK_TYPE='0402LF',
 LOCATION='PR530',
 CDS_LIB='pure_quanta',
 CDS_PART_NAME='Q_RES_0402LF-12.4K,1%,1/16W,CHA',
 WATTAGE='1/16W',
 TOLERANCE='1%',
 MATERIAL='CHIP',
 VALUE='12.4K',
 PRIM_FILE='W:/<user>/logical/q_res/chips/chips.prt';

PART_NAME
 PR532 'Q_RES_0402LF-60.4K,1%,1/16W,CHA':;

SECTION_NUMBER 1
 '@SCM_LIB.SCM(SCH_1):PAGE52_I88@PURE_QUANTA.Q_RES(CHIPS)':
 C_PATH='@scm_lib.scm(sch_1):page52_i88@pure_quanta.q_res(chips)',
 P_PATH='@scm_lib.scm(sch_1):page52_i88@pure_quanta.q_res(chips)',
 PATH='I88',
 DRAWING='@SCM_LIB.SCM(SCH_1):PAGE52',
 PHYS_PAGE='52',
 XY='(-2025,750)',
 ROT='6',
 VER='2',
 PACK_TYPE='0402LF',
 LOCATION='PR532',
 CDS_LIB='pure_quanta',
 CDS_PART_NAME='Q_RES_0402LF-60.4K,1%,1/16W,CHA',
 WATTAGE='1/16W',
 TOLERANCE='1%',
 MATERIAL='CHIP',
 VALUE='60.4K',
 PRIM_FILE='W:/<user>/logical/q_res/chips/chips.prt';

PART_NAME
 PR534 'Q_RES_0402LF-56K,1%,1/16W,CHIPA':;

SECTION_NUMBER 1
 '@SCM_LIB.SCM(SCH_1):PAGE52_I25@PURE_QUANTA.Q_RES(CHIPS)':
 C_PATH='@scm_lib.scm(sch_1):page52_i25@pure_quanta.q_res(chips)',
 P_PATH='@scm_lib.scm(sch_1):page52_i25@pure_quanta.q_res(chips)',
 PATH='I25',
 DRAWING='@SCM_LIB.SCM(SCH_1):PAGE52',
 PHYS_PAGE='52',
 XY='(3200,475)',
 ROT='6',
 VER='1',
 PACK_TYPE='0402LF',
 LOCATION='PR534',
 CDS_LIB='pure_quanta',
 CDS_PART_NAME='Q_RES_0402LF-56K,1%,1/16W,CHIPA',
 WATTAGE='1/16W',
 TOLERANCE='1%',
 MATERIAL='CHIP',
 VALUE='56K',
 PRIM_FILE='W:/<user>/logical/q_res/chips/chips.prt';

PART_NAME
 PR539 'Q_RES_0402LF-5.1,5%,1/16W,CHIPA':;

SECTION_NUMBER 1
 '@SCM_LIB.SCM(SCH_1):PAGE55_I8@PURE_QUANTA.Q_RES(CHIPS)':
 C_PATH='@scm_lib.scm(sch_1):page55_i8@pure_quanta.q_res(chips)',
 P_PATH='@scm_lib.scm(sch_1):page55_i8@pure_quanta.q_res(chips)',
 PATH='I8',
 DRAWING='@SCM_LIB.SCM(SCH_1):PAGE55',
 PHYS_PAGE='55',
 XY='(-3575,300)',
 ROT='0',
 VER='2',
 PACK_TYPE='0402LF',
 LOCATION='PR539',
 CDS_LIB='pure_quanta',
 CDS_PART_NAME='Q_RES_0402LF-5.1,5%,1/16W,CHIPA',
 WATTAGE='1/16W',
 TOLERANCE='5%',
 MATERIAL='CHIP',
 VALUE='5.1',
 PRIM_FILE='W:/<user>/logical/q_res/chips/chips.prt';

PART_NAME
 PR541 'Q_RES_0402LF-5.1,5%,1/16W,CHIPA':;

SECTION_NUMBER 1
 '@SCM_LIB.SCM(SCH_1):PAGE56_I8@PURE_QUANTA.Q_RES(CHIPS)':
 C_PATH='@scm_lib.scm(sch_1):page56_i8@pure_quanta.q_res(chips)',
 P_PATH='@scm_lib.scm(sch_1):page56_i8@pure_quanta.q_res(chips)',
 PATH='I8',
 DRAWING='@SCM_LIB.SCM(SCH_1):PAGE56',
 PHYS_PAGE='56',
 XY='(-4025,-75)',
 ROT='0',
 VER='2',
 PACK_TYPE='0402LF',
 LOCATION='PR541',
 CDS_LIB='pure_quanta',
 CDS_PART_NAME='Q_RES_0402LF-5.1,5%,1/16W,CHIPA',
 WATTAGE='1/16W',
 TOLERANCE='5%',
 MATERIAL='CHIP',
 VALUE='5.1',
 PRIM_FILE='W:/<user>/logical/q_res/chips/chips.prt';

PART_NAME
 PR543 'Q_RES_0402LF-100K,1%,1/16W,CHIA':;

SECTION_NUMBER 1
 '@SCM_LIB.SCM(SCH_1):PAGE56_I71@PURE_QUANTA.Q_RES(CHIPS)':
 C_PATH='@scm_lib.scm(sch_1):page56_i71@pure_quanta.q_res(chips)',
 P_PATH='@scm_lib.scm(sch_1):page56_i71@pure_quanta.q_res(chips)',
 PATH='I71',
 DRAWING='@SCM_LIB.SCM(SCH_1):PAGE56',
 PHYS_PAGE='56',
 XY='(-2950,-850)',
 ROT='0',
 VER='2',
 PACK_TYPE='0402LF',
 LOCATION='PR543',
 CDS_LIB='pure_quanta',
 CDS_PART_NAME='Q_RES_0402LF-100K,1%,1/16W,CHIA',
 WATTAGE='1/16W',
 TOLERANCE='1%',
 MATERIAL='CHIP',
 VALUE='100K',
 PRIM_FILE='W:/<user>/logical/q_res/chips/chips.prt';

PART_NAME
 PU1 'MPQ8626GDZ-MPQ8626GD-Z,SMLF,ICA':;

SECTION_NUMBER 1
 '@SCM_LIB.SCM(SCH_1):PAGE52_I82@PURE_QUANTA.MPQ8626GDZ(CHIPS)':
 C_PATH='@scm_lib.scm(sch_1):page52_i82@pure_quanta.mpq8626gdz(chips)',
 P_PATH='@scm_lib.scm(sch_1):page52_i82@pure_quanta.mpq8626gdz(chips)',
 PATH='I82',
 DRAWING='@SCM_LIB.SCM(SCH_1):PAGE52',
 PART_TYPE='SMLF',
 PHYS_PAGE='52',
 XY='(-275,1150)',
 ROT='0',
 VER='1',
 LOCATION='PU1',
 CDS_LIB='pure_quanta',
 CDS_PART_NAME='MPQ8626GDZ-MPQ8626GD-Z,SMLF,ICA',
 MATERIAL='IC',
 VALUE='MPQ8626GD-Z',
 PRIM_FILE='W:/<user>/logical/mpq8626gdz/chips/chips.prt';

PART_NAME
 PU38 'MPQ8633AGLEC807Z-MPQ8633AGLE-CA':;

SECTION_NUMBER 1
 '@SCM_LIB.SCM(SCH_1):PAGE51_I42@PURE_QUANTA.MPQ8633AGLEC807Z(CHIPS)':
 C_PATH='@scm_lib.scm(sch_1):page51_i42@pure_quanta.mpq8633aglec807z(chips)',
 P_PATH='@scm_lib.scm(sch_1):page51_i42@pure_quanta.mpq8633aglec807z(chips)',
 PATH='I42',
 DRAWING='@SCM_LIB.SCM(SCH_1):PAGE51',
 PART_TYPE='SMLF',
 PHYS_PAGE='51',
 XY='(925,500)',
 ROT='0',
 VER='1',
 LOCATION='PU38',
 CDS_LIB='pure_quanta',
 CDS_PART_NAME='MPQ8633AGLEC807Z-MPQ8633AGLE-CA',
 MATERIAL='IC',
 VALUE='MPQ8633AGLE-C807-Z',
 PRIM_FILE='W:/<user>/logical/mpq8633aglec807z/chips/chips.prt';

PART_NAME
 PU41 'NB695GDZ-NB695GD-Z,SMLF,IC,AL0A':;

SECTION_NUMBER 1
 '@SCM_LIB.SCM(SCH_1):PAGE55_I15@PURE_QUANTA.NB695GDZ(CHIPS)':
 C_PATH='@scm_lib.scm(sch_1):page55_i15@pure_quanta.nb695gdz(chips)',
 P_PATH='@scm_lib.scm(sch_1):page55_i15@pure_quanta.nb695gdz(chips)',
 PATH='I15',
 DRAWING='@SCM_LIB.SCM(SCH_1):PAGE55',
 PART_TYPE='SMLF',
 PHYS_PAGE='55',
 XY='(-175,400)',
 ROT='0',
 VER='1',
 LOCATION='PU41',
 CDS_LIB='pure_quanta',
 CDS_PART_NAME='NB695GDZ-NB695GD-Z,SMLF,IC,AL0A',
 MATERIAL='IC',
 VALUE='NB695GD-Z',
 PRIM_FILE='W:/<user>/logical/nb695gdz/chips/chips.prt';

PART_NAME
 PU42 'NB695GDZ-NB695GD-Z,SMLF,IC,AL0A':;

SECTION_NUMBER 1
 '@SCM_LIB.SCM(SCH_1):PAGE56_I15@PURE_QUANTA.NB695GDZ(CHIPS)':
 C_PATH='@scm_lib.scm(sch_1):page56_i15@pure_quanta.nb695gdz(chips)',
 P_PATH='@scm_lib.scm(sch_1):page56_i15@pure_quanta.nb695gdz(chips)',
 PATH='I15',
 DRAWING='@SCM_LIB.SCM(SCH_1):PAGE56',
 PART_TYPE='SMLF',
 PHYS_PAGE='56',
 XY='(-2025,150)',
 ROT='0',
 VER='1',
 LOCATION='PU42',
 CDS_LIB='pure_quanta',
 CDS_PART_NAME='NB695GDZ-NB695GD-Z,SMLF,IC,AL0A',
 MATERIAL='IC',
 VALUE='NB695GD-Z',
 PRIM_FILE='W:/<user>/logical/nb695gdz/chips/chips.prt';

PART_NAME
 Q1 'MMBT39047F-MMBT3904-7-F,SMLF,IA':;

SECTION_NUMBER 1
 '@SCM_LIB.SCM(SCH_1):PAGE22_I2@PURE_QUANTA.MMBT39047F(CHIPS)':
 C_PATH='@scm_lib.scm(sch_1):page22_i2@pure_quanta.mmbt39047f(chips)',
 P_PATH='@scm_lib.scm(sch_1):page22_i2@pure_quanta.mmbt39047f(chips)',
 PATH='I2',
 DRAWING='@SCM_LIB.SCM(SCH_1):PAGE22',
 SEC_TYPE='',
 PART_TYPE='SMLF',
 PHYS_PAGE='22',
 XY='(-525,4025)',
 ROT='2',
 VER='1',
 LOCATION='Q1',
 SEC='1',
 CDS_LIB='pure_quanta',
 CDS_PART_NAME='MMBT39047F-MMBT3904-7-F,SMLF,IA',
 MATERIAL='IC',
 VALUE='MMBT3904-7-F',
 PRIM_FILE='W:/<user>/logical/mmbt39047f/chips/chips.prt';

PART_NAME
 Q2 'MOSFET_NCH_DUAL-2N7002KDW,SMLFA':;

SECTION_NUMBER 1
 '@SCM_LIB.SCM(SCH_1):PAGE23_I56@PURE_QUANTA.MOSFET_NCH_DUAL(CHIPS)':
 C_PATH='@scm_lib.scm(sch_1):page23_i56@pure_quanta.mosfet_nch_dual(chips)',
 P_PATH='@scm_lib.scm(sch_1):page23_i56@pure_quanta.mosfet_nch_dual(chips)',
 PATH='I56',
 DRAWING='@SCM_LIB.SCM(SCH_1):PAGE23',
 PART_TYPE='SMLF',
 PHYS_PAGE='23',
 XY='(150,-375)',
 ROT='5',
 VER='1',
 LOCATION='Q2',
 CDS_LIB='pure_quanta',
 CDS_PART_NAME='MOSFET_NCH_DUAL-2N7002KDW,SMLFA',
 MATERIAL='IC',
 VALUE='2N7002KDW',
 PRIM_FILE='W:/<user>/logical/mosfet_nch_dual/chips/chips.prt';

SECTION_NUMBER 2
 '@SCM_LIB.SCM(SCH_1):PAGE23_I2@PURE_QUANTA.MOSFET_NCH_DUAL(CHIPS)':
 C_PATH='@scm_lib.scm(sch_1):page23_i2@pure_quanta.mosfet_nch_dual(chips)',
 P_PATH='@scm_lib.scm(sch_1):page23_i2@pure_quanta.mosfet_nch_dual(chips)',
 PATH='I2',
 DRAWING='@SCM_LIB.SCM(SCH_1):PAGE23',
 PART_TYPE='SMLF',
 PHYS_PAGE='23',
 XY='(500,-725)',
 ROT='5',
 VER='2',
 LOCATION='Q2',
 CDS_LIB='pure_quanta',
 CDS_PART_NAME='MOSFET_NCH_DUAL-2N7002KDW,SMLFA',
 MATERIAL='IC',
 VALUE='2N7002KDW',
 PRIM_FILE='W:/<user>/logical/mosfet_nch_dual/chips/chips.prt';

PART_NAME
 Q3 'MMBT39047F-MMBT3904-7-F,SMLF,IA':;

SECTION_NUMBER 1
 '@SCM_LIB.SCM(SCH_1):PAGE22_I4@PURE_QUANTA.MMBT39047F(CHIPS)':
 C_PATH='@scm_lib.scm(sch_1):page22_i4@pure_quanta.mmbt39047f(chips)',
 P_PATH='@scm_lib.scm(sch_1):page22_i4@pure_quanta.mmbt39047f(chips)',
 PATH='I4',
 DRAWING='@SCM_LIB.SCM(SCH_1):PAGE22',
 SEC_TYPE='',
 PART_TYPE='SMLF',
 PHYS_PAGE='22',
 XY='(275,3750)',
 ROT='2',
 VER='1',
 LOCATION='Q3',
 SEC='1',
 CDS_LIB='pure_quanta',
 CDS_PART_NAME='MMBT39047F-MMBT3904-7-F,SMLF,IA',
 MATERIAL='IC',
 VALUE='MMBT3904-7-F',
 PRIM_FILE='W:/<user>/logical/mmbt39047f/chips/chips.prt';

PART_NAME
 Q4 'MOSFET_PCH_GDS-NTR1P02LT1G,SMLA':;

SECTION_NUMBER 1
 '@SCM_LIB.SCM(SCH_1):PAGE17_I289@PURE_QUANTA.MOSFET_PCH_GDS(CHIPS)':
 C_PATH='@scm_lib.scm(sch_1):page17_i289@pure_quanta.mosfet_pch_gds(chips)',
 P_PATH='@scm_lib.scm(sch_1):page17_i289@pure_quanta.mosfet_pch_gds(chips)',
 PATH='I289',
 DRAWING='@SCM_LIB.SCM(SCH_1):PAGE17',
 PIN_NAMES_ROTATE='True',
 PART_TYPE='SMLF',
 PHYS_PAGE='17',
 XY='(3475,-125)',
 ROT='6',
 VER='1',
 LOCATION='Q4',
 CDS_LIB='pure_quanta',
 CDS_PART_NAME='MOSFET_PCH_GDS-NTR1P02LT1G,SMLA',
 MATERIAL='EMPTY',
 VALUE='NTR1P02LT1G',
 PRIM_FILE='W:/<user>/logical/mosfet_pch_gds/chips/chips.prt';

PART_NAME
 Q5 'MOSFET_NCH_4D1S-NTGS4141NT1G,SA':;

SECTION_NUMBER 1
 '@SCM_LIB.SCM(SCH_1):PAGE17_I274@PURE_QUANTA.MOSFET_NCH_4D1S(CHIPS)':
 C_PATH='@scm_lib.scm(sch_1):page17_i274@pure_quanta.mosfet_nch_4d1s(chips)',
 P_PATH='@scm_lib.scm(sch_1):page17_i274@pure_quanta.mosfet_nch_4d1s(chips)',
 PATH='I274',
 DRAWING='@SCM_LIB.SCM(SCH_1):PAGE17',
 SEC_TYPE='',
 PIN_NAMES_ROTATE='True',
 PART_TYPE='SMLF',
 PHYS_PAGE='17',
 XY='(3725,850)',
 ROT='6',
 VER='1',
 LOCATION='Q5',
 SEC='1',
 CDS_LIB='pure_quanta',
 CDS_PART_NAME='MOSFET_NCH_4D1S-NTGS4141NT1G,SA',
 MATERIAL='IC',
 VALUE='NTGS4141NT1G',
 PRIM_FILE='W:/<user>/logical/mosfet_nch_4d1s/chips/chips.prt';

PART_NAME
 Q6 '2N7002A7-2N7002A-7,SMLF,IC,BAMA':;

SECTION_NUMBER 1
 '@SCM_LIB.SCM(SCH_1):PAGE29_I202@PURE_QUANTA.2N7002A7(CHIPS)':
 C_PATH='@scm_lib.scm(sch_1):page29_i202@pure_quanta.\2n7002a7\(chips)',
 P_PATH='@scm_lib.scm(sch_1):page29_i202@pure_quanta.\2n7002a7\(chips)',
 PATH='I202',
 DRAWING='@SCM_LIB.SCM(SCH_1):PAGE29',
 PART_TYPE='SMLF',
 PHYS_PAGE='29',
 XY='(3150,-1525)',
 ROT='2',
 VER='1',
 LOCATION='Q6',
 CDS_LIB='pure_quanta',
 CDS_PART_NAME='2N7002A7-2N7002A-7,SMLF,IC,BAMA',
 MATERIAL='IC',
 VALUE='2N7002A-7',
 PRIM_FILE='W:/<user>/logical/2n7002a7/chips/chips.prt';

PART_NAME
 Q7 '2N7002A7-2N7002A-7,SMLF,IC,BAMA':;

SECTION_NUMBER 1
 '@SCM_LIB.SCM(SCH_1):PAGE27_I243@PURE_QUANTA.2N7002A7(CHIPS)':
 C_PATH='@scm_lib.scm(sch_1):page27_i243@pure_quanta.\2n7002a7\(chips)',
 P_PATH='@scm_lib.scm(sch_1):page27_i243@pure_quanta.\2n7002a7\(chips)',
 PATH='I243',
 DRAWING='@SCM_LIB.SCM(SCH_1):PAGE27',
 PART_TYPE='SMLF',
 PHYS_PAGE='27',
 XY='(3350,-700)',
 ROT='0',
 VER='1',
 LOCATION='Q7',
 CDS_LIB='pure_quanta',
 CDS_PART_NAME='2N7002A7-2N7002A-7,SMLF,IC,BAMA',
 MATERIAL='IC',
 VALUE='2N7002A-7',
 PRIM_FILE='W:/<user>/logical/2n7002a7/chips/chips.prt';

PART_NAME
 Q8 '2N7002A7-2N7002A-7,SMLF,IC,BAMA':;

SECTION_NUMBER 1
 '@SCM_LIB.SCM(SCH_1):PAGE28_I163@PURE_QUANTA.2N7002A7(CHIPS)':
 C_PATH='@scm_lib.scm(sch_1):page28_i163@pure_quanta.\2n7002a7\(chips)',
 P_PATH='@scm_lib.scm(sch_1):page28_i163@pure_quanta.\2n7002a7\(chips)',
 PATH='I163',
 DRAWING='@SCM_LIB.SCM(SCH_1):PAGE28',
 PART_TYPE='SMLF',
 PHYS_PAGE='28',
 XY='(4050,-625)',
 ROT='0',
 VER='1',
 LOCATION='Q8',
 CDS_LIB='pure_quanta',
 CDS_PART_NAME='2N7002A7-2N7002A-7,SMLF,IC,BAMA',
 MATERIAL='IC',
 VALUE='2N7002A-7',
 PRIM_FILE='W:/<user>/logical/2n7002a7/chips/chips.prt';

PART_NAME
 Q9 'MOSFET_NCH_DUAL-PJT138K,SMLF,IA':;

SECTION_NUMBER 1
 '@SCM_LIB.SCM(SCH_1):PAGE49_I6@PURE_QUANTA.MOSFET_NCH_DUAL(CHIPS)':
 C_PATH='@scm_lib.scm(sch_1):page49_i6@pure_quanta.mosfet_nch_dual(chips)',
 P_PATH='@scm_lib.scm(sch_1):page49_i6@pure_quanta.mosfet_nch_dual(chips)',
 PATH='I6',
 DRAWING='@SCM_LIB.SCM(SCH_1):PAGE49',
 PART_TYPE='SMLF',
 PHYS_PAGE='49',
 XY='(-5125,4850)',
 ROT='0',
 VER='1',
 CDS_LIB='pure_quanta',
 CDS_PART_NAME='MOSFET_NCH_DUAL-PJT138K,SMLF,IA',
 MATERIAL='IC',
 VALUE='PJT138K',
 PRIM_FILE='W:/<user>/logical/mosfet_nch_dual/chips/chips.prt';

PART_NAME
 Q10 'MOSFET_N_GSD-DMG6968U-7,SMLF,IA':;

SECTION_NUMBER 1
 '@SCM_LIB.SCM(SCH_1):PAGE17_I227@PURE_QUANTA.MOSFET_N_GSD(CHIPS)':
 C_PATH='@scm_lib.scm(sch_1):page17_i227@pure_quanta.mosfet_n_gsd(chips)',
 P_PATH='@scm_lib.scm(sch_1):page17_i227@pure_quanta.mosfet_n_gsd(chips)',
 PATH='I227',
 DRAWING='@SCM_LIB.SCM(SCH_1):PAGE17',
 SEC_TYPE='',
 PART_TYPE='SMLF',
 PHYS_PAGE='17',
 XY='(2850,-1125)',
 ROT='2',
 VER='1',
 LOCATION='Q10',
 SEC='1',
 CDS_LIB='pure_quanta',
 CDS_PART_NAME='MOSFET_N_GSD-DMG6968U-7,SMLF,IA',
 MATERIAL='IC',
 VALUE='DMG6968U-7',
 PRIM_FILE='W:/<user>/logical/mosfet_n_gsd/chips/chips.prt';

PART_NAME
 Q11 'MOSFET_N_GSD-NX7002AK,SMLF,IC,A':;

SECTION_NUMBER 1
 '@SCM_LIB.SCM(SCH_1):PAGE15_I179@PURE_QUANTA.MOSFET_N_GSD(CHIPS)':
 C_PATH='@scm_lib.scm(sch_1):page15_i179@pure_quanta.mosfet_n_gsd(chips)',
 P_PATH='@scm_lib.scm(sch_1):page15_i179@pure_quanta.mosfet_n_gsd(chips)',
 PATH='I179',
 DRAWING='@SCM_LIB.SCM(SCH_1):PAGE15',
 PART_TYPE='SMLF',
 PHYS_PAGE='15',
 XY='(625,-700)',
 ROT='0',
 VER='1',
 LOCATION='Q11',
 CDS_LIB='pure_quanta',
 CDS_PART_NAME='MOSFET_N_GSD-NX7002AK,SMLF,IC,A',
 MATERIAL='IC',
 VALUE='NX7002AK',
 PRIM_FILE='W:/<user>/logical/mosfet_n_gsd/chips/chips.prt';

PART_NAME
 Q12 'MOSFET_DUAL_6P-2N7002KDW,SMLF,A':;

SECTION_NUMBER 1
 '@SCM_LIB.SCM(SCH_1):PAGE49_I24@PURE_QUANTA.MOSFET_DUAL_6P(CHIPS)':
 C_PATH='@scm_lib.scm(sch_1):page49_i24@pure_quanta.mosfet_dual_6p(chips)',
 P_PATH='@scm_lib.scm(sch_1):page49_i24@pure_quanta.mosfet_dual_6p(chips)',
 PATH='I24',
 DRAWING='@SCM_LIB.SCM(SCH_1):PAGE49',
 PART_TYPE='SMLF',
 PHYS_PAGE='49',
 XY='(-7050,1300)',
 ROT='6',
 VER='1',
 LOCATION='Q12',
 CDS_LIB='pure_quanta',
 CDS_PART_NAME='MOSFET_DUAL_6P-2N7002KDW,SMLF,A',
 MATERIAL='IC',
 VALUE='2N7002KDW',
 PRIM_FILE='W:/<user>/logical/mosfet_dual_6p/chips/chips.prt';

PART_NAME
 Q13 'MOSFET_NCH_DUAL-PJT138K,SMLF,IA':;

SECTION_NUMBER 1
 '@SCM_LIB.SCM(SCH_1):PAGE50_I218@PURE_QUANTA.MOSFET_NCH_DUAL(CHIPS)':
 C_PATH='@scm_lib.scm(sch_1):page50_i218@pure_quanta.mosfet_nch_dual(chips)',
 P_PATH='@scm_lib.scm(sch_1):page50_i218@pure_quanta.mosfet_nch_dual(chips)',
 PATH='I218',
 DRAWING='@SCM_LIB.SCM(SCH_1):PAGE50',
 PART_TYPE='SMLF',
 PHYS_PAGE='50',
 XY='(-1625,-275)',
 ROT='0',
 VER='1',
 CDS_LIB='pure_quanta',
 CDS_PART_NAME='MOSFET_NCH_DUAL-PJT138K,SMLF,IA',
 MATERIAL='IC',
 VALUE='PJT138K',
 PRIM_FILE='W:/<user>/logical/mosfet_nch_dual/chips/chips.prt';

PART_NAME
 R1 'Q_RES_0402LF-0,5%,1/16W,EMPTY,A':;

SECTION_NUMBER 1
 '@SCM_LIB.SCM(SCH_1):PAGE20_I14@PURE_QUANTA.Q_RES(CHIPS)':
 C_PATH='@scm_lib.scm(sch_1):page20_i14@pure_quanta.q_res(chips)',
 P_PATH='@scm_lib.scm(sch_1):page20_i14@pure_quanta.q_res(chips)',
 PATH='I14',
 DRAWING='@SCM_LIB.SCM(SCH_1):PAGE20',
 SEC_TYPE='0402LF',
 PHYS_PAGE='20',
 XY='(-2425,-850)',
 ROT='0',
 VER='1',
 PACK_TYPE='0402LF',
 LOCATION='R1',
 SEC='1',
 CDS_LIB='pure_quanta',
 CDS_PART_NAME='Q_RES_0402LF-0,5%,1/16W,EMPTY,A',
 WATTAGE='1/16W',
 TOLERANCE='5%',
 MATERIAL='EMPTY',
 VALUE='0',
 PRIM_FILE='W:/<user>/logical/q_res/chips/chips.prt';

PART_NAME
 R2 'Q_RES_0402LF-0,5%,1/16W,CHIP,CA':;

SECTION_NUMBER 1
 '@SCM_LIB.SCM(SCH_1):PAGE20_I13@PURE_QUANTA.Q_RES(CHIPS)':
 C_PATH='@scm_lib.scm(sch_1):page20_i13@pure_quanta.q_res(chips)',
 P_PATH='@scm_lib.scm(sch_1):page20_i13@pure_quanta.q_res(chips)',
 PATH='I13',
 DRAWING='@SCM_LIB.SCM(SCH_1):PAGE20',
 SEC_TYPE='0402LF',
 PHYS_PAGE='20',
 XY='(-2425,-1050)',
 ROT='0',
 VER='1',
 PACK_TYPE='0402LF',
 LOCATION='R2',
 SEC='1',
 CDS_LIB='pure_quanta',
 CDS_PART_NAME='Q_RES_0402LF-0,5%,1/16W,CHIP,CA',
 WATTAGE='1/16W',
 TOLERANCE='5%',
 MATERIAL='CHIP',
 VALUE='0',
 PRIM_FILE='W:/<user>/logical/q_res/chips/chips.prt';

PART_NAME
 R3 'Q_RES_0402LF-0,5%,1/16W,CHIP,CA':;

SECTION_NUMBER 1
 '@SCM_LIB.SCM(SCH_1):PAGE20_I17@PURE_QUANTA.Q_RES(CHIPS)':
 C_PATH='@scm_lib.scm(sch_1):page20_i17@pure_quanta.q_res(chips)',
 P_PATH='@scm_lib.scm(sch_1):page20_i17@pure_quanta.q_res(chips)',
 PATH='I17',
 DRAWING='@SCM_LIB.SCM(SCH_1):PAGE20',
 SEC_TYPE='0402LF',
 PHYS_PAGE='20',
 XY='(-2350,-450)',
 ROT='0',
 VER='1',
 PACK_TYPE='0402LF',
 LOCATION='R3',
 SEC='1',
 CDS_LIB='pure_quanta',
 CDS_PART_NAME='Q_RES_0402LF-0,5%,1/16W,CHIP,CA',
 WATTAGE='1/16W',
 TOLERANCE='5%',
 MATERIAL='CHIP',
 VALUE='0',
 PRIM_FILE='W:/<user>/logical/q_res/chips/chips.prt';

PART_NAME
 R4 'Q_RES_0402LF-1K,1%,1/16W,CHIP,A':;

SECTION_NUMBER 1
 '@SCM_LIB.SCM(SCH_1):PAGE20_I141@PURE_QUANTA.Q_RES(CHIPS)':
 C_PATH='@scm_lib.scm(sch_1):page20_i141@pure_quanta.q_res(chips)',
 P_PATH='@scm_lib.scm(sch_1):page20_i141@pure_quanta.q_res(chips)',
 PATH='I141',
 DRAWING='@SCM_LIB.SCM(SCH_1):PAGE20',
 SEC_TYPE='0402LF',
 PHYS_PAGE='20',
 XY='(1400,2775)',
 ROT='0',
 VER='2',
 PACK_TYPE='0402LF',
 LOCATION='R4',
 SEC='1',
 CDS_LIB='pure_quanta',
 CDS_PART_NAME='Q_RES_0402LF-1K,1%,1/16W,CHIP,A',
 WATTAGE='1/16W',
 TOLERANCE='1%',
 MATERIAL='CHIP',
 VALUE='1K',
 PRIM_FILE='W:/<user>/logical/q_res/chips/chips.prt';

PART_NAME
 R5 'Q_RES_0402LF-1K,1%,1/16W,CHIP,A':;

SECTION_NUMBER 1
 '@SCM_LIB.SCM(SCH_1):PAGE20_I142@PURE_QUANTA.Q_RES(CHIPS)':
 C_PATH='@scm_lib.scm(sch_1):page20_i142@pure_quanta.q_res(chips)',
 P_PATH='@scm_lib.scm(sch_1):page20_i142@pure_quanta.q_res(chips)',
 PATH='I142',
 DRAWING='@SCM_LIB.SCM(SCH_1):PAGE20',
 SEC_TYPE='0402LF',
 PHYS_PAGE='20',
 XY='(1750,2775)',
 ROT='0',
 VER='2',
 PACK_TYPE='0402LF',
 LOCATION='R5',
 SEC='1',
 CDS_LIB='pure_quanta',
 CDS_PART_NAME='Q_RES_0402LF-1K,1%,1/16W,CHIP,A',
 WATTAGE='1/16W',
 TOLERANCE='1%',
 MATERIAL='CHIP',
 VALUE='1K',
 PRIM_FILE='W:/<user>/logical/q_res/chips/chips.prt';

PART_NAME
 R6 'Q_RES_0402LF-240,1%,1/16W,CHIPA':;

SECTION_NUMBER 1
 '@SCM_LIB.SCM(SCH_1):PAGE20_I143@PURE_QUANTA.Q_RES(CHIPS)':
 C_PATH='@scm_lib.scm(sch_1):page20_i143@pure_quanta.q_res(chips)',
 P_PATH='@scm_lib.scm(sch_1):page20_i143@pure_quanta.q_res(chips)',
 PATH='I143',
 DRAWING='@SCM_LIB.SCM(SCH_1):PAGE20',
 SEC_TYPE='0402LF',
 PHYS_PAGE='20',
 XY='(2075,2775)',
 ROT='0',
 VER='2',
 PACK_TYPE='0402LF',
 LOCATION='R6',
 SEC='1',
 CDS_LIB='pure_quanta',
 CDS_PART_NAME='Q_RES_0402LF-240,1%,1/16W,CHIPA',
 WATTAGE='1/16W',
 TOLERANCE='1%',
 MATERIAL='CHIP',
 VALUE='240',
 PRIM_FILE='W:/<user>/logical/q_res/chips/chips.prt';

PART_NAME
 R7 'Q_RES_0402LF-60.4,1%,1/16W,CHIA':;

SECTION_NUMBER 1
 '@SCM_LIB.SCM(SCH_1):PAGE20_I90@PURE_QUANTA.Q_RES(CHIPS)':
 C_PATH='@scm_lib.scm(sch_1):page20_i90@pure_quanta.q_res(chips)',
 P_PATH='@scm_lib.scm(sch_1):page20_i90@pure_quanta.q_res(chips)',
 PATH='I90',
 DRAWING='@SCM_LIB.SCM(SCH_1):PAGE20',
 SEC_TYPE='0402LF',
 PHYS_PAGE='20',
 XY='(2075,-950)',
 ROT='0',
 VER='1',
 PACK_TYPE='0402LF',
 LOCATION='R7',
 SEC='1',
 CDS_LIB='pure_quanta',
 CDS_PART_NAME='Q_RES_0402LF-60.4,1%,1/16W,CHIA',
 WATTAGE='1/16W',
 TOLERANCE='1%',
 MATERIAL='CHIP',
 VALUE='60.4',
 PRIM_FILE='W:/<user>/logical/q_res/chips/chips.prt';

PART_NAME
 R8 'Q_RES_0402LF-60.4,1%,1/16W,CHIA':;

SECTION_NUMBER 1
 '@SCM_LIB.SCM(SCH_1):PAGE20_I89@PURE_QUANTA.Q_RES(CHIPS)':
 C_PATH='@scm_lib.scm(sch_1):page20_i89@pure_quanta.q_res(chips)',
 P_PATH='@scm_lib.scm(sch_1):page20_i89@pure_quanta.q_res(chips)',
 PATH='I89',
 DRAWING='@SCM_LIB.SCM(SCH_1):PAGE20',
 SEC_TYPE='0402LF',
 PHYS_PAGE='20',
 XY='(2075,-1150)',
 ROT='0',
 VER='1',
 PACK_TYPE='0402LF',
 LOCATION='R8',
 SEC='1',
 CDS_LIB='pure_quanta',
 CDS_PART_NAME='Q_RES_0402LF-60.4,1%,1/16W,CHIA',
 WATTAGE='1/16W',
 TOLERANCE='1%',
 MATERIAL='CHIP',
 VALUE='60.4',
 PRIM_FILE='W:/<user>/logical/q_res/chips/chips.prt';

PART_NAME
 R9 'Q_RES_0402LF-4.7K,1%,1/16W,CHIA':;

SECTION_NUMBER 1
 '@SCM_LIB.SCM(SCH_1):PAGE20_I111@PURE_QUANTA.Q_RES(CHIPS)':
 C_PATH='@scm_lib.scm(sch_1):page20_i111@pure_quanta.q_res(chips)',
 P_PATH='@scm_lib.scm(sch_1):page20_i111@pure_quanta.q_res(chips)',
 PATH='I111',
 DRAWING='@SCM_LIB.SCM(SCH_1):PAGE20',
 SEC_TYPE='0402LF',
 PHYS_PAGE='20',
 XY='(4325,175)',
 ROT='0',
 VER='1',
 PACK_TYPE='0402LF',
 LOCATION='R9',
 SEC='1',
 CDS_LIB='pure_quanta',
 CDS_PART_NAME='Q_RES_0402LF-4.7K,1%,1/16W,CHIA',
 WATTAGE='1/16W',
 TOLERANCE='1%',
 MATERIAL='CHIP',
 VALUE='4.7K',
 PRIM_FILE='W:/<user>/logical/q_res/chips/chips.prt';

PART_NAME
 R10 'Q_RES_0402LF-0,5%,1/16W,CHIP,CA':;

SECTION_NUMBER 1
 '@SCM_LIB.SCM(SCH_1):PAGE34_I155@PURE_QUANTA.Q_RES(CHIPS)':
 C_PATH='@scm_lib.scm(sch_1):page34_i155@pure_quanta.q_res(chips)',
 P_PATH='@scm_lib.scm(sch_1):page34_i155@pure_quanta.q_res(chips)',
 PATH='I155',
 DRAWING='@SCM_LIB.SCM(SCH_1):PAGE34',
 SEC_TYPE='0402LF',
 PHYS_PAGE='34',
 XY='(-2725,5250)',
 ROT='0',
 VER='1',
 PACK_TYPE='0402LF',
 SEC='1',
 CDS_LIB='pure_quanta',
 CDS_PART_NAME='Q_RES_0402LF-0,5%,1/16W,CHIP,CA',
 WATTAGE='1/16W',
 TOLERANCE='5%',
 MATERIAL='CHIP',
 VALUE='0',
 PRIM_FILE='W:/<user>/logical/q_res/chips/chips.prt';

PART_NAME
 R11 'Q_RES_0402LF-4.7K,1%,1/16W,CHIA':;

SECTION_NUMBER 1
 '@SCM_LIB.SCM(SCH_1):PAGE21_I172@PURE_QUANTA.Q_RES(CHIPS)':
 C_PATH='@scm_lib.scm(sch_1):page21_i172@pure_quanta.q_res(chips)',
 P_PATH='@scm_lib.scm(sch_1):page21_i172@pure_quanta.q_res(chips)',
 PATH='I172',
 DRAWING='@SCM_LIB.SCM(SCH_1):PAGE21',
 PHYS_PAGE='21',
 XY='(-2575,2250)',
 ROT='0',
 VER='2',
 PACK_TYPE='0402LF',
 LOCATION='R11',
 CDS_LIB='pure_quanta',
 CDS_PART_NAME='Q_RES_0402LF-4.7K,1%,1/16W,CHIA',
 WATTAGE='1/16W',
 TOLERANCE='1%',
 MATERIAL='CHIP',
 VALUE='4.7K',
 PRIM_FILE='W:/<user>/logical/q_res/chips/chips.prt';

PART_NAME
 R12 'Q_RES_0402LF-4.7K,1%,1/16W,EMPA':;

SECTION_NUMBER 1
 '@SCM_LIB.SCM(SCH_1):PAGE26_I9@PURE_QUANTA.Q_RES(CHIPS)':
 C_PATH='@scm_lib.scm(sch_1):page26_i9@pure_quanta.q_res(chips)',
 P_PATH='@scm_lib.scm(sch_1):page26_i9@pure_quanta.q_res(chips)',
 PATH='I9',
 DRAWING='@SCM_LIB.SCM(SCH_1):PAGE26',
 SEC_TYPE='0402LF',
 PHYS_PAGE='26',
 XY='(-1800,1175)',
 ROT='0',
 VER='2',
 PACK_TYPE='0402LF',
 LOCATION='R12',
 SEC='1',
 CDS_LIB='pure_quanta',
 CDS_PART_NAME='Q_RES_0402LF-4.7K,1%,1/16W,EMPA',
 WATTAGE='1/16W',
 TOLERANCE='1%',
 MATERIAL='EMPTY',
 VALUE='4.7K',
 PRIM_FILE='W:/<user>/logical/q_res/chips/chips.prt';

PART_NAME
 R13 'Q_RES_0402LF-4.7K,1%,1/16W,EMPA':;

SECTION_NUMBER 1
 '@SCM_LIB.SCM(SCH_1):PAGE26_I11@PURE_QUANTA.Q_RES(CHIPS)':
 C_PATH='@scm_lib.scm(sch_1):page26_i11@pure_quanta.q_res(chips)',
 P_PATH='@scm_lib.scm(sch_1):page26_i11@pure_quanta.q_res(chips)',
 PATH='I11',
 DRAWING='@SCM_LIB.SCM(SCH_1):PAGE26',
 SEC_TYPE='0402LF',
 PHYS_PAGE='26',
 XY='(-1450,1175)',
 ROT='0',
 VER='2',
 PACK_TYPE='0402LF',
 LOCATION='R13',
 SEC='1',
 CDS_LIB='pure_quanta',
 CDS_PART_NAME='Q_RES_0402LF-4.7K,1%,1/16W,EMPA',
 WATTAGE='1/16W',
 TOLERANCE='1%',
 MATERIAL='EMPTY',
 VALUE='4.7K',
 PRIM_FILE='W:/<user>/logical/q_res/chips/chips.prt';

PART_NAME
 R14 'Q_RES_0402LF-4.7K,1%,1/16W,EMPA':;

SECTION_NUMBER 1
 '@SCM_LIB.SCM(SCH_1):PAGE26_I14@PURE_QUANTA.Q_RES(CHIPS)':
 C_PATH='@scm_lib.scm(sch_1):page26_i14@pure_quanta.q_res(chips)',
 P_PATH='@scm_lib.scm(sch_1):page26_i14@pure_quanta.q_res(chips)',
 PATH='I14',
 DRAWING='@SCM_LIB.SCM(SCH_1):PAGE26',
 SEC_TYPE='0402LF',
 PHYS_PAGE='26',
 XY='(-1100,1175)',
 ROT='0',
 VER='2',
 PACK_TYPE='0402LF',
 LOCATION='R14',
 SEC='1',
 CDS_LIB='pure_quanta',
 CDS_PART_NAME='Q_RES_0402LF-4.7K,1%,1/16W,EMPA',
 WATTAGE='1/16W',
 TOLERANCE='1%',
 MATERIAL='EMPTY',
 VALUE='4.7K',
 PRIM_FILE='W:/<user>/logical/q_res/chips/chips.prt';

PART_NAME
 R15 'Q_RES_0402LF-1K,1%,1/16W,CHIP,A':;

SECTION_NUMBER 1
 '@SCM_LIB.SCM(SCH_1):PAGE26_I32@PURE_QUANTA.Q_RES(CHIPS)':
 C_PATH='@scm_lib.scm(sch_1):page26_i32@pure_quanta.q_res(chips)',
 P_PATH='@scm_lib.scm(sch_1):page26_i32@pure_quanta.q_res(chips)',
 PATH='I32',
 DRAWING='@SCM_LIB.SCM(SCH_1):PAGE26',
 PHYS_PAGE='26',
 XY='(1075,450)',
 ROT='0',
 VER='2',
 PACK_TYPE='0402LF',
 LOCATION='R15',
 CDS_LIB='pure_quanta',
 CDS_PART_NAME='Q_RES_0402LF-1K,1%,1/16W,CHIP,A',
 WATTAGE='1/16W',
 TOLERANCE='1%',
 MATERIAL='CHIP',
 VALUE='1K',
 PRIM_FILE='W:/<user>/logical/q_res/chips/chips.prt';

PART_NAME
 R16 'Q_RES_0402LF-2.21K,1%,1/16W,EMA':;

SECTION_NUMBER 1
 '@SCM_LIB.SCM(SCH_1):PAGE23_I75@PURE_QUANTA.Q_RES(CHIPS)':
 C_PATH='@scm_lib.scm(sch_1):page23_i75@pure_quanta.q_res(chips)',
 P_PATH='@scm_lib.scm(sch_1):page23_i75@pure_quanta.q_res(chips)',
 PATH='I75',
 DRAWING='@SCM_LIB.SCM(SCH_1):PAGE23',
 PHYS_PAGE='23',
 XY='(4875,3575)',
 ROT='0',
 VER='1',
 PACK_TYPE='0402LF',
 LOCATION='R16',
 CDS_LIB='pure_quanta',
 CDS_PART_NAME='Q_RES_0402LF-2.21K,1%,1/16W,EMA',
 WATTAGE='1/16W',
 TOLERANCE='1%',
 MATERIAL='EMPTY',
 VALUE='2.21K',
 PRIM_FILE='W:/<user>/logical/q_res/chips/chips.prt';

PART_NAME
 R17 'Q_RES_0402LF-2.21K,1%,1/16W,EMA':;

SECTION_NUMBER 1
 '@SCM_LIB.SCM(SCH_1):PAGE23_I68@PURE_QUANTA.Q_RES(CHIPS)':
 C_PATH='@scm_lib.scm(sch_1):page23_i68@pure_quanta.q_res(chips)',
 P_PATH='@scm_lib.scm(sch_1):page23_i68@pure_quanta.q_res(chips)',
 PATH='I68',
 DRAWING='@SCM_LIB.SCM(SCH_1):PAGE23',
 PHYS_PAGE='23',
 XY='(4750,3425)',
 ROT='0',
 VER='1',
 PACK_TYPE='0402LF',
 LOCATION='R17',
 CDS_LIB='pure_quanta',
 CDS_PART_NAME='Q_RES_0402LF-2.21K,1%,1/16W,EMA',
 WATTAGE='1/16W',
 TOLERANCE='1%',
 MATERIAL='EMPTY',
 VALUE='2.21K',
 PRIM_FILE='W:/<user>/logical/q_res/chips/chips.prt';

PART_NAME
 R18 'Q_RES_0402LF-0,5%,1/16W,CHIP,CA':;

SECTION_NUMBER 1
 '@SCM_LIB.SCM(SCH_1):PAGE23_I19@PURE_QUANTA.Q_RES(CHIPS)':
 C_PATH='@scm_lib.scm(sch_1):page23_i19@pure_quanta.q_res(chips)',
 P_PATH='@scm_lib.scm(sch_1):page23_i19@pure_quanta.q_res(chips)',
 PATH='I19',
 DRAWING='@SCM_LIB.SCM(SCH_1):PAGE23',
 PHYS_PAGE='23',
 XY='(-1675,2825)',
 ROT='0',
 VER='1',
 PACK_TYPE='0402LF',
 LOCATION='R18',
 CDS_LIB='pure_quanta',
 CDS_PART_NAME='Q_RES_0402LF-0,5%,1/16W,CHIP,CA',
 WATTAGE='1/16W',
 TOLERANCE='5%',
 MATERIAL='CHIP',
 VALUE='0',
 PRIM_FILE='W:/<user>/logical/q_res/chips/chips.prt';

PART_NAME
 R19 'Q_RES_0402LF-0,5%,1/16W,CHIP,CA':;

SECTION_NUMBER 1
 '@SCM_LIB.SCM(SCH_1):PAGE15_I141@PURE_QUANTA.Q_RES(CHIPS)':
 C_PATH='@scm_lib.scm(sch_1):page15_i141@pure_quanta.q_res(chips)',
 P_PATH='@scm_lib.scm(sch_1):page15_i141@pure_quanta.q_res(chips)',
 PATH='I141',
 DRAWING='@SCM_LIB.SCM(SCH_1):PAGE15',
 PHYS_PAGE='15',
 XY='(2975,4125)',
 ROT='0',
 VER='1',
 PACK_TYPE='0402LF',
 LOCATION='R19',
 CDS_LIB='pure_quanta',
 CDS_PART_NAME='Q_RES_0402LF-0,5%,1/16W,CHIP,CA',
 WATTAGE='1/16W',
 TOLERANCE='5%',
 MATERIAL='CHIP',
 VALUE='0',
 PRIM_FILE='W:/<user>/logical/q_res/chips/chips.prt';

PART_NAME
 R20 'Q_RES_0402LF-0,5%,1/16W,CHIP,CA':;

SECTION_NUMBER 1
 '@SCM_LIB.SCM(SCH_1):PAGE15_I140@PURE_QUANTA.Q_RES(CHIPS)':
 C_PATH='@scm_lib.scm(sch_1):page15_i140@pure_quanta.q_res(chips)',
 P_PATH='@scm_lib.scm(sch_1):page15_i140@pure_quanta.q_res(chips)',
 PATH='I140',
 DRAWING='@SCM_LIB.SCM(SCH_1):PAGE15',
 PHYS_PAGE='15',
 XY='(2975,4075)',
 ROT='0',
 VER='1',
 PACK_TYPE='0402LF',
 LOCATION='R20',
 CDS_LIB='pure_quanta',
 CDS_PART_NAME='Q_RES_0402LF-0,5%,1/16W,CHIP,CA',
 WATTAGE='1/16W',
 TOLERANCE='5%',
 MATERIAL='CHIP',
 VALUE='0',
 PRIM_FILE='W:/<user>/logical/q_res/chips/chips.prt';

PART_NAME
 R21 'Q_RES_0402LF-10,1%,1/16W,CHIP,A':;

SECTION_NUMBER 1
 '@SCM_LIB.SCM(SCH_1):PAGE15_I133@PURE_QUANTA.Q_RES(CHIPS)':
 C_PATH='@scm_lib.scm(sch_1):page15_i133@pure_quanta.q_res(chips)',
 P_PATH='@scm_lib.scm(sch_1):page15_i133@pure_quanta.q_res(chips)',
 PATH='I133',
 DRAWING='@SCM_LIB.SCM(SCH_1):PAGE15',
 PHYS_PAGE='15',
 XY='(3000,4275)',
 ROT='0',
 VER='1',
 PACK_TYPE='0402LF',
 LOCATION='R21',
 CDS_LIB='pure_quanta',
 CDS_PART_NAME='Q_RES_0402LF-10,1%,1/16W,CHIP,A',
 WATTAGE='1/16W',
 TOLERANCE='1%',
 MATERIAL='CHIP',
 VALUE='10',
 PRIM_FILE='W:/<user>/logical/q_res/chips/chips.prt';

PART_NAME
 R22 'Q_RES_0402LF-150,1%,1/16W,CHIPA':;

SECTION_NUMBER 1
 '@SCM_LIB.SCM(SCH_1):PAGE15_I151@PURE_QUANTA.Q_RES(CHIPS)':
 C_PATH='@scm_lib.scm(sch_1):page15_i151@pure_quanta.q_res(chips)',
 P_PATH='@scm_lib.scm(sch_1):page15_i151@pure_quanta.q_res(chips)',
 PATH='I151',
 DRAWING='@SCM_LIB.SCM(SCH_1):PAGE15',
 PHYS_PAGE='15',
 XY='(5600,4375)',
 ROT='0',
 VER='1',
 PACK_TYPE='0402LF',
 LOCATION='R22',
 CDS_LIB='pure_quanta',
 CDS_PART_NAME='Q_RES_0402LF-150,1%,1/16W,CHIPA',
 WATTAGE='1/16W',
 TOLERANCE='1%',
 MATERIAL='CHIP',
 VALUE='150',
 PRIM_FILE='W:/<user>/logical/q_res/chips/chips.prt';

PART_NAME
 R23 'Q_RES_0402LF-150,1%,1/16W,CHIPA':;

SECTION_NUMBER 1
 '@SCM_LIB.SCM(SCH_1):PAGE15_I150@PURE_QUANTA.Q_RES(CHIPS)':
 C_PATH='@scm_lib.scm(sch_1):page15_i150@pure_quanta.q_res(chips)',
 P_PATH='@scm_lib.scm(sch_1):page15_i150@pure_quanta.q_res(chips)',
 PATH='I150',
 DRAWING='@SCM_LIB.SCM(SCH_1):PAGE15',
 PHYS_PAGE='15',
 XY='(5600,4275)',
 ROT='0',
 VER='1',
 PACK_TYPE='0402LF',
 LOCATION='R23',
 CDS_LIB='pure_quanta',
 CDS_PART_NAME='Q_RES_0402LF-150,1%,1/16W,CHIPA',
 WATTAGE='1/16W',
 TOLERANCE='1%',
 MATERIAL='CHIP',
 VALUE='150',
 PRIM_FILE='W:/<user>/logical/q_res/chips/chips.prt';

PART_NAME
 R24 'Q_RES_0402LF-10,1%,1/16W,CHIP,A':;

SECTION_NUMBER 1
 '@SCM_LIB.SCM(SCH_1):PAGE15_I134@PURE_QUANTA.Q_RES(CHIPS)':
 C_PATH='@scm_lib.scm(sch_1):page15_i134@pure_quanta.q_res(chips)',
 P_PATH='@scm_lib.scm(sch_1):page15_i134@pure_quanta.q_res(chips)',
 PATH='I134',
 DRAWING='@SCM_LIB.SCM(SCH_1):PAGE15',
 PHYS_PAGE='15',
 XY='(3000,4325)',
 ROT='0',
 VER='1',
 PACK_TYPE='0402LF',
 LOCATION='R24',
 CDS_LIB='pure_quanta',
 CDS_PART_NAME='Q_RES_0402LF-10,1%,1/16W,CHIP,A',
 WATTAGE='1/16W',
 TOLERANCE='1%',
 MATERIAL='CHIP',
 VALUE='10',
 PRIM_FILE='W:/<user>/logical/q_res/chips/chips.prt';

PART_NAME
 R25 'Q_RES_0402LF-150,1%,1/16W,CHIPA':;

SECTION_NUMBER 1
 '@SCM_LIB.SCM(SCH_1):PAGE15_I149@PURE_QUANTA.Q_RES(CHIPS)':
 C_PATH='@scm_lib.scm(sch_1):page15_i149@pure_quanta.q_res(chips)',
 P_PATH='@scm_lib.scm(sch_1):page15_i149@pure_quanta.q_res(chips)',
 PATH='I149',
 DRAWING='@SCM_LIB.SCM(SCH_1):PAGE15',
 PHYS_PAGE='15',
 XY='(5600,4175)',
 ROT='0',
 VER='1',
 PACK_TYPE='0402LF',
 LOCATION='R25',
 CDS_LIB='pure_quanta',
 CDS_PART_NAME='Q_RES_0402LF-150,1%,1/16W,CHIPA',
 WATTAGE='1/16W',
 TOLERANCE='1%',
 MATERIAL='CHIP',
 VALUE='150',
 PRIM_FILE='W:/<user>/logical/q_res/chips/chips.prt';

PART_NAME
 R26 'Q_RES_0402LF-10,1%,1/16W,CHIP,A':;

SECTION_NUMBER 1
 '@SCM_LIB.SCM(SCH_1):PAGE15_I142@PURE_QUANTA.Q_RES(CHIPS)':
 C_PATH='@scm_lib.scm(sch_1):page15_i142@pure_quanta.q_res(chips)',
 P_PATH='@scm_lib.scm(sch_1):page15_i142@pure_quanta.q_res(chips)',
 PATH='I142',
 DRAWING='@SCM_LIB.SCM(SCH_1):PAGE15',
 PHYS_PAGE='15',
 XY='(3000,4225)',
 ROT='0',
 VER='1',
 PACK_TYPE='0402LF',
 LOCATION='R26',
 CDS_LIB='pure_quanta',
 CDS_PART_NAME='Q_RES_0402LF-10,1%,1/16W,CHIP,A',
 WATTAGE='1/16W',
 TOLERANCE='1%',
 MATERIAL='CHIP',
 VALUE='10',
 PRIM_FILE='W:/<user>/logical/q_res/chips/chips.prt';

PART_NAME
 R27 'Q_RES_0603LF-0,5%,1/10W,EMPTY,A':;

SECTION_NUMBER 1
 '@SCM_LIB.SCM(SCH_1):PAGE23_I40@PURE_QUANTA.Q_RES(CHIPS)':
 C_PATH='@scm_lib.scm(sch_1):page23_i40@pure_quanta.q_res(chips)',
 P_PATH='@scm_lib.scm(sch_1):page23_i40@pure_quanta.q_res(chips)',
 PATH='I40',
 DRAWING='@SCM_LIB.SCM(SCH_1):PAGE23',
 PHYS_PAGE='23',
 XY='(-1875,4075)',
 ROT='0',
 VER='1',
 PACK_TYPE='0603LF',
 LOCATION='R27',
 CDS_LIB='pure_quanta',
 CDS_PART_NAME='Q_RES_0603LF-0,5%,1/10W,EMPTY,A',
 WATTAGE='1/10W',
 TOLERANCE='5%',
 MATERIAL='EMPTY',
 VALUE='0',
 PRIM_FILE='W:/<user>/logical/q_res/chips/chips.prt';

PART_NAME
 R28 'Q_RES_0402LF-33.2,1%,1/16W,CHIA':;

SECTION_NUMBER 1
 '@SCM_LIB.SCM(SCH_1):PAGE23_I99@PURE_QUANTA.Q_RES(CHIPS)':
 C_PATH='@scm_lib.scm(sch_1):page23_i99@pure_quanta.q_res(chips)',
 P_PATH='@scm_lib.scm(sch_1):page23_i99@pure_quanta.q_res(chips)',
 PATH='I99',
 DRAWING='@SCM_LIB.SCM(SCH_1):PAGE23',
 PHYS_PAGE='23',
 XY='(-925,3300)',
 ROT='0',
 VER='1',
 PACK_TYPE='0402LF',
 LOCATION='R28',
 CDS_LIB='pure_quanta',
 CDS_PART_NAME='Q_RES_0402LF-33.2,1%,1/16W,CHIA',
 WATTAGE='1/16W',
 TOLERANCE='1%',
 MATERIAL='CHIP',
 VALUE='33.2',
 PRIM_FILE='W:/<user>/logical/q_res/chips/chips.prt';

PART_NAME
 R29 'Q_RES_0402LF-33.2,1%,1/16W,CHIA':;

SECTION_NUMBER 1
 '@SCM_LIB.SCM(SCH_1):PAGE23_I34@PURE_QUANTA.Q_RES(CHIPS)':
 C_PATH='@scm_lib.scm(sch_1):page23_i34@pure_quanta.q_res(chips)',
 P_PATH='@scm_lib.scm(sch_1):page23_i34@pure_quanta.q_res(chips)',
 PATH='I34',
 DRAWING='@SCM_LIB.SCM(SCH_1):PAGE23',
 PHYS_PAGE='23',
 XY='(-925,3100)',
 ROT='0',
 VER='1',
 PACK_TYPE='0402LF',
 LOCATION='R29',
 CDS_LIB='pure_quanta',
 CDS_PART_NAME='Q_RES_0402LF-33.2,1%,1/16W,CHIA',
 WATTAGE='1/16W',
 TOLERANCE='1%',
 MATERIAL='CHIP',
 VALUE='33.2',
 PRIM_FILE='W:/<user>/logical/q_res/chips/chips.prt';

PART_NAME
 R30 'Q_RES_0402LF-0,5%,1/16W,CHIP,CA':;

SECTION_NUMBER 1
 '@SCM_LIB.SCM(SCH_1):PAGE23_I39@PURE_QUANTA.Q_RES(CHIPS)':
 C_PATH='@scm_lib.scm(sch_1):page23_i39@pure_quanta.q_res(chips)',
 P_PATH='@scm_lib.scm(sch_1):page23_i39@pure_quanta.q_res(chips)',
 PATH='I39',
 DRAWING='@SCM_LIB.SCM(SCH_1):PAGE23',
 PHYS_PAGE='23',
 XY='(-450,3475)',
 ROT='2',
 VER='2',
 PACK_TYPE='0402LF',
 LOCATION='R30',
 CDS_LIB='pure_quanta',
 CDS_PART_NAME='Q_RES_0402LF-0,5%,1/16W,CHIP,CA',
 WATTAGE='1/16W',
 TOLERANCE='5%',
 MATERIAL='CHIP',
 VALUE='0',
 PRIM_FILE='W:/<user>/logical/q_res/chips/chips.prt';

PART_NAME
 R31 'Q_RES_0402LF-4.7K,1%,1/16W,CHIA':;

SECTION_NUMBER 1
 '@SCM_LIB.SCM(SCH_1):PAGE23_I27@PURE_QUANTA.Q_RES(CHIPS)':
 C_PATH='@scm_lib.scm(sch_1):page23_i27@pure_quanta.q_res(chips)',
 P_PATH='@scm_lib.scm(sch_1):page23_i27@pure_quanta.q_res(chips)',
 PATH='I27',
 DRAWING='@SCM_LIB.SCM(SCH_1):PAGE23',
 PHYS_PAGE='23',
 XY='(-1100,-200)',
 ROT='0',
 VER='2',
 PACK_TYPE='0402LF',
 LOCATION='R31',
 CDS_LIB='pure_quanta',
 CDS_PART_NAME='Q_RES_0402LF-4.7K,1%,1/16W,CHIA',
 WATTAGE='1/16W',
 TOLERANCE='1%',
 MATERIAL='CHIP',
 VALUE='4.7K',
 PRIM_FILE='W:/<user>/logical/q_res/chips/chips.prt';

PART_NAME
 R32 'Q_RES_0402LF-4.7K,1%,1/16W,CHIA':;

SECTION_NUMBER 1
 '@SCM_LIB.SCM(SCH_1):PAGE23_I50@PURE_QUANTA.Q_RES(CHIPS)':
 C_PATH='@scm_lib.scm(sch_1):page23_i50@pure_quanta.q_res(chips)',
 P_PATH='@scm_lib.scm(sch_1):page23_i50@pure_quanta.q_res(chips)',
 PATH='I50',
 DRAWING='@SCM_LIB.SCM(SCH_1):PAGE23',
 PHYS_PAGE='23',
 XY='(-800,-200)',
 ROT='0',
 VER='2',
 PACK_TYPE='0402LF',
 LOCATION='R32',
 CDS_LIB='pure_quanta',
 CDS_PART_NAME='Q_RES_0402LF-4.7K,1%,1/16W,CHIA',
 WATTAGE='1/16W',
 TOLERANCE='1%',
 MATERIAL='CHIP',
 VALUE='4.7K',
 PRIM_FILE='W:/<user>/logical/q_res/chips/chips.prt';

PART_NAME
 R33 'Q_RES_0402LF-33.2,1%,1/16W,CHIA':;

SECTION_NUMBER 1
 '@SCM_LIB.SCM(SCH_1):PAGE46_I117@PURE_QUANTA.Q_RES(CHIPS)':
 C_PATH='@scm_lib.scm(sch_1):page46_i117@pure_quanta.q_res(chips)',
 P_PATH='@scm_lib.scm(sch_1):page46_i117@pure_quanta.q_res(chips)',
 PATH='I117',
 DRAWING='@SCM_LIB.SCM(SCH_1):PAGE46',
 PHYS_PAGE='46',
 XY='(-9900,-5800)',
 ROT='0',
 VER='1',
 PACK_TYPE='0402LF',
 LOCATION='R33',
 CDS_LIB='pure_quanta',
 CDS_PART_NAME='Q_RES_0402LF-33.2,1%,1/16W,CHIA',
 WATTAGE='1/16W',
 TOLERANCE='1%',
 MATERIAL='CHIP',
 VALUE='33.2',
 PRIM_FILE='W:/<user>/logical/q_res/chips/chips.prt';

PART_NAME
 R34 'Q_RES_0402LF-4.7K,1%,1/16W,EMPA':;

SECTION_NUMBER 1
 '@SCM_LIB.SCM(SCH_1):PAGE11_I194@PURE_QUANTA.Q_RES(CHIPS)':
 C_PATH='@scm_lib.scm(sch_1):page11_i194@pure_quanta.q_res(chips)',
 P_PATH='@scm_lib.scm(sch_1):page11_i194@pure_quanta.q_res(chips)',
 PATH='I194',
 DRAWING='@SCM_LIB.SCM(SCH_1):PAGE11',
 PHYS_PAGE='11',
 XY='(-3375,6975)',
 ROT='0',
 VER='1',
 PACK_TYPE='0402LF',
 LOCATION='R34',
 CDS_LIB='pure_quanta',
 CDS_PART_NAME='Q_RES_0402LF-4.7K,1%,1/16W,EMPA',
 WATTAGE='1/16W',
 TOLERANCE='1%',
 MATERIAL='EMPTY',
 VALUE='4.7K',
 PRIM_FILE='W:/<user>/logical/q_res/chips/chips.prt';

PART_NAME
 R35 'Q_RES_0402LF-0,5%,1/16W,CHIP,CA':;

SECTION_NUMBER 1
 '@SCM_LIB.SCM(SCH_1):PAGE53_I58@PURE_QUANTA.Q_RES(CHIPS)':
 C_PATH='@scm_lib.scm(sch_1):page53_i58@pure_quanta.q_res(chips)',
 P_PATH='@scm_lib.scm(sch_1):page53_i58@pure_quanta.q_res(chips)',
 PATH='I58',
 DRAWING='@SCM_LIB.SCM(SCH_1):PAGE53',
 PHYS_PAGE='53',
 XY='(-2525,-125)',
 ROT='0',
 VER='1',
 PACK_TYPE='0402LF',
 LOCATION='R35',
 CDS_LIB='pure_quanta',
 CDS_PART_NAME='Q_RES_0402LF-0,5%,1/16W,CHIP,CA',
 WATTAGE='1/16W',
 TOLERANCE='5%',
 MATERIAL='CHIP',
 VALUE='0',
 PRIM_FILE='W:/<user>/logical/q_res/chips/chips.prt';

PART_NAME
 R36 'Q_RES_0402LF-33.2,1%,1/16W,CHIA':;

SECTION_NUMBER 1
 '@SCM_LIB.SCM(SCH_1):PAGE10_I458@PURE_QUANTA.Q_RES(CHIPS)':
 C_PATH='@scm_lib.scm(sch_1):page10_i458@pure_quanta.q_res(chips)',
 P_PATH='@scm_lib.scm(sch_1):page10_i458@pure_quanta.q_res(chips)',
 PATH='I458',
 DRAWING='@SCM_LIB.SCM(SCH_1):PAGE10',
 SEC_TYPE='0402LF',
 PHYS_PAGE='10',
 XY='(-10350,2200)',
 ROT='0',
 VER='1',
 PACK_TYPE='0402LF',
 LOCATION='R36',
 SEC='1',
 CDS_LIB='pure_quanta',
 CDS_PART_NAME='Q_RES_0402LF-33.2,1%,1/16W,CHIA',
 WATTAGE='1/16W',
 TOLERANCE='1%',
 MATERIAL='CHIP',
 VALUE='33.2',
 PRIM_FILE='W:/<user>/logical/q_res/chips/chips.prt';

PART_NAME
 R37 'Q_RES_0402LF-33.2,1%,1/16W,CHIA':;

SECTION_NUMBER 1
 '@SCM_LIB.SCM(SCH_1):PAGE13_I133@PURE_QUANTA.Q_RES(CHIPS)':
 C_PATH='@scm_lib.scm(sch_1):page13_i133@pure_quanta.q_res(chips)',
 P_PATH='@scm_lib.scm(sch_1):page13_i133@pure_quanta.q_res(chips)',
 PATH='I133',
 DRAWING='@SCM_LIB.SCM(SCH_1):PAGE13',
 PHYS_PAGE='13',
 XY='(-1825,3625)',
 ROT='0',
 VER='1',
 PACK_TYPE='0402LF',
 LOCATION='R37',
 CDS_LIB='pure_quanta',
 CDS_PART_NAME='Q_RES_0402LF-33.2,1%,1/16W,CHIA',
 WATTAGE='1/16W',
 TOLERANCE='1%',
 MATERIAL='CHIP',
 VALUE='33.2',
 PRIM_FILE='W:/<user>/logical/q_res/chips/chips.prt';

PART_NAME
 R38 'Q_RES_0402LF-4.7K,1%,1/16W,CHIA':;

SECTION_NUMBER 1
 '@SCM_LIB.SCM(SCH_1):PAGE13_I200@PURE_QUANTA.Q_RES(CHIPS)':
 C_PATH='@scm_lib.scm(sch_1):page13_i200@pure_quanta.q_res(chips)',
 P_PATH='@scm_lib.scm(sch_1):page13_i200@pure_quanta.q_res(chips)',
 PATH='I200',
 DRAWING='@SCM_LIB.SCM(SCH_1):PAGE13',
 PHYS_PAGE='13',
 XY='(2750,75)',
 ROT='0',
 VER='1',
 PACK_TYPE='0402LF',
 LOCATION='R38',
 CDS_LIB='pure_quanta',
 CDS_PART_NAME='Q_RES_0402LF-4.7K,1%,1/16W,CHIA',
 WATTAGE='1/16W',
 TOLERANCE='1%',
 MATERIAL='CHIP',
 VALUE='4.7K',
 PRIM_FILE='W:/<user>/logical/q_res/chips/chips.prt';

PART_NAME
 R39 'Q_RES_0402LF-0,5%,1/16W,CHIP,CA':;

SECTION_NUMBER 1
 '@SCM_LIB.SCM(SCH_1):PAGE30_I267@PURE_QUANTA.Q_RES(CHIPS)':
 C_PATH='@scm_lib.scm(sch_1):page30_i267@pure_quanta.q_res(chips)',
 P_PATH='@scm_lib.scm(sch_1):page30_i267@pure_quanta.q_res(chips)',
 PATH='I267',
 DRAWING='@SCM_LIB.SCM(SCH_1):PAGE30',
 PHYS_PAGE='30',
 XY='(475,4175)',
 ROT='0',
 VER='1',
 PACK_TYPE='0402LF',
 LOCATION='R39',
 CDS_LIB='pure_quanta',
 CDS_PART_NAME='Q_RES_0402LF-0,5%,1/16W,CHIP,CA',
 WATTAGE='1/16W',
 TOLERANCE='5%',
 MATERIAL='CHIP',
 VALUE='0',
 PRIM_FILE='W:/<user>/logical/q_res/chips/chips.prt';

PART_NAME
 R40 'Q_RES_0402LF-2K,1%,1/16W,EMPTYA':;

SECTION_NUMBER 1
 '@SCM_LIB.SCM(SCH_1):PAGE11_I171@PURE_QUANTA.Q_RES(CHIPS)':
 C_PATH='@scm_lib.scm(sch_1):page11_i171@pure_quanta.q_res(chips)',
 P_PATH='@scm_lib.scm(sch_1):page11_i171@pure_quanta.q_res(chips)',
 PATH='I171',
 DRAWING='@SCM_LIB.SCM(SCH_1):PAGE11',
 PHYS_PAGE='11',
 XY='(-200,3625)',
 ROT='0',
 VER='1',
 PACK_TYPE='0402LF',
 LOCATION='R40',
 CDS_LIB='pure_quanta',
 CDS_PART_NAME='Q_RES_0402LF-2K,1%,1/16W,EMPTYA',
 WATTAGE='1/16W',
 TOLERANCE='1%',
 MATERIAL='EMPTY',
 VALUE='2K',
 PRIM_FILE='W:/<user>/logical/q_res/chips/chips.prt';

PART_NAME
 R41 'Q_RES_0402LF-10K,1%,1/16W,EMPTA':;

SECTION_NUMBER 1
 '@SCM_LIB.SCM(SCH_1):PAGE11_I225@PURE_QUANTA.Q_RES(CHIPS)':
 C_PATH='@scm_lib.scm(sch_1):page11_i225@pure_quanta.q_res(chips)',
 P_PATH='@scm_lib.scm(sch_1):page11_i225@pure_quanta.q_res(chips)',
 PATH='I225',
 DRAWING='@SCM_LIB.SCM(SCH_1):PAGE11',
 PHYS_PAGE='11',
 XY='(-3325,6225)',
 ROT='0',
 VER='1',
 PACK_TYPE='0402LF',
 LOCATION='R41',
 CDS_LIB='pure_quanta',
 CDS_PART_NAME='Q_RES_0402LF-10K,1%,1/16W,EMPTA',
 WATTAGE='1/16W',
 TOLERANCE='1%',
 MATERIAL='EMPTY',
 VALUE='10K',
 PRIM_FILE='W:/<user>/logical/q_res/chips/chips.prt';

PART_NAME
 R42 'Q_RES_0402LF-4.7K,1%,1/16W,CHIA':;

SECTION_NUMBER 1
 '@SCM_LIB.SCM(SCH_1):PAGE27_I222@PURE_QUANTA.Q_RES(CHIPS)':
 C_PATH='@scm_lib.scm(sch_1):page27_i222@pure_quanta.q_res(chips)',
 P_PATH='@scm_lib.scm(sch_1):page27_i222@pure_quanta.q_res(chips)',
 PATH='I222',
 DRAWING='@SCM_LIB.SCM(SCH_1):PAGE27',
 PHYS_PAGE='27',
 XY='(2375,-275)',
 ROT='0',
 VER='2',
 PACK_TYPE='0402LF',
 LOCATION='R42',
 CDS_LIB='pure_quanta',
 CDS_PART_NAME='Q_RES_0402LF-4.7K,1%,1/16W,CHIA',
 WATTAGE='1/16W',
 TOLERANCE='1%',
 MATERIAL='CHIP',
 VALUE='4.7K',
 PRIM_FILE='W:/<user>/logical/q_res/chips/chips.prt';

PART_NAME
 R43 'Q_RES_0402LF-220,1%,1/16W,CHIPA':;

SECTION_NUMBER 1
 '@SCM_LIB.SCM(SCH_1):PAGE49_I79@PURE_QUANTA.Q_RES(CHIPS)':
 C_PATH='@scm_lib.scm(sch_1):page49_i79@pure_quanta.q_res(chips)',
 P_PATH='@scm_lib.scm(sch_1):page49_i79@pure_quanta.q_res(chips)',
 PATH='I79',
 DRAWING='@SCM_LIB.SCM(SCH_1):PAGE49',
 PHYS_PAGE='49',
 XY='(-3200,5550)',
 ROT='1',
 VER='1',
 PACK_TYPE='0402LF',
 CDS_LIB='pure_quanta',
 CDS_PART_NAME='Q_RES_0402LF-220,1%,1/16W,CHIPA',
 WATTAGE='1/16W',
 TOLERANCE='1%',
 MATERIAL='CHIP',
 VALUE='220',
 PRIM_FILE='W:/<user>/logical/q_res/chips/chips.prt';

PART_NAME
 R44 'Q_RES_0402LF-4.7K,1%,1/16W,EMPA':;

SECTION_NUMBER 1
 '@SCM_LIB.SCM(SCH_1):PAGE11_I175@PURE_QUANTA.Q_RES(CHIPS)':
 C_PATH='@scm_lib.scm(sch_1):page11_i175@pure_quanta.q_res(chips)',
 P_PATH='@scm_lib.scm(sch_1):page11_i175@pure_quanta.q_res(chips)',
 PATH='I175',
 DRAWING='@SCM_LIB.SCM(SCH_1):PAGE11',
 PHYS_PAGE='11',
 XY='(-3325,6025)',
 ROT='0',
 VER='1',
 PACK_TYPE='0402LF',
 LOCATION='R44',
 CDS_LIB='pure_quanta',
 CDS_PART_NAME='Q_RES_0402LF-4.7K,1%,1/16W,EMPA',
 WATTAGE='1/16W',
 TOLERANCE='1%',
 MATERIAL='EMPTY',
 VALUE='4.7K',
 PRIM_FILE='W:/<user>/logical/q_res/chips/chips.prt';

PART_NAME
 R45 'Q_RES_0402LF-4.7K,1%,1/16W,CHIA':;

SECTION_NUMBER 1
 '@SCM_LIB.SCM(SCH_1):PAGE11_I176@PURE_QUANTA.Q_RES(CHIPS)':
 C_PATH='@scm_lib.scm(sch_1):page11_i176@pure_quanta.q_res(chips)',
 P_PATH='@scm_lib.scm(sch_1):page11_i176@pure_quanta.q_res(chips)',
 PATH='I176',
 DRAWING='@SCM_LIB.SCM(SCH_1):PAGE11',
 PHYS_PAGE='11',
 XY='(-3325,5825)',
 ROT='0',
 VER='1',
 PACK_TYPE='0402LF',
 LOCATION='R45',
 CDS_LIB='pure_quanta',
 CDS_PART_NAME='Q_RES_0402LF-4.7K,1%,1/16W,CHIA',
 WATTAGE='1/16W',
 TOLERANCE='1%',
 MATERIAL='CHIP',
 VALUE='4.7K',
 PRIM_FILE='W:/<user>/logical/q_res/chips/chips.prt';

PART_NAME
 R46 'Q_RES_0402LF-33.2,1%,1/16W,CHIA':;

SECTION_NUMBER 1
 '@SCM_LIB.SCM(SCH_1):PAGE10_I459@PURE_QUANTA.Q_RES(CHIPS)':
 C_PATH='@scm_lib.scm(sch_1):page10_i459@pure_quanta.q_res(chips)',
 P_PATH='@scm_lib.scm(sch_1):page10_i459@pure_quanta.q_res(chips)',
 PATH='I459',
 DRAWING='@SCM_LIB.SCM(SCH_1):PAGE10',
 SEC_TYPE='0402LF',
 PHYS_PAGE='10',
 XY='(-10350,2150)',
 ROT='0',
 VER='1',
 PACK_TYPE='0402LF',
 LOCATION='R46',
 SEC='1',
 CDS_LIB='pure_quanta',
 CDS_PART_NAME='Q_RES_0402LF-33.2,1%,1/16W,CHIA',
 WATTAGE='1/16W',
 TOLERANCE='1%',
 MATERIAL='CHIP',
 VALUE='33.2',
 PRIM_FILE='W:/<user>/logical/q_res/chips/chips.prt';

PART_NAME
 R47 'Q_RES_0402LF-33.2,1%,1/16W,CHIA':;

SECTION_NUMBER 1
 '@SCM_LIB.SCM(SCH_1):PAGE46_I106@PURE_QUANTA.Q_RES(CHIPS)':
 C_PATH='@scm_lib.scm(sch_1):page46_i106@pure_quanta.q_res(chips)',
 P_PATH='@scm_lib.scm(sch_1):page46_i106@pure_quanta.q_res(chips)',
 PATH='I106',
 DRAWING='@SCM_LIB.SCM(SCH_1):PAGE46',
 PHYS_PAGE='46',
 XY='(-6600,-5700)',
 ROT='6',
 VER='1',
 PACK_TYPE='0402LF',
 LOCATION='R47',
 CDS_LIB='pure_quanta',
 CDS_PART_NAME='Q_RES_0402LF-33.2,1%,1/16W,CHIA',
 WATTAGE='1/16W',
 TOLERANCE='1%',
 MATERIAL='CHIP',
 VALUE='33.2',
 PRIM_FILE='W:/<user>/logical/q_res/chips/chips.prt';

PART_NAME
 R48 'Q_RES_0402LF-33.2,1%,1/16W,EMPA':;

SECTION_NUMBER 1
 '@SCM_LIB.SCM(SCH_1):PAGE21_I35@PURE_QUANTA.Q_RES(CHIPS)':
 C_PATH='@scm_lib.scm(sch_1):page21_i35@pure_quanta.q_res(chips)',
 P_PATH='@scm_lib.scm(sch_1):page21_i35@pure_quanta.q_res(chips)',
 PATH='I35',
 DRAWING='@SCM_LIB.SCM(SCH_1):PAGE21',
 PHYS_PAGE='21',
 XY='(3250,2150)',
 ROT='0',
 VER='1',
 PACK_TYPE='0402LF',
 LOCATION='R48',
 CDS_LIB='pure_quanta',
 CDS_PART_NAME='Q_RES_0402LF-33.2,1%,1/16W,EMPA',
 WATTAGE='1/16W',
 TOLERANCE='1%',
 MATERIAL='EMPTY',
 VALUE='33.2',
 PRIM_FILE='W:/<user>/logical/q_res/chips/chips.prt';

PART_NAME
 R49 'Q_RES_0402LF-0,5%,1/16W,CHIP,CA':;

SECTION_NUMBER 1
 '@SCM_LIB.SCM(SCH_1):PAGE22_I72@PURE_QUANTA.Q_RES(CHIPS)':
 C_PATH='@scm_lib.scm(sch_1):page22_i72@pure_quanta.q_res(chips)',
 P_PATH='@scm_lib.scm(sch_1):page22_i72@pure_quanta.q_res(chips)',
 PATH='I72',
 DRAWING='@SCM_LIB.SCM(SCH_1):PAGE22',
 PHYS_PAGE='22',
 XY='(-2975,-275)',
 ROT='0',
 VER='1',
 PACK_TYPE='0402LF',
 LOCATION='R49',
 CDS_LIB='pure_quanta',
 CDS_PART_NAME='Q_RES_0402LF-0,5%,1/16W,CHIP,CA',
 WATTAGE='1/16W',
 TOLERANCE='5%',
 MATERIAL='CHIP',
 VALUE='0',
 PRIM_FILE='W:/<user>/logical/q_res/chips/chips.prt';

PART_NAME
 R50 'Q_RES_0402LF-10K,1%,1/16W,CHIPA':;

SECTION_NUMBER 1
 '@SCM_LIB.SCM(SCH_1):PAGE46_I104@PURE_QUANTA.Q_RES(CHIPS)':
 C_PATH='@scm_lib.scm(sch_1):page46_i104@pure_quanta.q_res(chips)',
 P_PATH='@scm_lib.scm(sch_1):page46_i104@pure_quanta.q_res(chips)',
 PATH='I104',
 DRAWING='@SCM_LIB.SCM(SCH_1):PAGE46',
 PHYS_PAGE='46',
 XY='(-6300,-5325)',
 ROT='2',
 VER='2',
 PACK_TYPE='0402LF',
 LOCATION='R50',
 CDS_LIB='pure_quanta',
 CDS_PART_NAME='Q_RES_0402LF-10K,1%,1/16W,CHIPA',
 WATTAGE='1/16W',
 TOLERANCE='1%',
 MATERIAL='CHIP',
 VALUE='10K',
 PRIM_FILE='W:/<user>/logical/q_res/chips/chips.prt';

PART_NAME
 R51 'Q_RES_0402LF-0,5%,1/16W,CHIP,CA':;

SECTION_NUMBER 1
 '@SCM_LIB.SCM(SCH_1):PAGE35_I80@PURE_QUANTA.Q_RES(CHIPS)':
 C_PATH='@scm_lib.scm(sch_1):page35_i80@pure_quanta.q_res(chips)',
 P_PATH='@scm_lib.scm(sch_1):page35_i80@pure_quanta.q_res(chips)',
 PATH='I80',
 DRAWING='@SCM_LIB.SCM(SCH_1):PAGE35',
 SEC_TYPE='0402LF',
 PHYS_PAGE='35',
 XY='(-7300,4150)',
 ROT='0',
 VER='1',
 PACK_TYPE='0402LF',
 LOCATION='R51',
 SEC='1',
 CDS_LIB='pure_quanta',
 CDS_PART_NAME='Q_RES_0402LF-0,5%,1/16W,CHIP,CA',
 WATTAGE='1/16W',
 TOLERANCE='5%',
 MATERIAL='CHIP',
 VALUE='0',
 PRIM_FILE='W:/<user>/logical/q_res/chips/chips.prt';

PART_NAME
 R52 'Q_RES_0402LF-4.7K,1%,1/16W,CHIA':;

SECTION_NUMBER 1
 '@SCM_LIB.SCM(SCH_1):PAGE26_I67@PURE_QUANTA.Q_RES(CHIPS)':
 C_PATH='@scm_lib.scm(sch_1):page26_i67@pure_quanta.q_res(chips)',
 P_PATH='@scm_lib.scm(sch_1):page26_i67@pure_quanta.q_res(chips)',
 PATH='I67',
 DRAWING='@SCM_LIB.SCM(SCH_1):PAGE26',
 PHYS_PAGE='26',
 XY='(-1450,3350)',
 ROT='0',
 VER='2',
 PACK_TYPE='0402LF',
 CDS_LIB='pure_quanta',
 CDS_PART_NAME='Q_RES_0402LF-4.7K,1%,1/16W,CHIA',
 WATTAGE='1/16W',
 TOLERANCE='1%',
 MATERIAL='CHIP',
 VALUE='4.7K',
 PRIM_FILE='W:/<user>/logical/q_res/chips/chips.prt';

PART_NAME
 R53 'Q_RES_0402LF-1K,1%,1/16W,EMPTYA':;

SECTION_NUMBER 1
 '@SCM_LIB.SCM(SCH_1):PAGE26_I66@PURE_QUANTA.Q_RES(CHIPS)':
 C_PATH='@scm_lib.scm(sch_1):page26_i66@pure_quanta.q_res(chips)',
 P_PATH='@scm_lib.scm(sch_1):page26_i66@pure_quanta.q_res(chips)',
 PATH='I66',
 DRAWING='@SCM_LIB.SCM(SCH_1):PAGE26',
 PHYS_PAGE='26',
 XY='(-1450,2650)',
 ROT='0',
 VER='2',
 PACK_TYPE='0402LF',
 CDS_LIB='pure_quanta',
 CDS_PART_NAME='Q_RES_0402LF-1K,1%,1/16W,EMPTYA',
 WATTAGE='1/16W',
 TOLERANCE='1%',
 MATERIAL='EMPTY',
 VALUE='1K',
 PRIM_FILE='W:/<user>/logical/q_res/chips/chips.prt';

PART_NAME
 R54 'Q_RES_0402LF-10K,1%,1/16W,CHIPA':;

SECTION_NUMBER 1
 '@SCM_LIB.SCM(SCH_1):PAGE26_I65@PURE_QUANTA.Q_RES(CHIPS)':
 C_PATH='@scm_lib.scm(sch_1):page26_i65@pure_quanta.q_res(chips)',
 P_PATH='@scm_lib.scm(sch_1):page26_i65@pure_quanta.q_res(chips)',
 PATH='I65',
 DRAWING='@SCM_LIB.SCM(SCH_1):PAGE26',
 PHYS_PAGE='26',
 XY='(1625,2925)',
 ROT='0',
 VER='1',
 PACK_TYPE='0402LF',
 CDS_LIB='pure_quanta',
 CDS_PART_NAME='Q_RES_0402LF-10K,1%,1/16W,CHIPA',
 WATTAGE='1/16W',
 TOLERANCE='1%',
 MATERIAL='CHIP',
 VALUE='10K',
 PRIM_FILE='W:/<user>/logical/q_res/chips/chips.prt';

PART_NAME
 R55 'Q_RES_0402LF-4.7K,1%,1/16W,CHIA':;

SECTION_NUMBER 1
 '@SCM_LIB.SCM(SCH_1):PAGE13_I278@PURE_QUANTA.Q_RES(CHIPS)':
 C_PATH='@scm_lib.scm(sch_1):page13_i278@pure_quanta.q_res(chips)',
 P_PATH='@scm_lib.scm(sch_1):page13_i278@pure_quanta.q_res(chips)',
 PATH='I278',
 DRAWING='@SCM_LIB.SCM(SCH_1):PAGE13',
 SEC_TYPE='0402LF',
 PHYS_PAGE='13',
 XY='(2800,-600)',
 ROT='0',
 VER='1',
 PACK_TYPE='0402LF',
 LOCATION='R55',
 SEC='1',
 CDS_LIB='pure_quanta',
 CDS_PART_NAME='Q_RES_0402LF-4.7K,1%,1/16W,CHIA',
 WATTAGE='1/16W',
 TOLERANCE='1%',
 MATERIAL='CHIP',
 VALUE='4.7K',
 PRIM_FILE='W:/<user>/logical/q_res/chips/chips.prt';

PART_NAME
 R56 'Q_RES_0402LF-4.7K,1%,1/16W,CHIA':;

SECTION_NUMBER 1
 '@SCM_LIB.SCM(SCH_1):PAGE13_I279@PURE_QUANTA.Q_RES(CHIPS)':
 C_PATH='@scm_lib.scm(sch_1):page13_i279@pure_quanta.q_res(chips)',
 P_PATH='@scm_lib.scm(sch_1):page13_i279@pure_quanta.q_res(chips)',
 PATH='I279',
 DRAWING='@SCM_LIB.SCM(SCH_1):PAGE13',
 SEC_TYPE='0402LF',
 PHYS_PAGE='13',
 XY='(2800,-650)',
 ROT='0',
 VER='1',
 PACK_TYPE='0402LF',
 LOCATION='R56',
 SEC='1',
 CDS_LIB='pure_quanta',
 CDS_PART_NAME='Q_RES_0402LF-4.7K,1%,1/16W,CHIA',
 WATTAGE='1/16W',
 TOLERANCE='1%',
 MATERIAL='CHIP',
 VALUE='4.7K',
 PRIM_FILE='W:/<user>/logical/q_res/chips/chips.prt';

PART_NAME
 R57 'Q_RES_0402LF-0,5%,1/16W,CHIP,CA':;

SECTION_NUMBER 1
 '@SCM_LIB.SCM(SCH_1):PAGE21_I167@PURE_QUANTA.Q_RES(CHIPS)':
 C_PATH='@scm_lib.scm(sch_1):page21_i167@pure_quanta.q_res(chips)',
 P_PATH='@scm_lib.scm(sch_1):page21_i167@pure_quanta.q_res(chips)',
 PATH='I167',
 DRAWING='@SCM_LIB.SCM(SCH_1):PAGE21',
 PHYS_PAGE='21',
 XY='(-150,3200)',
 ROT='0',
 VER='1',
 PACK_TYPE='0402LF',
 CDS_LIB='pure_quanta',
 CDS_PART_NAME='Q_RES_0402LF-0,5%,1/16W,CHIP,CA',
 WATTAGE='1/16W',
 TOLERANCE='5%',
 MATERIAL='CHIP',
 VALUE='0',
 PRIM_FILE='W:/<user>/logical/q_res/chips/chips.prt';

PART_NAME
 R58 'Q_RES_0402LF-4.7K,1%,1/16W,EMPB':;

SECTION_NUMBER 1
 '@SCM_LIB.SCM(SCH_1):PAGE21_I168@PURE_QUANTA.Q_RES(CHIPS)':
 C_PATH='@scm_lib.scm(sch_1):page21_i168@pure_quanta.q_res(chips)',
 P_PATH='@scm_lib.scm(sch_1):page21_i168@pure_quanta.q_res(chips)',
 PATH='I168',
 DRAWING='@SCM_LIB.SCM(SCH_1):PAGE21',
 PHYS_PAGE='21',
 XY='(50,3725)',
 ROT='0',
 VER='2',
 PACK_TYPE='0402LF',
 CDS_LIB='pure_quanta',
 CDS_PART_NAME='Q_RES_0402LF-4.7K,1%,1/16W,EMPB',
 WATTAGE='1/16W',
 TOLERANCE='1%',
 MATERIAL='EMPTY',
 VALUE='4.7K',
 PRIM_FILE='W:/<user>/logical/q_res/chips/chips.prt';

PART_NAME
 R59 'Q_RES_0402LF-10K,1%,1/16W,CHIPA':;

SECTION_NUMBER 1
 '@SCM_LIB.SCM(SCH_1):PAGE46_I98@PURE_QUANTA.Q_RES(CHIPS)':
 C_PATH='@scm_lib.scm(sch_1):page46_i98@pure_quanta.q_res(chips)',
 P_PATH='@scm_lib.scm(sch_1):page46_i98@pure_quanta.q_res(chips)',
 PATH='I98',
 DRAWING='@SCM_LIB.SCM(SCH_1):PAGE46',
 PHYS_PAGE='46',
 XY='(-5625,-5400)',
 ROT='2',
 VER='2',
 PACK_TYPE='0402LF',
 LOCATION='R59',
 CDS_LIB='pure_quanta',
 CDS_PART_NAME='Q_RES_0402LF-10K,1%,1/16W,CHIPA',
 WATTAGE='1/16W',
 TOLERANCE='1%',
 MATERIAL='CHIP',
 VALUE='10K',
 PRIM_FILE='W:/<user>/logical/q_res/chips/chips.prt';

PART_NAME
 R60 'Q_RES_0402LF-33.2,1%,1/16W,CHIA':;

SECTION_NUMBER 1
 '@SCM_LIB.SCM(SCH_1):PAGE13_I382@PURE_QUANTA.Q_RES(CHIPS)':
 C_PATH='@scm_lib.scm(sch_1):page13_i382@pure_quanta.q_res(chips)',
 P_PATH='@scm_lib.scm(sch_1):page13_i382@pure_quanta.q_res(chips)',
 PATH='I382',
 DRAWING='@SCM_LIB.SCM(SCH_1):PAGE13',
 PHYS_PAGE='13',
 XY='(3275,1225)',
 ROT='0',
 VER='1',
 PACK_TYPE='0402LF',
 LOCATION='R60',
 CDS_LIB='pure_quanta',
 CDS_PART_NAME='Q_RES_0402LF-33.2,1%,1/16W,CHIA',
 WATTAGE='1/16W',
 TOLERANCE='1%',
 MATERIAL='CHIP',
 VALUE='33.2',
 PRIM_FILE='W:/<user>/logical/q_res/chips/chips.prt';

PART_NAME
 R61 'Q_RES_0402LF-4.7K,1%,1/16W,CHIA':;

SECTION_NUMBER 1
 '@SCM_LIB.SCM(SCH_1):PAGE13_I204@PURE_QUANTA.Q_RES(CHIPS)':
 C_PATH='@scm_lib.scm(sch_1):page13_i204@pure_quanta.q_res(chips)',
 P_PATH='@scm_lib.scm(sch_1):page13_i204@pure_quanta.q_res(chips)',
 PATH='I204',
 DRAWING='@SCM_LIB.SCM(SCH_1):PAGE13',
 PHYS_PAGE='13',
 XY='(2750,25)',
 ROT='0',
 VER='1',
 PACK_TYPE='0402LF',
 LOCATION='R61',
 CDS_LIB='pure_quanta',
 CDS_PART_NAME='Q_RES_0402LF-4.7K,1%,1/16W,CHIA',
 WATTAGE='1/16W',
 TOLERANCE='1%',
 MATERIAL='CHIP',
 VALUE='4.7K',
 PRIM_FILE='W:/<user>/logical/q_res/chips/chips.prt';

PART_NAME
 R62 'Q_RES_0402LF-4.7K,1%,1/16W,CHIA':;

SECTION_NUMBER 1
 '@SCM_LIB.SCM(SCH_1):PAGE12_I350@PURE_QUANTA.Q_RES(CHIPS)':
 C_PATH='@scm_lib.scm(sch_1):page12_i350@pure_quanta.q_res(chips)',
 P_PATH='@scm_lib.scm(sch_1):page12_i350@pure_quanta.q_res(chips)',
 PATH='I350',
 DRAWING='@SCM_LIB.SCM(SCH_1):PAGE12',
 PHYS_PAGE='12',
 XY='(-2550,3300)',
 ROT='0',
 VER='1',
 PACK_TYPE='0402LF',
 LOCATION='R62',
 CDS_LIB='pure_quanta',
 CDS_PART_NAME='Q_RES_0402LF-4.7K,1%,1/16W,CHIA',
 WATTAGE='1/16W',
 TOLERANCE='1%',
 MATERIAL='CHIP',
 VALUE='4.7K',
 PRIM_FILE='W:/<user>/logical/q_res/chips/chips.prt';

PART_NAME
 R63 'Q_RES_0402LF-0,5%,1/16W,EMPTY,A':;

SECTION_NUMBER 1
 '@SCM_LIB.SCM(SCH_1):PAGE11_I231@PURE_QUANTA.Q_RES(CHIPS)':
 C_PATH='@scm_lib.scm(sch_1):page11_i231@pure_quanta.q_res(chips)',
 P_PATH='@scm_lib.scm(sch_1):page11_i231@pure_quanta.q_res(chips)',
 PATH='I231',
 DRAWING='@SCM_LIB.SCM(SCH_1):PAGE11',
 PHYS_PAGE='11',
 XY='(2450,5575)',
 ROT='2',
 VER='1',
 PACK_TYPE='0402LF',
 LOCATION='R63',
 CDS_LIB='pure_quanta',
 CDS_PART_NAME='Q_RES_0402LF-0,5%,1/16W,EMPTY,A',
 WATTAGE='1/16W',
 TOLERANCE='5%',
 MATERIAL='EMPTY',
 VALUE='0',
 PRIM_FILE='W:/<user>/logical/q_res/chips/chips.prt';

PART_NAME
 R64 'Q_RES_0402LF-0,5%,1/16W,EMPTY,A':;

SECTION_NUMBER 1
 '@SCM_LIB.SCM(SCH_1):PAGE11_I233@PURE_QUANTA.Q_RES(CHIPS)':
 C_PATH='@scm_lib.scm(sch_1):page11_i233@pure_quanta.q_res(chips)',
 P_PATH='@scm_lib.scm(sch_1):page11_i233@pure_quanta.q_res(chips)',
 PATH='I233',
 DRAWING='@SCM_LIB.SCM(SCH_1):PAGE11',
 PHYS_PAGE='11',
 XY='(2450,5950)',
 ROT='2',
 VER='1',
 PACK_TYPE='0402LF',
 LOCATION='R64',
 CDS_LIB='pure_quanta',
 CDS_PART_NAME='Q_RES_0402LF-0,5%,1/16W,EMPTY,A',
 WATTAGE='1/16W',
 TOLERANCE='5%',
 MATERIAL='EMPTY',
 VALUE='0',
 PRIM_FILE='W:/<user>/logical/q_res/chips/chips.prt';

PART_NAME
 R65 'Q_RES_0402LF-33.2,1%,1/16W,CHIA':;

SECTION_NUMBER 1
 '@SCM_LIB.SCM(SCH_1):PAGE13_I421@PURE_QUANTA.Q_RES(CHIPS)':
 C_PATH='@scm_lib.scm(sch_1):page13_i421@pure_quanta.q_res(chips)',
 P_PATH='@scm_lib.scm(sch_1):page13_i421@pure_quanta.q_res(chips)',
 PATH='I421',
 DRAWING='@SCM_LIB.SCM(SCH_1):PAGE13',
 SEC_TYPE='0402LF',
 PHYS_PAGE='13',
 XY='(3650,3225)',
 ROT='0',
 VER='1',
 PACK_TYPE='0402LF',
 LOCATION='R65',
 SEC='1',
 CDS_LIB='pure_quanta',
 CDS_PART_NAME='Q_RES_0402LF-33.2,1%,1/16W,CHIA',
 WATTAGE='1/16W',
 TOLERANCE='1%',
 MATERIAL='CHIP',
 VALUE='33.2',
 PRIM_FILE='W:/<user>/logical/q_res/chips/chips.prt';

PART_NAME
 R66 'Q_RES_0402LF-100K,1%,1/16W,CHIA':;

SECTION_NUMBER 1
 '@SCM_LIB.SCM(SCH_1):PAGE11_I181@PURE_QUANTA.Q_RES(CHIPS)':
 C_PATH='@scm_lib.scm(sch_1):page11_i181@pure_quanta.q_res(chips)',
 P_PATH='@scm_lib.scm(sch_1):page11_i181@pure_quanta.q_res(chips)',
 PATH='I181',
 DRAWING='@SCM_LIB.SCM(SCH_1):PAGE11',
 PHYS_PAGE='11',
 XY='(-200,3950)',
 ROT='0',
 VER='1',
 PACK_TYPE='0402LF',
 LOCATION='R66',
 CDS_LIB='pure_quanta',
 CDS_PART_NAME='Q_RES_0402LF-100K,1%,1/16W,CHIA',
 WATTAGE='1/16W',
 TOLERANCE='1%',
 MATERIAL='CHIP',
 VALUE='100K',
 PRIM_FILE='W:/<user>/logical/q_res/chips/chips.prt';

PART_NAME
 R67 'Q_RES_0402LF-4.7K,1%,1/16W,CHIA':;

SECTION_NUMBER 1
 '@SCM_LIB.SCM(SCH_1):PAGE30_I146@PURE_QUANTA.Q_RES(CHIPS)':
 C_PATH='@scm_lib.scm(sch_1):page30_i146@pure_quanta.q_res(chips)',
 P_PATH='@scm_lib.scm(sch_1):page30_i146@pure_quanta.q_res(chips)',
 PATH='I146',
 DRAWING='@SCM_LIB.SCM(SCH_1):PAGE30',
 SEC_TYPE='0402LF',
 PHYS_PAGE='30',
 XY='(1825,2450)',
 ROT='2',
 VER='2',
 PACK_TYPE='0402LF',
 LOCATION='R67',
 SEC='1',
 CDS_LIB='pure_quanta',
 CDS_PART_NAME='Q_RES_0402LF-4.7K,1%,1/16W,CHIA',
 WATTAGE='1/16W',
 TOLERANCE='1%',
 MATERIAL='CHIP',
 VALUE='4.7K',
 PRIM_FILE='W:/<user>/logical/q_res/chips/chips.prt';

PART_NAME
 R68 'Q_RES_0402LF-4.7K,1%,1/16W,CHIA':;

SECTION_NUMBER 1
 '@SCM_LIB.SCM(SCH_1):PAGE11_I179@PURE_QUANTA.Q_RES(CHIPS)':
 C_PATH='@scm_lib.scm(sch_1):page11_i179@pure_quanta.q_res(chips)',
 P_PATH='@scm_lib.scm(sch_1):page11_i179@pure_quanta.q_res(chips)',
 PATH='I179',
 DRAWING='@SCM_LIB.SCM(SCH_1):PAGE11',
 PHYS_PAGE='11',
 XY='(-3300,4625)',
 ROT='0',
 VER='1',
 PACK_TYPE='0402LF',
 LOCATION='R68',
 CDS_LIB='pure_quanta',
 CDS_PART_NAME='Q_RES_0402LF-4.7K,1%,1/16W,CHIA',
 WATTAGE='1/16W',
 TOLERANCE='1%',
 MATERIAL='CHIP',
 VALUE='4.7K',
 PRIM_FILE='W:/<user>/logical/q_res/chips/chips.prt';

PART_NAME
 R69 'Q_RES_0402LF-4.7K,1%,1/16W,CHIA':;

SECTION_NUMBER 1
 '@SCM_LIB.SCM(SCH_1):PAGE11_I227@PURE_QUANTA.Q_RES(CHIPS)':
 C_PATH='@scm_lib.scm(sch_1):page11_i227@pure_quanta.q_res(chips)',
 P_PATH='@scm_lib.scm(sch_1):page11_i227@pure_quanta.q_res(chips)',
 PATH='I227',
 DRAWING='@SCM_LIB.SCM(SCH_1):PAGE11',
 PHYS_PAGE='11',
 XY='(-3300,4825)',
 ROT='0',
 VER='1',
 PACK_TYPE='0402LF',
 LOCATION='R69',
 CDS_LIB='pure_quanta',
 CDS_PART_NAME='Q_RES_0402LF-4.7K,1%,1/16W,CHIA',
 WATTAGE='1/16W',
 TOLERANCE='1%',
 MATERIAL='CHIP',
 VALUE='4.7K',
 PRIM_FILE='W:/<user>/logical/q_res/chips/chips.prt';

PART_NAME
 R70 'Q_RES_0402LF-33.2,1%,1/16W,CHIA':;

SECTION_NUMBER 1
 '@SCM_LIB.SCM(SCH_1):PAGE13_I419@PURE_QUANTA.Q_RES(CHIPS)':
 C_PATH='@scm_lib.scm(sch_1):page13_i419@pure_quanta.q_res(chips)',
 P_PATH='@scm_lib.scm(sch_1):page13_i419@pure_quanta.q_res(chips)',
 PATH='I419',
 DRAWING='@SCM_LIB.SCM(SCH_1):PAGE13',
 SEC_TYPE='0402LF',
 PHYS_PAGE='13',
 XY='(3650,3275)',
 ROT='0',
 VER='1',
 PACK_TYPE='0402LF',
 LOCATION='R70',
 SEC='1',
 CDS_LIB='pure_quanta',
 CDS_PART_NAME='Q_RES_0402LF-33.2,1%,1/16W,CHIA',
 WATTAGE='1/16W',
 TOLERANCE='1%',
 MATERIAL='CHIP',
 VALUE='33.2',
 PRIM_FILE='W:/<user>/logical/q_res/chips/chips.prt';

PART_NAME
 R71 'Q_RES_0402LF-33.2,1%,1/16W,CHIA':;

SECTION_NUMBER 1
 '@SCM_LIB.SCM(SCH_1):PAGE12_I277@PURE_QUANTA.Q_RES(CHIPS)':
 C_PATH='@scm_lib.scm(sch_1):page12_i277@pure_quanta.q_res(chips)',
 P_PATH='@scm_lib.scm(sch_1):page12_i277@pure_quanta.q_res(chips)',
 PATH='I277',
 DRAWING='@SCM_LIB.SCM(SCH_1):PAGE12',
 PHYS_PAGE='12',
 XY='(4775,-350)',
 ROT='0',
 VER='1',
 PACK_TYPE='0402LF',
 LOCATION='R71',
 CDS_LIB='pure_quanta',
 CDS_PART_NAME='Q_RES_0402LF-33.2,1%,1/16W,CHIA',
 WATTAGE='1/16W',
 TOLERANCE='1%',
 MATERIAL='CHIP',
 VALUE='33.2',
 PRIM_FILE='W:/<user>/logical/q_res/chips/chips.prt';

PART_NAME
 R72 'Q_RES_0402LF-4.7K,1%,1/16W,CHIA':;

SECTION_NUMBER 1
 '@SCM_LIB.SCM(SCH_1):PAGE30_I231@PURE_QUANTA.Q_RES(CHIPS)':
 C_PATH='@scm_lib.scm(sch_1):page30_i231@pure_quanta.q_res(chips)',
 P_PATH='@scm_lib.scm(sch_1):page30_i231@pure_quanta.q_res(chips)',
 PATH='I231',
 DRAWING='@SCM_LIB.SCM(SCH_1):PAGE30',
 SEC_TYPE='0402LF',
 PHYS_PAGE='30',
 XY='(-825,2475)',
 ROT='2',
 VER='2',
 PACK_TYPE='0402LF',
 LOCATION='R72',
 SEC='1',
 CDS_LIB='pure_quanta',
 CDS_PART_NAME='Q_RES_0402LF-4.7K,1%,1/16W,CHIA',
 WATTAGE='1/16W',
 TOLERANCE='1%',
 MATERIAL='CHIP',
 VALUE='4.7K',
 PRIM_FILE='W:/<user>/logical/q_res/chips/chips.prt';

PART_NAME
 R73 'Q_RES_0402LF-1K,1%,1/16W,EMPTYA':;

SECTION_NUMBER 1
 '@SCM_LIB.SCM(SCH_1):PAGE11_I118@PURE_QUANTA.Q_RES(CHIPS)':
 C_PATH='@scm_lib.scm(sch_1):page11_i118@pure_quanta.q_res(chips)',
 P_PATH='@scm_lib.scm(sch_1):page11_i118@pure_quanta.q_res(chips)',
 PATH='I118',
 DRAWING='@SCM_LIB.SCM(SCH_1):PAGE11',
 PHYS_PAGE='11',
 XY='(-3350,3825)',
 ROT='0',
 VER='1',
 PACK_TYPE='0402LF',
 LOCATION='R73',
 CDS_LIB='pure_quanta',
 CDS_PART_NAME='Q_RES_0402LF-1K,1%,1/16W,EMPTYA',
 WATTAGE='1/16W',
 TOLERANCE='1%',
 MATERIAL='EMPTY',
 VALUE='1K',
 PRIM_FILE='W:/<user>/logical/q_res/chips/chips.prt';

PART_NAME
 R74 'Q_RES_0402LF-2K,1%,1/16W,CHIP,A':;

SECTION_NUMBER 1
 '@SCM_LIB.SCM(SCH_1):PAGE11_I117@PURE_QUANTA.Q_RES(CHIPS)':
 C_PATH='@scm_lib.scm(sch_1):page11_i117@pure_quanta.q_res(chips)',
 P_PATH='@scm_lib.scm(sch_1):page11_i117@pure_quanta.q_res(chips)',
 PATH='I117',
 DRAWING='@SCM_LIB.SCM(SCH_1):PAGE11',
 PHYS_PAGE='11',
 XY='(-3325,3625)',
 ROT='0',
 VER='1',
 PACK_TYPE='0402LF',
 LOCATION='R74',
 CDS_LIB='pure_quanta',
 CDS_PART_NAME='Q_RES_0402LF-2K,1%,1/16W,CHIP,A',
 WATTAGE='1/16W',
 TOLERANCE='1%',
 MATERIAL='CHIP',
 VALUE='2K',
 PRIM_FILE='W:/<user>/logical/q_res/chips/chips.prt';

PART_NAME
 R75 'Q_RES_0402LF-2K,1%,1/16W,CHIP,A':;

SECTION_NUMBER 1
 '@SCM_LIB.SCM(SCH_1):PAGE11_I110@PURE_QUANTA.Q_RES(CHIPS)':
 C_PATH='@scm_lib.scm(sch_1):page11_i110@pure_quanta.q_res(chips)',
 P_PATH='@scm_lib.scm(sch_1):page11_i110@pure_quanta.q_res(chips)',
 PATH='I110',
 DRAWING='@SCM_LIB.SCM(SCH_1):PAGE11',
 PHYS_PAGE='11',
 XY='(-3325,3425)',
 ROT='0',
 VER='1',
 PACK_TYPE='0402LF',
 LOCATION='R75',
 CDS_LIB='pure_quanta',
 CDS_PART_NAME='Q_RES_0402LF-2K,1%,1/16W,CHIP,A',
 WATTAGE='1/16W',
 TOLERANCE='1%',
 MATERIAL='CHIP',
 VALUE='2K',
 PRIM_FILE='W:/<user>/logical/q_res/chips/chips.prt';

PART_NAME
 R76 'Q_RES_0402LF-2K,1%,1/16W,CHIP,A':;

SECTION_NUMBER 1
 '@SCM_LIB.SCM(SCH_1):PAGE11_I230@PURE_QUANTA.Q_RES(CHIPS)':
 C_PATH='@scm_lib.scm(sch_1):page11_i230@pure_quanta.q_res(chips)',
 P_PATH='@scm_lib.scm(sch_1):page11_i230@pure_quanta.q_res(chips)',
 PATH='I230',
 DRAWING='@SCM_LIB.SCM(SCH_1):PAGE11',
 PHYS_PAGE='11',
 XY='(2450,5750)',
 ROT='0',
 VER='1',
 PACK_TYPE='0402LF',
 LOCATION='R76',
 CDS_LIB='pure_quanta',
 CDS_PART_NAME='Q_RES_0402LF-2K,1%,1/16W,CHIP,A',
 WATTAGE='1/16W',
 TOLERANCE='1%',
 MATERIAL='CHIP',
 VALUE='2K',
 PRIM_FILE='W:/<user>/logical/q_res/chips/chips.prt';

PART_NAME
 R77 'Q_RES_0402LF-1K,1%,1/16W,EMPTYA':;

SECTION_NUMBER 1
 '@SCM_LIB.SCM(SCH_1):PAGE11_I128@PURE_QUANTA.Q_RES(CHIPS)':
 C_PATH='@scm_lib.scm(sch_1):page11_i128@pure_quanta.q_res(chips)',
 P_PATH='@scm_lib.scm(sch_1):page11_i128@pure_quanta.q_res(chips)',
 PATH='I128',
 DRAWING='@SCM_LIB.SCM(SCH_1):PAGE11',
 PHYS_PAGE='11',
 XY='(-3325,4450)',
 ROT='0',
 VER='1',
 PACK_TYPE='0402LF',
 LOCATION='R77',
 CDS_LIB='pure_quanta',
 CDS_PART_NAME='Q_RES_0402LF-1K,1%,1/16W,EMPTYA',
 WATTAGE='1/16W',
 TOLERANCE='1%',
 MATERIAL='EMPTY',
 VALUE='1K',
 PRIM_FILE='W:/<user>/logical/q_res/chips/chips.prt';

PART_NAME
 R78 'Q_RES_0402LF-2K,1%,1/16W,CHIP,A':;

SECTION_NUMBER 1
 '@SCM_LIB.SCM(SCH_1):PAGE11_I129@PURE_QUANTA.Q_RES(CHIPS)':
 C_PATH='@scm_lib.scm(sch_1):page11_i129@pure_quanta.q_res(chips)',
 P_PATH='@scm_lib.scm(sch_1):page11_i129@pure_quanta.q_res(chips)',
 PATH='I129',
 DRAWING='@SCM_LIB.SCM(SCH_1):PAGE11',
 PHYS_PAGE='11',
 XY='(-3325,4250)',
 ROT='0',
 VER='1',
 PACK_TYPE='0402LF',
 LOCATION='R78',
 CDS_LIB='pure_quanta',
 CDS_PART_NAME='Q_RES_0402LF-2K,1%,1/16W,CHIP,A',
 WATTAGE='1/16W',
 TOLERANCE='1%',
 MATERIAL='CHIP',
 VALUE='2K',
 PRIM_FILE='W:/<user>/logical/q_res/chips/chips.prt';

PART_NAME
 R79 'Q_RES_0402LF-2K,1%,1/16W,CHIP,A':;

SECTION_NUMBER 1
 '@SCM_LIB.SCM(SCH_1):PAGE11_I130@PURE_QUANTA.Q_RES(CHIPS)':
 C_PATH='@scm_lib.scm(sch_1):page11_i130@pure_quanta.q_res(chips)',
 P_PATH='@scm_lib.scm(sch_1):page11_i130@pure_quanta.q_res(chips)',
 PATH='I130',
 DRAWING='@SCM_LIB.SCM(SCH_1):PAGE11',
 PHYS_PAGE='11',
 XY='(-3325,4050)',
 ROT='0',
 VER='1',
 PACK_TYPE='0402LF',
 LOCATION='R79',
 CDS_LIB='pure_quanta',
 CDS_PART_NAME='Q_RES_0402LF-2K,1%,1/16W,CHIP,A',
 WATTAGE='1/16W',
 TOLERANCE='1%',
 MATERIAL='CHIP',
 VALUE='2K',
 PRIM_FILE='W:/<user>/logical/q_res/chips/chips.prt';

PART_NAME
 R80 'Q_RES_0402LF-220,1%,1/16W,CHIPA':;

SECTION_NUMBER 1
 '@SCM_LIB.SCM(SCH_1):PAGE50_I210@PURE_QUANTA.Q_RES(CHIPS)':
 C_PATH='@scm_lib.scm(sch_1):page50_i210@pure_quanta.q_res(chips)',
 P_PATH='@scm_lib.scm(sch_1):page50_i210@pure_quanta.q_res(chips)',
 PATH='I210',
 DRAWING='@SCM_LIB.SCM(SCH_1):PAGE50',
 PHYS_PAGE='50',
 XY='(750,800)',
 ROT='1',
 VER='1',
 PACK_TYPE='0402LF',
 CDS_LIB='pure_quanta',
 CDS_PART_NAME='Q_RES_0402LF-220,1%,1/16W,CHIPA',
 WATTAGE='1/16W',
 TOLERANCE='1%',
 MATERIAL='CHIP',
 VALUE='220',
 PRIM_FILE='W:/<user>/logical/q_res/chips/chips.prt';

PART_NAME
 R81 'Q_RES_0402LF-4.7K,1%,1/16W,CHIA':;

SECTION_NUMBER 1
 '@SCM_LIB.SCM(SCH_1):PAGE11_I245@PURE_QUANTA.Q_RES(CHIPS)':
 C_PATH='@scm_lib.scm(sch_1):page11_i245@pure_quanta.q_res(chips)',
 P_PATH='@scm_lib.scm(sch_1):page11_i245@pure_quanta.q_res(chips)',
 PATH='I245',
 DRAWING='@SCM_LIB.SCM(SCH_1):PAGE11',
 PHYS_PAGE='11',
 XY='(-3325,2750)',
 ROT='0',
 VER='1',
 PACK_TYPE='0402LF',
 LOCATION='R81',
 CDS_LIB='pure_quanta',
 CDS_PART_NAME='Q_RES_0402LF-4.7K,1%,1/16W,CHIA',
 WATTAGE='1/16W',
 TOLERANCE='1%',
 MATERIAL='CHIP',
 VALUE='4.7K',
 PRIM_FILE='W:/<user>/logical/q_res/chips/chips.prt';

PART_NAME
 R82 'Q_RES_0402LF-2K,1%,1/16W,CHIP,A':;

SECTION_NUMBER 1
 '@SCM_LIB.SCM(SCH_1):PAGE11_I232@PURE_QUANTA.Q_RES(CHIPS)':
 C_PATH='@scm_lib.scm(sch_1):page11_i232@pure_quanta.q_res(chips)',
 P_PATH='@scm_lib.scm(sch_1):page11_i232@pure_quanta.q_res(chips)',
 PATH='I232',
 DRAWING='@SCM_LIB.SCM(SCH_1):PAGE11',
 PHYS_PAGE='11',
 XY='(2450,6125)',
 ROT='0',
 VER='1',
 PACK_TYPE='0402LF',
 LOCATION='R82',
 CDS_LIB='pure_quanta',
 CDS_PART_NAME='Q_RES_0402LF-2K,1%,1/16W,CHIP,A',
 WATTAGE='1/16W',
 TOLERANCE='1%',
 MATERIAL='CHIP',
 VALUE='2K',
 PRIM_FILE='W:/<user>/logical/q_res/chips/chips.prt';

PART_NAME
 R83 'Q_RES_0402LF-0,5%,1/16W,CHIP,CA':;

SECTION_NUMBER 1
 '@SCM_LIB.SCM(SCH_1):PAGE28_I164@PURE_QUANTA.Q_RES(CHIPS)':
 C_PATH='@scm_lib.scm(sch_1):page28_i164@pure_quanta.q_res(chips)',
 P_PATH='@scm_lib.scm(sch_1):page28_i164@pure_quanta.q_res(chips)',
 PATH='I164',
 DRAWING='@SCM_LIB.SCM(SCH_1):PAGE28',
 PHYS_PAGE='28',
 XY='(2725,-600)',
 ROT='2',
 VER='1',
 PACK_TYPE='0402LF',
 LOCATION='R83',
 CDS_LIB='pure_quanta',
 CDS_PART_NAME='Q_RES_0402LF-0,5%,1/16W,CHIP,CA',
 WATTAGE='1/16W',
 TOLERANCE='5%',
 MATERIAL='CHIP',
 VALUE='0',
 PRIM_FILE='W:/<user>/logical/q_res/chips/chips.prt';

PART_NAME
 R84 'Q_RES_0402LF-0,5%,1/16W,CHIP,CA':;

SECTION_NUMBER 1
 '@SCM_LIB.SCM(SCH_1):PAGE23_I61@PURE_QUANTA.Q_RES(CHIPS)':
 C_PATH='@scm_lib.scm(sch_1):page23_i61@pure_quanta.q_res(chips)',
 P_PATH='@scm_lib.scm(sch_1):page23_i61@pure_quanta.q_res(chips)',
 PATH='I61',
 DRAWING='@SCM_LIB.SCM(SCH_1):PAGE23',
 PHYS_PAGE='23',
 XY='(425,2725)',
 ROT='0',
 VER='1',
 PACK_TYPE='0402LF',
 LOCATION='R84',
 CDS_LIB='pure_quanta',
 CDS_PART_NAME='Q_RES_0402LF-0,5%,1/16W,CHIP,CA',
 WATTAGE='1/16W',
 TOLERANCE='5%',
 MATERIAL='CHIP',
 VALUE='0',
 PRIM_FILE='W:/<user>/logical/q_res/chips/chips.prt';

PART_NAME
 R85 'Q_RES_0402LF-0,5%,1/16W,CHIP,CA':;

SECTION_NUMBER 1
 '@SCM_LIB.SCM(SCH_1):PAGE23_I60@PURE_QUANTA.Q_RES(CHIPS)':
 C_PATH='@scm_lib.scm(sch_1):page23_i60@pure_quanta.q_res(chips)',
 P_PATH='@scm_lib.scm(sch_1):page23_i60@pure_quanta.q_res(chips)',
 PATH='I60',
 DRAWING='@SCM_LIB.SCM(SCH_1):PAGE23',
 PHYS_PAGE='23',
 XY='(625,2325)',
 ROT='0',
 VER='1',
 PACK_TYPE='0402LF',
 LOCATION='R85',
 CDS_LIB='pure_quanta',
 CDS_PART_NAME='Q_RES_0402LF-0,5%,1/16W,CHIP,CA',
 WATTAGE='1/16W',
 TOLERANCE='5%',
 MATERIAL='CHIP',
 VALUE='0',
 PRIM_FILE='W:/<user>/logical/q_res/chips/chips.prt';

PART_NAME
 R86 'Q_RES_0402LF-0,5%,1/16W,CHIP,CA':;

SECTION_NUMBER 1
 '@SCM_LIB.SCM(SCH_1):PAGE23_I51@PURE_QUANTA.Q_RES(CHIPS)':
 C_PATH='@scm_lib.scm(sch_1):page23_i51@pure_quanta.q_res(chips)',
 P_PATH='@scm_lib.scm(sch_1):page23_i51@pure_quanta.q_res(chips)',
 PATH='I51',
 DRAWING='@SCM_LIB.SCM(SCH_1):PAGE23',
 PHYS_PAGE='23',
 XY='(-350,-50)',
 ROT='0',
 VER='1',
 PACK_TYPE='0402LF',
 LOCATION='R86',
 CDS_LIB='pure_quanta',
 CDS_PART_NAME='Q_RES_0402LF-0,5%,1/16W,CHIP,CA',
 WATTAGE='1/16W',
 TOLERANCE='5%',
 MATERIAL='CHIP',
 VALUE='0',
 PRIM_FILE='W:/<user>/logical/q_res/chips/chips.prt';

PART_NAME
 R87 'Q_RES_0402LF-150,1%,1/16W,CHIPA':;

SECTION_NUMBER 1
 '@SCM_LIB.SCM(SCH_1):PAGE23_I57@PURE_QUANTA.Q_RES(CHIPS)':
 C_PATH='@scm_lib.scm(sch_1):page23_i57@pure_quanta.q_res(chips)',
 P_PATH='@scm_lib.scm(sch_1):page23_i57@pure_quanta.q_res(chips)',
 PATH='I57',
 DRAWING='@SCM_LIB.SCM(SCH_1):PAGE23',
 PHYS_PAGE='23',
 XY='(1450,1075)',
 ROT='0',
 VER='2',
 PACK_TYPE='0402LF',
 LOCATION='R87',
 CDS_LIB='pure_quanta',
 CDS_PART_NAME='Q_RES_0402LF-150,1%,1/16W,CHIPA',
 WATTAGE='1/16W',
 TOLERANCE='1%',
 MATERIAL='CHIP',
 VALUE='150',
 PRIM_FILE='W:/<user>/logical/q_res/chips/chips.prt';

PART_NAME
 R88 'Q_RES_0402LF-150,1%,1/16W,CHIPA':;

SECTION_NUMBER 1
 '@SCM_LIB.SCM(SCH_1):PAGE23_I59@PURE_QUANTA.Q_RES(CHIPS)':
 C_PATH='@scm_lib.scm(sch_1):page23_i59@pure_quanta.q_res(chips)',
 P_PATH='@scm_lib.scm(sch_1):page23_i59@pure_quanta.q_res(chips)',
 PATH='I59',
 DRAWING='@SCM_LIB.SCM(SCH_1):PAGE23',
 PHYS_PAGE='23',
 XY='(2000,1100)',
 ROT='0',
 VER='2',
 PACK_TYPE='0402LF',
 LOCATION='R88',
 CDS_LIB='pure_quanta',
 CDS_PART_NAME='Q_RES_0402LF-150,1%,1/16W,CHIPA',
 WATTAGE='1/16W',
 TOLERANCE='1%',
 MATERIAL='CHIP',
 VALUE='150',
 PRIM_FILE='W:/<user>/logical/q_res/chips/chips.prt';

PART_NAME
 R89 'Q_RES_0402LF-150,1%,1/16W,CHIPA':;

SECTION_NUMBER 1
 '@SCM_LIB.SCM(SCH_1):PAGE23_I65@PURE_QUANTA.Q_RES(CHIPS)':
 C_PATH='@scm_lib.scm(sch_1):page23_i65@pure_quanta.q_res(chips)',
 P_PATH='@scm_lib.scm(sch_1):page23_i65@pure_quanta.q_res(chips)',
 PATH='I65',
 DRAWING='@SCM_LIB.SCM(SCH_1):PAGE23',
 PHYS_PAGE='23',
 XY='(2525,1100)',
 ROT='0',
 VER='2',
 PACK_TYPE='0402LF',
 LOCATION='R89',
 CDS_LIB='pure_quanta',
 CDS_PART_NAME='Q_RES_0402LF-150,1%,1/16W,CHIPA',
 WATTAGE='1/16W',
 TOLERANCE='1%',
 MATERIAL='CHIP',
 VALUE='150',
 PRIM_FILE='W:/<user>/logical/q_res/chips/chips.prt';

PART_NAME
 R90 'Q_RES_0402LF-4.7K,1%,1/16W,EMPA':;

SECTION_NUMBER 1
 '@SCM_LIB.SCM(SCH_1):PAGE21_I182@PURE_QUANTA.Q_RES(CHIPS)':
 C_PATH='@scm_lib.scm(sch_1):page21_i182@pure_quanta.q_res(chips)',
 P_PATH='@scm_lib.scm(sch_1):page21_i182@pure_quanta.q_res(chips)',
 PATH='I182',
 DRAWING='@SCM_LIB.SCM(SCH_1):PAGE21',
 PHYS_PAGE='21',
 XY='(3100,3925)',
 ROT='0',
 VER='2',
 PACK_TYPE='0402LF',
 LOCATION='R90',
 CDS_LIB='pure_quanta',
 CDS_PART_NAME='Q_RES_0402LF-4.7K,1%,1/16W,EMPA',
 WATTAGE='1/16W',
 TOLERANCE='1%',
 MATERIAL='EMPTY',
 VALUE='4.7K',
 PRIM_FILE='W:/<user>/logical/q_res/chips/chips.prt';

PART_NAME
 R91 'Q_RES_0402LF-2.2K,5%,1/16W,CHIA':;

SECTION_NUMBER 1
 '@SCM_LIB.SCM(SCH_1):PAGE23_I62@PURE_QUANTA.Q_RES(CHIPS)':
 C_PATH='@scm_lib.scm(sch_1):page23_i62@pure_quanta.q_res(chips)',
 P_PATH='@scm_lib.scm(sch_1):page23_i62@pure_quanta.q_res(chips)',
 PATH='I62',
 DRAWING='@SCM_LIB.SCM(SCH_1):PAGE23',
 PHYS_PAGE='23',
 XY='(775,-200)',
 ROT='0',
 VER='2',
 PACK_TYPE='0402LF',
 LOCATION='R91',
 CDS_LIB='pure_quanta',
 CDS_PART_NAME='Q_RES_0402LF-2.2K,5%,1/16W,CHIA',
 WATTAGE='1/16W',
 TOLERANCE='5%',
 MATERIAL='CHIP',
 VALUE='2.2K',
 PRIM_FILE='W:/<user>/logical/q_res/chips/chips.prt';

PART_NAME
 R92 'Q_RES_0402LF-2.2K,5%,1/16W,CHIA':;

SECTION_NUMBER 1
 '@SCM_LIB.SCM(SCH_1):PAGE23_I64@PURE_QUANTA.Q_RES(CHIPS)':
 C_PATH='@scm_lib.scm(sch_1):page23_i64@pure_quanta.q_res(chips)',
 P_PATH='@scm_lib.scm(sch_1):page23_i64@pure_quanta.q_res(chips)',
 PATH='I64',
 DRAWING='@SCM_LIB.SCM(SCH_1):PAGE23',
 PHYS_PAGE='23',
 XY='(1025,-200)',
 ROT='0',
 VER='2',
 PACK_TYPE='0402LF',
 LOCATION='R92',
 CDS_LIB='pure_quanta',
 CDS_PART_NAME='Q_RES_0402LF-2.2K,5%,1/16W,CHIA',
 WATTAGE='1/16W',
 TOLERANCE='5%',
 MATERIAL='CHIP',
 VALUE='2.2K',
 PRIM_FILE='W:/<user>/logical/q_res/chips/chips.prt';

PART_NAME
 R93 'Q_RES_0402LF-33.2,1%,1/16W,CHIA':;

SECTION_NUMBER 1
 '@SCM_LIB.SCM(SCH_1):PAGE12_I276@PURE_QUANTA.Q_RES(CHIPS)':
 C_PATH='@scm_lib.scm(sch_1):page12_i276@pure_quanta.q_res(chips)',
 P_PATH='@scm_lib.scm(sch_1):page12_i276@pure_quanta.q_res(chips)',
 PATH='I276',
 DRAWING='@SCM_LIB.SCM(SCH_1):PAGE12',
 PHYS_PAGE='12',
 XY='(4775,-400)',
 ROT='0',
 VER='1',
 PACK_TYPE='0402LF',
 LOCATION='R93',
 CDS_LIB='pure_quanta',
 CDS_PART_NAME='Q_RES_0402LF-33.2,1%,1/16W,CHIA',
 WATTAGE='1/16W',
 TOLERANCE='1%',
 MATERIAL='CHIP',
 VALUE='33.2',
 PRIM_FILE='W:/<user>/logical/q_res/chips/chips.prt';

PART_NAME
 R94 'Q_RES_0402LF-4.7K,1%,1/16W,CHIA':;

SECTION_NUMBER 1
 '@SCM_LIB.SCM(SCH_1):PAGE27_I246@PURE_QUANTA.Q_RES(CHIPS)':
 C_PATH='@scm_lib.scm(sch_1):page27_i246@pure_quanta.q_res(chips)',
 P_PATH='@scm_lib.scm(sch_1):page27_i246@pure_quanta.q_res(chips)',
 PATH='I246',
 DRAWING='@SCM_LIB.SCM(SCH_1):PAGE27',
 PHYS_PAGE='27',
 XY='(-3325,-975)',
 ROT='0',
 VER='2',
 PACK_TYPE='0402LF',
 LOCATION='R94',
 CDS_LIB='pure_quanta',
 CDS_PART_NAME='Q_RES_0402LF-4.7K,1%,1/16W,CHIA',
 WATTAGE='1/16W',
 TOLERANCE='1%',
 MATERIAL='CHIP',
 VALUE='4.7K',
 PRIM_FILE='W:/<user>/logical/q_res/chips/chips.prt';

PART_NAME
 R95 'Q_RES_0402LF-0,5%,1/16W,CHIP,CA':;

SECTION_NUMBER 1
 '@SCM_LIB.SCM(SCH_1):PAGE28_I152@PURE_QUANTA.Q_RES(CHIPS)':
 C_PATH='@scm_lib.scm(sch_1):page28_i152@pure_quanta.q_res(chips)',
 P_PATH='@scm_lib.scm(sch_1):page28_i152@pure_quanta.q_res(chips)',
 PATH='I152',
 DRAWING='@SCM_LIB.SCM(SCH_1):PAGE28',
 PHYS_PAGE='28',
 XY='(-2400,-1225)',
 ROT='0',
 VER='1',
 PACK_TYPE='0402LF',
 LOCATION='R95',
 CDS_LIB='pure_quanta',
 CDS_PART_NAME='Q_RES_0402LF-0,5%,1/16W,CHIP,CA',
 WATTAGE='1/16W',
 TOLERANCE='5%',
 MATERIAL='CHIP',
 VALUE='0',
 PRIM_FILE='W:/<user>/logical/q_res/chips/chips.prt';

PART_NAME
 R96 'Q_RES_0402LF-33.2,1%,1/16W,CHIA':;

SECTION_NUMBER 1
 '@SCM_LIB.SCM(SCH_1):PAGE13_I286@PURE_QUANTA.Q_RES(CHIPS)':
 C_PATH='@scm_lib.scm(sch_1):page13_i286@pure_quanta.q_res(chips)',
 P_PATH='@scm_lib.scm(sch_1):page13_i286@pure_quanta.q_res(chips)',
 PATH='I286',
 DRAWING='@SCM_LIB.SCM(SCH_1):PAGE13',
 SEC_TYPE='0402LF',
 PHYS_PAGE='13',
 XY='(3650,3025)',
 ROT='0',
 VER='1',
 PACK_TYPE='0402LF',
 LOCATION='R96',
 SEC='1',
 CDS_LIB='pure_quanta',
 CDS_PART_NAME='Q_RES_0402LF-33.2,1%,1/16W,CHIA',
 WATTAGE='1/16W',
 TOLERANCE='1%',
 MATERIAL='CHIP',
 VALUE='33.2',
 PRIM_FILE='W:/<user>/logical/q_res/chips/chips.prt';

PART_NAME
 R97 'Q_RES_0402LF-0,5%,1/16W,CHIP,CA':;

SECTION_NUMBER 1
 '@SCM_LIB.SCM(SCH_1):PAGE46_I115@PURE_QUANTA.Q_RES(CHIPS)':
 C_PATH='@scm_lib.scm(sch_1):page46_i115@pure_quanta.q_res(chips)',
 P_PATH='@scm_lib.scm(sch_1):page46_i115@pure_quanta.q_res(chips)',
 PATH='I115',
 DRAWING='@SCM_LIB.SCM(SCH_1):PAGE46',
 PHYS_PAGE='46',
 XY='(-9900,-5650)',
 ROT='2',
 VER='1',
 PACK_TYPE='0402LF',
 LOCATION='R97',
 CDS_LIB='pure_quanta',
 CDS_PART_NAME='Q_RES_0402LF-0,5%,1/16W,CHIP,CA',
 WATTAGE='1/16W',
 TOLERANCE='5%',
 MATERIAL='CHIP',
 VALUE='0',
 PRIM_FILE='W:/<user>/logical/q_res/chips/chips.prt';

PART_NAME
 R98 'Q_RES_0402LF-0,5%,1/16W,CHIP,CA':;

SECTION_NUMBER 1
 '@SCM_LIB.SCM(SCH_1):PAGE46_I119@PURE_QUANTA.Q_RES(CHIPS)':
 C_PATH='@scm_lib.scm(sch_1):page46_i119@pure_quanta.q_res(chips)',
 P_PATH='@scm_lib.scm(sch_1):page46_i119@pure_quanta.q_res(chips)',
 PATH='I119',
 DRAWING='@SCM_LIB.SCM(SCH_1):PAGE46',
 PHYS_PAGE='46',
 XY='(-9900,-5700)',
 ROT='2',
 VER='1',
 PACK_TYPE='0402LF',
 LOCATION='R98',
 CDS_LIB='pure_quanta',
 CDS_PART_NAME='Q_RES_0402LF-0,5%,1/16W,CHIP,CA',
 WATTAGE='1/16W',
 TOLERANCE='5%',
 MATERIAL='CHIP',
 VALUE='0',
 PRIM_FILE='W:/<user>/logical/q_res/chips/chips.prt';

PART_NAME
 R99 'Q_RES_0402LF-0,5%,1/16W,CHIP,CA':;

SECTION_NUMBER 1
 '@SCM_LIB.SCM(SCH_1):PAGE52_I96@PURE_QUANTA.Q_RES(CHIPS)':
 C_PATH='@scm_lib.scm(sch_1):page52_i96@pure_quanta.q_res(chips)',
 P_PATH='@scm_lib.scm(sch_1):page52_i96@pure_quanta.q_res(chips)',
 PATH='I96',
 DRAWING='@SCM_LIB.SCM(SCH_1):PAGE52',
 PHYS_PAGE='52',
 XY='(400,-1700)',
 ROT='0',
 VER='1',
 PACK_TYPE='0402LF',
 LOCATION='R99',
 CDS_LIB='pure_quanta',
 CDS_PART_NAME='Q_RES_0402LF-0,5%,1/16W,CHIP,CA',
 WATTAGE='1/16W',
 TOLERANCE='5%',
 MATERIAL='CHIP',
 VALUE='0',
 PRIM_FILE='W:/<user>/logical/q_res/chips/chips.prt';

PART_NAME
 R100 'Q_RES_0402LF-33.2,1%,1/16W,CHIA':;

SECTION_NUMBER 1
 '@SCM_LIB.SCM(SCH_1):PAGE46_I147@PURE_QUANTA.Q_RES(CHIPS)':
 C_PATH='@scm_lib.scm(sch_1):page46_i147@pure_quanta.q_res(chips)',
 P_PATH='@scm_lib.scm(sch_1):page46_i147@pure_quanta.q_res(chips)',
 PATH='I147',
 DRAWING='@SCM_LIB.SCM(SCH_1):PAGE46',
 PHYS_PAGE='46',
 XY='(-9900,-5750)',
 ROT='2',
 VER='1',
 PACK_TYPE='0402LF',
 LOCATION='R100',
 CDS_LIB='pure_quanta',
 CDS_PART_NAME='Q_RES_0402LF-33.2,1%,1/16W,CHIA',
 WATTAGE='1/16W',
 TOLERANCE='1%',
 MATERIAL='CHIP',
 VALUE='33.2',
 PRIM_FILE='W:/<user>/logical/q_res/chips/chips.prt';

PART_NAME
 R101 'Q_RES_0402LF-4.7K,1%,1/16W,CHIA':;

SECTION_NUMBER 1
 '@SCM_LIB.SCM(SCH_1):PAGE11_I214@PURE_QUANTA.Q_RES(CHIPS)':
 C_PATH='@scm_lib.scm(sch_1):page11_i214@pure_quanta.q_res(chips)',
 P_PATH='@scm_lib.scm(sch_1):page11_i214@pure_quanta.q_res(chips)',
 PATH='I214',
 DRAWING='@SCM_LIB.SCM(SCH_1):PAGE11',
 PHYS_PAGE='11',
 XY='(-3325,5425)',
 ROT='0',
 VER='1',
 PACK_TYPE='0402LF',
 LOCATION='R101',
 CDS_LIB='pure_quanta',
 CDS_PART_NAME='Q_RES_0402LF-4.7K,1%,1/16W,CHIA',
 WATTAGE='1/16W',
 TOLERANCE='1%',
 MATERIAL='CHIP',
 VALUE='4.7K',
 PRIM_FILE='W:/<user>/logical/q_res/chips/chips.prt';

PART_NAME
 R102 'Q_RES_0402LF-33.2,1%,1/16W,CHIA':;

SECTION_NUMBER 1
 '@SCM_LIB.SCM(SCH_1):PAGE30_I148@PURE_QUANTA.Q_RES(CHIPS)':
 C_PATH='@scm_lib.scm(sch_1):page30_i148@pure_quanta.q_res(chips)',
 P_PATH='@scm_lib.scm(sch_1):page30_i148@pure_quanta.q_res(chips)',
 PATH='I148',
 DRAWING='@SCM_LIB.SCM(SCH_1):PAGE30',
 SEC_TYPE='0402LF',
 PHYS_PAGE='30',
 XY='(3250,950)',
 ROT='0',
 VER='1',
 PACK_TYPE='0402LF',
 LOCATION='R102',
 SEC='1',
 CDS_LIB='pure_quanta',
 CDS_PART_NAME='Q_RES_0402LF-33.2,1%,1/16W,CHIA',
 WATTAGE='1/16W',
 TOLERANCE='1%',
 MATERIAL='CHIP',
 VALUE='33.2',
 PRIM_FILE='W:/<user>/logical/q_res/chips/chips.prt';

PART_NAME
 R103 'Q_RES_0402LF-4.7K,1%,1/16W,CHIA':;

SECTION_NUMBER 1
 '@SCM_LIB.SCM(SCH_1):PAGE11_I219@PURE_QUANTA.Q_RES(CHIPS)':
 C_PATH='@scm_lib.scm(sch_1):page11_i219@pure_quanta.q_res(chips)',
 P_PATH='@scm_lib.scm(sch_1):page11_i219@pure_quanta.q_res(chips)',
 PATH='I219',
 DRAWING='@SCM_LIB.SCM(SCH_1):PAGE11',
 PHYS_PAGE='11',
 XY='(-3325,5225)',
 ROT='0',
 VER='1',
 PACK_TYPE='0402LF',
 LOCATION='R103',
 CDS_LIB='pure_quanta',
 CDS_PART_NAME='Q_RES_0402LF-4.7K,1%,1/16W,CHIA',
 WATTAGE='1/16W',
 TOLERANCE='1%',
 MATERIAL='CHIP',
 VALUE='4.7K',
 PRIM_FILE='W:/<user>/logical/q_res/chips/chips.prt';

PART_NAME
 R104 'Q_RES_0402LF-33.2,1%,1/16W,CHIA':;

SECTION_NUMBER 1
 '@SCM_LIB.SCM(SCH_1):PAGE30_I147@PURE_QUANTA.Q_RES(CHIPS)':
 C_PATH='@scm_lib.scm(sch_1):page30_i147@pure_quanta.q_res(chips)',
 P_PATH='@scm_lib.scm(sch_1):page30_i147@pure_quanta.q_res(chips)',
 PATH='I147',
 DRAWING='@SCM_LIB.SCM(SCH_1):PAGE30',
 SEC_TYPE='0402LF',
 PHYS_PAGE='30',
 XY='(3250,850)',
 ROT='0',
 VER='1',
 PACK_TYPE='0402LF',
 LOCATION='R104',
 SEC='1',
 CDS_LIB='pure_quanta',
 CDS_PART_NAME='Q_RES_0402LF-33.2,1%,1/16W,CHIA',
 WATTAGE='1/16W',
 TOLERANCE='1%',
 MATERIAL='CHIP',
 VALUE='33.2',
 PRIM_FILE='W:/<user>/logical/q_res/chips/chips.prt';

PART_NAME
 R105 'Q_RES_0402LF-0,5%,1/16W,CHIP,CA':;

SECTION_NUMBER 1
 '@SCM_LIB.SCM(SCH_1):PAGE36_I58@PURE_QUANTA.Q_RES(CHIPS)':
 C_PATH='@scm_lib.scm(sch_1):page36_i58@pure_quanta.q_res(chips)',
 P_PATH='@scm_lib.scm(sch_1):page36_i58@pure_quanta.q_res(chips)',
 PATH='I58',
 DRAWING='@SCM_LIB.SCM(SCH_1):PAGE36',
 SEC_TYPE='0402LF',
 PHYS_PAGE='36',
 XY='(-2525,3425)',
 ROT='0',
 VER='1',
 PACK_TYPE='0402LF',
 SEC='1',
 CDS_LIB='pure_quanta',
 CDS_PART_NAME='Q_RES_0402LF-0,5%,1/16W,CHIP,CA',
 WATTAGE='1/16W',
 TOLERANCE='5%',
 MATERIAL='CHIP',
 VALUE='0',
 PRIM_FILE='W:/<user>/logical/q_res/chips/chips.prt';

PART_NAME
 R106 'Q_RES_0402LF-0,5%,1/16W,EMPTY,A':;

SECTION_NUMBER 1
 '@SCM_LIB.SCM(SCH_1):PAGE22_I12@PURE_QUANTA.Q_RES(CHIPS)':
 C_PATH='@scm_lib.scm(sch_1):page22_i12@pure_quanta.q_res(chips)',
 P_PATH='@scm_lib.scm(sch_1):page22_i12@pure_quanta.q_res(chips)',
 PATH='I12',
 DRAWING='@SCM_LIB.SCM(SCH_1):PAGE22',
 PHYS_PAGE='22',
 XY='(-2025,3650)',
 ROT='0',
 VER='1',
 PACK_TYPE='0402LF',
 LOCATION='R106',
 CDS_LIB='pure_quanta',
 CDS_PART_NAME='Q_RES_0402LF-0,5%,1/16W,EMPTY,A',
 WATTAGE='1/16W',
 TOLERANCE='5%',
 MATERIAL='EMPTY',
 VALUE='0',
 PRIM_FILE='W:/<user>/logical/q_res/chips/chips.prt';

PART_NAME
 R107 'Q_RES_0402LF-316,1%,1/16W,CHIPA':;

SECTION_NUMBER 1
 '@SCM_LIB.SCM(SCH_1):PAGE50_I222@PURE_QUANTA.Q_RES(CHIPS)':
 C_PATH='@scm_lib.scm(sch_1):page50_i222@pure_quanta.q_res(chips)',
 P_PATH='@scm_lib.scm(sch_1):page50_i222@pure_quanta.q_res(chips)',
 PATH='I222',
 DRAWING='@SCM_LIB.SCM(SCH_1):PAGE50',
 PHYS_PAGE='50',
 XY='(-750,1625)',
 ROT='0',
 VER='1',
 PACK_TYPE='0402LF',
 CDS_LIB='pure_quanta',
 CDS_PART_NAME='Q_RES_0402LF-316,1%,1/16W,CHIPA',
 WATTAGE='1/16W',
 TOLERANCE='1%',
 MATERIAL='CHIP',
 VALUE='316',
 PRIM_FILE='W:/<user>/logical/q_res/chips/chips.prt';

PART_NAME
 R108 'Q_RES_0402LF-49.9,1%,1/16W,CHIA':;

SECTION_NUMBER 1
 '@SCM_LIB.SCM(SCH_1):PAGE22_I65@PURE_QUANTA.Q_RES(CHIPS)':
 C_PATH='@scm_lib.scm(sch_1):page22_i65@pure_quanta.q_res(chips)',
 P_PATH='@scm_lib.scm(sch_1):page22_i65@pure_quanta.q_res(chips)',
 PATH='I65',
 DRAWING='@SCM_LIB.SCM(SCH_1):PAGE22',
 PHYS_PAGE='22',
 XY='(450,1000)',
 ROT='0',
 VER='1',
 PACK_TYPE='0402LF',
 LOCATION='R108',
 CDS_LIB='pure_quanta',
 CDS_PART_NAME='Q_RES_0402LF-49.9,1%,1/16W,CHIA',
 WATTAGE='1/16W',
 TOLERANCE='1%',
 MATERIAL='CHIP',
 VALUE='49.9',
 PRIM_FILE='W:/<user>/logical/q_res/chips/chips.prt';

PART_NAME
 R109 'Q_RES_0402LF-0,5%,1/16W,CHIP,CA':;

SECTION_NUMBER 1
 '@SCM_LIB.SCM(SCH_1):PAGE46_I114@PURE_QUANTA.Q_RES(CHIPS)':
 C_PATH='@scm_lib.scm(sch_1):page46_i114@pure_quanta.q_res(chips)',
 P_PATH='@scm_lib.scm(sch_1):page46_i114@pure_quanta.q_res(chips)',
 PATH='I114',
 DRAWING='@SCM_LIB.SCM(SCH_1):PAGE46',
 PHYS_PAGE='46',
 XY='(-9900,-5550)',
 ROT='2',
 VER='1',
 PACK_TYPE='0402LF',
 LOCATION='R109',
 CDS_LIB='pure_quanta',
 CDS_PART_NAME='Q_RES_0402LF-0,5%,1/16W,CHIP,CA',
 WATTAGE='1/16W',
 TOLERANCE='5%',
 MATERIAL='CHIP',
 VALUE='0',
 PRIM_FILE='W:/<user>/logical/q_res/chips/chips.prt';

PART_NAME
 R110 'Q_RES_0402LF-0,5%,1/16W,CHIP,CA':;

SECTION_NUMBER 1
 '@SCM_LIB.SCM(SCH_1):PAGE46_I116@PURE_QUANTA.Q_RES(CHIPS)':
 C_PATH='@scm_lib.scm(sch_1):page46_i116@pure_quanta.q_res(chips)',
 P_PATH='@scm_lib.scm(sch_1):page46_i116@pure_quanta.q_res(chips)',
 PATH='I116',
 DRAWING='@SCM_LIB.SCM(SCH_1):PAGE46',
 PHYS_PAGE='46',
 XY='(-9900,-5600)',
 ROT='2',
 VER='1',
 PACK_TYPE='0402LF',
 LOCATION='R110',
 CDS_LIB='pure_quanta',
 CDS_PART_NAME='Q_RES_0402LF-0,5%,1/16W,CHIP,CA',
 WATTAGE='1/16W',
 TOLERANCE='5%',
 MATERIAL='CHIP',
 VALUE='0',
 PRIM_FILE='W:/<user>/logical/q_res/chips/chips.prt';

PART_NAME
 R111 'Q_RES_0402LF-33.2,1%,1/16W,CHIA':;

SECTION_NUMBER 1
 '@SCM_LIB.SCM(SCH_1):PAGE13_I266@PURE_QUANTA.Q_RES(CHIPS)':
 C_PATH='@scm_lib.scm(sch_1):page13_i266@pure_quanta.q_res(chips)',
 P_PATH='@scm_lib.scm(sch_1):page13_i266@pure_quanta.q_res(chips)',
 PATH='I266',
 DRAWING='@SCM_LIB.SCM(SCH_1):PAGE13',
 SEC_TYPE='0402LF',
 PHYS_PAGE='13',
 XY='(3800,2825)',
 ROT='0',
 VER='1',
 PACK_TYPE='0402LF',
 LOCATION='R111',
 SEC='1',
 CDS_LIB='pure_quanta',
 CDS_PART_NAME='Q_RES_0402LF-33.2,1%,1/16W,CHIA',
 WATTAGE='1/16W',
 TOLERANCE='1%',
 MATERIAL='CHIP',
 VALUE='33.2',
 PRIM_FILE='W:/<user>/logical/q_res/chips/chips.prt';

PART_NAME
 R112 'Q_RES_0402LF-33.2,1%,1/16W,CHIA':;

SECTION_NUMBER 1
 '@SCM_LIB.SCM(SCH_1):PAGE13_I427@PURE_QUANTA.Q_RES(CHIPS)':
 C_PATH='@scm_lib.scm(sch_1):page13_i427@pure_quanta.q_res(chips)',
 P_PATH='@scm_lib.scm(sch_1):page13_i427@pure_quanta.q_res(chips)',
 PATH='I427',
 DRAWING='@SCM_LIB.SCM(SCH_1):PAGE13',
 PHYS_PAGE='13',
 XY='(3150,1575)',
 ROT='0',
 VER='1',
 PACK_TYPE='0402LF',
 LOCATION='R112',
 CDS_LIB='pure_quanta',
 CDS_PART_NAME='Q_RES_0402LF-33.2,1%,1/16W,CHIA',
 WATTAGE='1/16W',
 TOLERANCE='1%',
 MATERIAL='CHIP',
 VALUE='33.2',
 PRIM_FILE='W:/<user>/logical/q_res/chips/chips.prt';

PART_NAME
 R113 'Q_RES_0402LF-0,5%,1/16W,CHIP,CA':;

SECTION_NUMBER 1
 '@SCM_LIB.SCM(SCH_1):PAGE46_I105@PURE_QUANTA.Q_RES(CHIPS)':
 C_PATH='@scm_lib.scm(sch_1):page46_i105@pure_quanta.q_res(chips)',
 P_PATH='@scm_lib.scm(sch_1):page46_i105@pure_quanta.q_res(chips)',
 PATH='I105',
 DRAWING='@SCM_LIB.SCM(SCH_1):PAGE46',
 SEC_TYPE='0402LF',
 PHYS_PAGE='46',
 XY='(-6600,-5650)',
 ROT='2',
 VER='1',
 PACK_TYPE='0402LF',
 LOCATION='R113',
 SEC='1',
 CDS_LIB='pure_quanta',
 CDS_PART_NAME='Q_RES_0402LF-0,5%,1/16W,CHIP,CA',
 WATTAGE='1/16W',
 TOLERANCE='5%',
 MATERIAL='CHIP',
 VALUE='0',
 PRIM_FILE='W:/<user>/logical/q_res/chips/chips.prt';

PART_NAME
 R114 'Q_RES_0402LF-0,5%,1/16W,CHIP,CA':;

SECTION_NUMBER 1
 '@SCM_LIB.SCM(SCH_1):PAGE36_I57@PURE_QUANTA.Q_RES(CHIPS)':
 C_PATH='@scm_lib.scm(sch_1):page36_i57@pure_quanta.q_res(chips)',
 P_PATH='@scm_lib.scm(sch_1):page36_i57@pure_quanta.q_res(chips)',
 PATH='I57',
 DRAWING='@SCM_LIB.SCM(SCH_1):PAGE36',
 SEC_TYPE='0402LF',
 PHYS_PAGE='36',
 XY='(-2525,3375)',
 ROT='0',
 VER='1',
 PACK_TYPE='0402LF',
 SEC='1',
 CDS_LIB='pure_quanta',
 CDS_PART_NAME='Q_RES_0402LF-0,5%,1/16W,CHIP,CA',
 WATTAGE='1/16W',
 TOLERANCE='5%',
 MATERIAL='CHIP',
 VALUE='0',
 PRIM_FILE='W:/<user>/logical/q_res/chips/chips.prt';

PART_NAME
 R115 'Q_RES_0402LF-4.7K,1%,1/16W,EMPA':;

SECTION_NUMBER 1
 '@SCM_LIB.SCM(SCH_1):PAGE12_I4@PURE_QUANTA.Q_RES(CHIPS)':
 C_PATH='@scm_lib.scm(sch_1):page12_i4@pure_quanta.q_res(chips)',
 P_PATH='@scm_lib.scm(sch_1):page12_i4@pure_quanta.q_res(chips)',
 PATH='I4',
 DRAWING='@SCM_LIB.SCM(SCH_1):PAGE12',
 PHYS_PAGE='12',
 XY='(-1475,-325)',
 ROT='0',
 VER='1',
 PACK_TYPE='0402LF',
 LOCATION='R115',
 CDS_LIB='pure_quanta',
 CDS_PART_NAME='Q_RES_0402LF-4.7K,1%,1/16W,EMPA',
 WATTAGE='1/16W',
 TOLERANCE='1%',
 MATERIAL='EMPTY',
 VALUE='4.7K',
 PRIM_FILE='W:/<user>/logical/q_res/chips/chips.prt';

PART_NAME
 R116 'Q_RES_0402LF-4.7K,1%,1/16W,CHIA':;

SECTION_NUMBER 1
 '@SCM_LIB.SCM(SCH_1):PAGE12_I3@PURE_QUANTA.Q_RES(CHIPS)':
 C_PATH='@scm_lib.scm(sch_1):page12_i3@pure_quanta.q_res(chips)',
 P_PATH='@scm_lib.scm(sch_1):page12_i3@pure_quanta.q_res(chips)',
 PATH='I3',
 DRAWING='@SCM_LIB.SCM(SCH_1):PAGE12',
 PHYS_PAGE='12',
 XY='(-1475,-375)',
 ROT='0',
 VER='1',
 PACK_TYPE='0402LF',
 LOCATION='R116',
 CDS_LIB='pure_quanta',
 CDS_PART_NAME='Q_RES_0402LF-4.7K,1%,1/16W,CHIA',
 WATTAGE='1/16W',
 TOLERANCE='1%',
 MATERIAL='CHIP',
 VALUE='4.7K',
 PRIM_FILE='W:/<user>/logical/q_res/chips/chips.prt';

PART_NAME
 R117 'Q_RES_0402LF-4.7K,1%,1/16W,EMPA':;

SECTION_NUMBER 1
 '@SCM_LIB.SCM(SCH_1):PAGE12_I2@PURE_QUANTA.Q_RES(CHIPS)':
 C_PATH='@scm_lib.scm(sch_1):page12_i2@pure_quanta.q_res(chips)',
 P_PATH='@scm_lib.scm(sch_1):page12_i2@pure_quanta.q_res(chips)',
 PATH='I2',
 DRAWING='@SCM_LIB.SCM(SCH_1):PAGE12',
 PHYS_PAGE='12',
 XY='(-1475,-425)',
 ROT='0',
 VER='1',
 PACK_TYPE='0402LF',
 LOCATION='R117',
 CDS_LIB='pure_quanta',
 CDS_PART_NAME='Q_RES_0402LF-4.7K,1%,1/16W,EMPA',
 WATTAGE='1/16W',
 TOLERANCE='1%',
 MATERIAL='EMPTY',
 VALUE='4.7K',
 PRIM_FILE='W:/<user>/logical/q_res/chips/chips.prt';

PART_NAME
 R118 'Q_RES_0402LF-100K,1%,1/16W,CHIA':;

SECTION_NUMBER 1
 '@SCM_LIB.SCM(SCH_1):PAGE12_I53@PURE_QUANTA.Q_RES(CHIPS)':
 C_PATH='@scm_lib.scm(sch_1):page12_i53@pure_quanta.q_res(chips)',
 P_PATH='@scm_lib.scm(sch_1):page12_i53@pure_quanta.q_res(chips)',
 PATH='I53',
 DRAWING='@SCM_LIB.SCM(SCH_1):PAGE12',
 PHYS_PAGE='12',
 XY='(-1150,4800)',
 ROT='0',
 VER='1',
 PACK_TYPE='0402LF',
 LOCATION='R118',
 CDS_LIB='pure_quanta',
 CDS_PART_NAME='Q_RES_0402LF-100K,1%,1/16W,CHIA',
 WATTAGE='1/16W',
 TOLERANCE='1%',
 MATERIAL='CHIP',
 VALUE='100K',
 PRIM_FILE='W:/<user>/logical/q_res/chips/chips.prt';

PART_NAME
 R119 'Q_RES_0402LF-33.2,1%,1/16W,CHIA':;

SECTION_NUMBER 1
 '@SCM_LIB.SCM(SCH_1):PAGE12_I34@PURE_QUANTA.Q_RES(CHIPS)':
 C_PATH='@scm_lib.scm(sch_1):page12_i34@pure_quanta.q_res(chips)',
 P_PATH='@scm_lib.scm(sch_1):page12_i34@pure_quanta.q_res(chips)',
 PATH='I34',
 DRAWING='@SCM_LIB.SCM(SCH_1):PAGE12',
 PHYS_PAGE='12',
 XY='(-850,2000)',
 ROT='0',
 VER='1',
 PACK_TYPE='0402LF',
 LOCATION='R119',
 CDS_LIB='pure_quanta',
 CDS_PART_NAME='Q_RES_0402LF-33.2,1%,1/16W,CHIA',
 WATTAGE='1/16W',
 TOLERANCE='1%',
 MATERIAL='CHIP',
 VALUE='33.2',
 PRIM_FILE='W:/<user>/logical/q_res/chips/chips.prt';

PART_NAME
 R120 'Q_RES_0402LF-33.2,1%,1/16W,CHIA':;

SECTION_NUMBER 1
 '@SCM_LIB.SCM(SCH_1):PAGE12_I33@PURE_QUANTA.Q_RES(CHIPS)':
 C_PATH='@scm_lib.scm(sch_1):page12_i33@pure_quanta.q_res(chips)',
 P_PATH='@scm_lib.scm(sch_1):page12_i33@pure_quanta.q_res(chips)',
 PATH='I33',
 DRAWING='@SCM_LIB.SCM(SCH_1):PAGE12',
 PHYS_PAGE='12',
 XY='(-850,1950)',
 ROT='0',
 VER='1',
 PACK_TYPE='0402LF',
 LOCATION='R120',
 CDS_LIB='pure_quanta',
 CDS_PART_NAME='Q_RES_0402LF-33.2,1%,1/16W,CHIA',
 WATTAGE='1/16W',
 TOLERANCE='1%',
 MATERIAL='CHIP',
 VALUE='33.2',
 PRIM_FILE='W:/<user>/logical/q_res/chips/chips.prt';

PART_NAME
 R121 'Q_RES_0402LF-33.2,1%,1/16W,CHIA':;

SECTION_NUMBER 1
 '@SCM_LIB.SCM(SCH_1):PAGE13_I381@PURE_QUANTA.Q_RES(CHIPS)':
 C_PATH='@scm_lib.scm(sch_1):page13_i381@pure_quanta.q_res(chips)',
 P_PATH='@scm_lib.scm(sch_1):page13_i381@pure_quanta.q_res(chips)',
 PATH='I381',
 DRAWING='@SCM_LIB.SCM(SCH_1):PAGE13',
 PHYS_PAGE='13',
 XY='(3275,1375)',
 ROT='0',
 VER='1',
 PACK_TYPE='0402LF',
 LOCATION='R121',
 CDS_LIB='pure_quanta',
 CDS_PART_NAME='Q_RES_0402LF-33.2,1%,1/16W,CHIA',
 WATTAGE='1/16W',
 TOLERANCE='1%',
 MATERIAL='CHIP',
 VALUE='33.2',
 PRIM_FILE='W:/<user>/logical/q_res/chips/chips.prt';

PART_NAME
 R122 'Q_RES_0402LF-33.2,1%,1/16W,CHIA':;

SECTION_NUMBER 1
 '@SCM_LIB.SCM(SCH_1):PAGE13_I399@PURE_QUANTA.Q_RES(CHIPS)':
 C_PATH='@scm_lib.scm(sch_1):page13_i399@pure_quanta.q_res(chips)',
 P_PATH='@scm_lib.scm(sch_1):page13_i399@pure_quanta.q_res(chips)',
 PATH='I399',
 DRAWING='@SCM_LIB.SCM(SCH_1):PAGE13',
 PHYS_PAGE='13',
 XY='(-2200,1225)',
 ROT='0',
 VER='1',
 PACK_TYPE='0402LF',
 LOCATION='R122',
 CDS_LIB='pure_quanta',
 CDS_PART_NAME='Q_RES_0402LF-33.2,1%,1/16W,CHIA',
 WATTAGE='1/16W',
 TOLERANCE='1%',
 MATERIAL='CHIP',
 VALUE='33.2',
 PRIM_FILE='W:/<user>/logical/q_res/chips/chips.prt';

PART_NAME
 R123 'Q_RES_0402LF-33.2,1%,1/16W,CHIA':;

SECTION_NUMBER 1
 '@SCM_LIB.SCM(SCH_1):PAGE34_I156@PURE_QUANTA.Q_RES(CHIPS)':
 C_PATH='@scm_lib.scm(sch_1):page34_i156@pure_quanta.q_res(chips)',
 P_PATH='@scm_lib.scm(sch_1):page34_i156@pure_quanta.q_res(chips)',
 PATH='I156',
 DRAWING='@SCM_LIB.SCM(SCH_1):PAGE34',
 PHYS_PAGE='34',
 XY='(-7000,5150)',
 ROT='0',
 VER='1',
 PACK_TYPE='0402LF',
 LOCATION='R123',
 CDS_LIB='pure_quanta',
 CDS_PART_NAME='Q_RES_0402LF-33.2,1%,1/16W,CHIA',
 WATTAGE='1/16W',
 TOLERANCE='1%',
 MATERIAL='CHIP',
 VALUE='33.2',
 PRIM_FILE='W:/<user>/logical/q_res/chips/chips.prt';

PART_NAME
 R124 'Q_RES_0402LF-2K,1%,1/16W,CHIP,A':;

SECTION_NUMBER 1
 '@SCM_LIB.SCM(SCH_1):PAGE22_I67@PURE_QUANTA.Q_RES(CHIPS)':
 C_PATH='@scm_lib.scm(sch_1):page22_i67@pure_quanta.q_res(chips)',
 P_PATH='@scm_lib.scm(sch_1):page22_i67@pure_quanta.q_res(chips)',
 PATH='I67',
 DRAWING='@SCM_LIB.SCM(SCH_1):PAGE22',
 PHYS_PAGE='22',
 XY='(1275,2525)',
 ROT='0',
 VER='2',
 PACK_TYPE='0402LF',
 LOCATION='R124',
 CDS_LIB='pure_quanta',
 CDS_PART_NAME='Q_RES_0402LF-2K,1%,1/16W,CHIP,A',
 WATTAGE='1/16W',
 TOLERANCE='1%',
 MATERIAL='CHIP',
 VALUE='2K',
 PRIM_FILE='W:/<user>/logical/q_res/chips/chips.prt';

PART_NAME
 R125 'Q_RES_0402LF-100,1%,1/16W,CHIPA':;

SECTION_NUMBER 1
 '@SCM_LIB.SCM(SCH_1):PAGE22_I69@PURE_QUANTA.Q_RES(CHIPS)':
 C_PATH='@scm_lib.scm(sch_1):page22_i69@pure_quanta.q_res(chips)',
 P_PATH='@scm_lib.scm(sch_1):page22_i69@pure_quanta.q_res(chips)',
 PATH='I69',
 DRAWING='@SCM_LIB.SCM(SCH_1):PAGE22',
 PHYS_PAGE='22',
 XY='(3075,1425)',
 ROT='0',
 VER='1',
 PACK_TYPE='0402LF',
 LOCATION='R125',
 CDS_LIB='pure_quanta',
 CDS_PART_NAME='Q_RES_0402LF-100,1%,1/16W,CHIPA',
 WATTAGE='1/16W',
 TOLERANCE='1%',
 MATERIAL='CHIP',
 VALUE='100',
 PRIM_FILE='W:/<user>/logical/q_res/chips/chips.prt';

PART_NAME
 R126 'Q_RES_0402LF-10K,1%,1/16W,CHIPA':;

SECTION_NUMBER 1
 '@SCM_LIB.SCM(SCH_1):PAGE46_I134@PURE_QUANTA.Q_RES(CHIPS)':
 C_PATH='@scm_lib.scm(sch_1):page46_i134@pure_quanta.q_res(chips)',
 P_PATH='@scm_lib.scm(sch_1):page46_i134@pure_quanta.q_res(chips)',
 PATH='I134',
 DRAWING='@SCM_LIB.SCM(SCH_1):PAGE46',
 PHYS_PAGE='46',
 XY='(-9000,-3250)',
 ROT='2',
 VER='2',
 PACK_TYPE='0402LF',
 LOCATION='R126',
 CDS_LIB='pure_quanta',
 CDS_PART_NAME='Q_RES_0402LF-10K,1%,1/16W,CHIPA',
 WATTAGE='1/16W',
 TOLERANCE='1%',
 MATERIAL='CHIP',
 VALUE='10K',
 PRIM_FILE='W:/<user>/logical/q_res/chips/chips.prt';

PART_NAME
 R127 'Q_RES_0402LF-240,1%,1/16W,CHIPA':;

SECTION_NUMBER 1
 '@SCM_LIB.SCM(SCH_1):PAGE12_I46@PURE_QUANTA.Q_RES(CHIPS)':
 C_PATH='@scm_lib.scm(sch_1):page12_i46@pure_quanta.q_res(chips)',
 P_PATH='@scm_lib.scm(sch_1):page12_i46@pure_quanta.q_res(chips)',
 PATH='I46',
 DRAWING='@SCM_LIB.SCM(SCH_1):PAGE12',
 PHYS_PAGE='12',
 XY='(-200,2200)',
 ROT='0',
 VER='1',
 PACK_TYPE='0402LF',
 LOCATION='R127',
 CDS_LIB='pure_quanta',
 CDS_PART_NAME='Q_RES_0402LF-240,1%,1/16W,CHIPA',
 WATTAGE='1/16W',
 TOLERANCE='1%',
 MATERIAL='CHIP',
 VALUE='240',
 PRIM_FILE='W:/<user>/logical/q_res/chips/chips.prt';

PART_NAME
 R128 'Q_RES_0402LF-22,1%,1/16W,CHIP,A':;

SECTION_NUMBER 1
 '@SCM_LIB.SCM(SCH_1):PAGE12_I442@PURE_QUANTA.Q_RES(CHIPS)':
 C_PATH='@scm_lib.scm(sch_1):page12_i442@pure_quanta.q_res(chips)',
 P_PATH='@scm_lib.scm(sch_1):page12_i442@pure_quanta.q_res(chips)',
 PATH='I442',
 DRAWING='@SCM_LIB.SCM(SCH_1):PAGE12',
 PHYS_PAGE='12',
 XY='(3825,2100)',
 ROT='0',
 VER='1',
 PACK_TYPE='0402LF',
 LOCATION='R128',
 CDS_LIB='pure_quanta',
 CDS_PART_NAME='Q_RES_0402LF-22,1%,1/16W,CHIP,A',
 WATTAGE='1/16W',
 TOLERANCE='1%',
 MATERIAL='CHIP',
 VALUE='22',
 PRIM_FILE='W:/<user>/logical/q_res/chips/chips.prt';

PART_NAME
 R129 'Q_RES_0402LF-22,1%,1/16W,CHIP,A':;

SECTION_NUMBER 1
 '@SCM_LIB.SCM(SCH_1):PAGE12_I445@PURE_QUANTA.Q_RES(CHIPS)':
 C_PATH='@scm_lib.scm(sch_1):page12_i445@pure_quanta.q_res(chips)',
 P_PATH='@scm_lib.scm(sch_1):page12_i445@pure_quanta.q_res(chips)',
 PATH='I445',
 DRAWING='@SCM_LIB.SCM(SCH_1):PAGE12',
 PHYS_PAGE='12',
 XY='(3825,2050)',
 ROT='0',
 VER='1',
 PACK_TYPE='0402LF',
 LOCATION='R129',
 CDS_LIB='pure_quanta',
 CDS_PART_NAME='Q_RES_0402LF-22,1%,1/16W,CHIP,A',
 WATTAGE='1/16W',
 TOLERANCE='1%',
 MATERIAL='CHIP',
 VALUE='22',
 PRIM_FILE='W:/<user>/logical/q_res/chips/chips.prt';

PART_NAME
 R130 'Q_RES_0402LF-22,1%,1/16W,CHIP,A':;

SECTION_NUMBER 1
 '@SCM_LIB.SCM(SCH_1):PAGE12_I444@PURE_QUANTA.Q_RES(CHIPS)':
 C_PATH='@scm_lib.scm(sch_1):page12_i444@pure_quanta.q_res(chips)',
 P_PATH='@scm_lib.scm(sch_1):page12_i444@pure_quanta.q_res(chips)',
 PATH='I444',
 DRAWING='@SCM_LIB.SCM(SCH_1):PAGE12',
 PHYS_PAGE='12',
 XY='(3825,2000)',
 ROT='0',
 VER='1',
 PACK_TYPE='0402LF',
 LOCATION='R130',
 CDS_LIB='pure_quanta',
 CDS_PART_NAME='Q_RES_0402LF-22,1%,1/16W,CHIP,A',
 WATTAGE='1/16W',
 TOLERANCE='1%',
 MATERIAL='CHIP',
 VALUE='22',
 PRIM_FILE='W:/<user>/logical/q_res/chips/chips.prt';

PART_NAME
 R131 'Q_RES_0402LF-22,1%,1/16W,CHIP,A':;

SECTION_NUMBER 1
 '@SCM_LIB.SCM(SCH_1):PAGE12_I443@PURE_QUANTA.Q_RES(CHIPS)':
 C_PATH='@scm_lib.scm(sch_1):page12_i443@pure_quanta.q_res(chips)',
 P_PATH='@scm_lib.scm(sch_1):page12_i443@pure_quanta.q_res(chips)',
 PATH='I443',
 DRAWING='@SCM_LIB.SCM(SCH_1):PAGE12',
 PHYS_PAGE='12',
 XY='(3825,1950)',
 ROT='0',
 VER='1',
 PACK_TYPE='0402LF',
 LOCATION='R131',
 CDS_LIB='pure_quanta',
 CDS_PART_NAME='Q_RES_0402LF-22,1%,1/16W,CHIP,A',
 WATTAGE='1/16W',
 TOLERANCE='1%',
 MATERIAL='CHIP',
 VALUE='22',
 PRIM_FILE='W:/<user>/logical/q_res/chips/chips.prt';

PART_NAME
 R132 'Q_RES_0402LF-33.2,1%,1/16W,CHIA':;

SECTION_NUMBER 1
 '@SCM_LIB.SCM(SCH_1):PAGE12_I98@PURE_QUANTA.Q_RES(CHIPS)':
 C_PATH='@scm_lib.scm(sch_1):page12_i98@pure_quanta.q_res(chips)',
 P_PATH='@scm_lib.scm(sch_1):page12_i98@pure_quanta.q_res(chips)',
 PATH='I98',
 DRAWING='@SCM_LIB.SCM(SCH_1):PAGE12',
 PHYS_PAGE='12',
 XY='(4125,1850)',
 ROT='0',
 VER='1',
 PACK_TYPE='0402LF',
 LOCATION='R132',
 CDS_LIB='pure_quanta',
 CDS_PART_NAME='Q_RES_0402LF-33.2,1%,1/16W,CHIA',
 WATTAGE='1/16W',
 TOLERANCE='1%',
 MATERIAL='CHIP',
 VALUE='33.2',
 PRIM_FILE='W:/<user>/logical/q_res/chips/chips.prt';

PART_NAME
 R133 'Q_RES_0402LF-33.2,1%,1/16W,CHIA':;

SECTION_NUMBER 1
 '@SCM_LIB.SCM(SCH_1):PAGE12_I97@PURE_QUANTA.Q_RES(CHIPS)':
 C_PATH='@scm_lib.scm(sch_1):page12_i97@pure_quanta.q_res(chips)',
 P_PATH='@scm_lib.scm(sch_1):page12_i97@pure_quanta.q_res(chips)',
 PATH='I97',
 DRAWING='@SCM_LIB.SCM(SCH_1):PAGE12',
 PHYS_PAGE='12',
 XY='(4125,1800)',
 ROT='0',
 VER='1',
 PACK_TYPE='0402LF',
 LOCATION='R133',
 CDS_LIB='pure_quanta',
 CDS_PART_NAME='Q_RES_0402LF-33.2,1%,1/16W,CHIA',
 WATTAGE='1/16W',
 TOLERANCE='1%',
 MATERIAL='CHIP',
 VALUE='33.2',
 PRIM_FILE='W:/<user>/logical/q_res/chips/chips.prt';

PART_NAME
 R134 'Q_RES_0402LF-0,5%,1/16W,CHIP,CA':;

SECTION_NUMBER 1
 '@SCM_LIB.SCM(SCH_1):PAGE36_I47@PURE_QUANTA.Q_RES(CHIPS)':
 C_PATH='@scm_lib.scm(sch_1):page36_i47@pure_quanta.q_res(chips)',
 P_PATH='@scm_lib.scm(sch_1):page36_i47@pure_quanta.q_res(chips)',
 PATH='I47',
 DRAWING='@SCM_LIB.SCM(SCH_1):PAGE36',
 PHYS_PAGE='36',
 XY='(-2575,4575)',
 ROT='0',
 VER='1',
 PACK_TYPE='0402LF',
 CDS_LIB='pure_quanta',
 CDS_PART_NAME='Q_RES_0402LF-0,5%,1/16W,CHIP,CA',
 WATTAGE='1/16W',
 TOLERANCE='5%',
 MATERIAL='CHIP',
 VALUE='0',
 PRIM_FILE='W:/<user>/logical/q_res/chips/chips.prt';

PART_NAME
 R135 'Q_RES_0402LF-0,5%,1/16W,CHIP,CA':;

SECTION_NUMBER 1
 '@SCM_LIB.SCM(SCH_1):PAGE28_I109@PURE_QUANTA.Q_RES(CHIPS)':
 C_PATH='@scm_lib.scm(sch_1):page28_i109@pure_quanta.q_res(chips)',
 P_PATH='@scm_lib.scm(sch_1):page28_i109@pure_quanta.q_res(chips)',
 PATH='I109',
 DRAWING='@SCM_LIB.SCM(SCH_1):PAGE28',
 PHYS_PAGE='28',
 XY='(-1125,2225)',
 ROT='0',
 VER='1',
 PACK_TYPE='0402LF',
 LOCATION='R135',
 CDS_LIB='pure_quanta',
 CDS_PART_NAME='Q_RES_0402LF-0,5%,1/16W,CHIP,CA',
 WATTAGE='1/16W',
 TOLERANCE='5%',
 MATERIAL='CHIP',
 VALUE='0',
 PRIM_FILE='W:/<user>/logical/q_res/chips/chips.prt';

PART_NAME
 R136 'Q_RES_0402LF-10K,1%,1/16W,CHIPA':;

SECTION_NUMBER 1
 '@SCM_LIB.SCM(SCH_1):PAGE46_I132@PURE_QUANTA.Q_RES(CHIPS)':
 C_PATH='@scm_lib.scm(sch_1):page46_i132@pure_quanta.q_res(chips)',
 P_PATH='@scm_lib.scm(sch_1):page46_i132@pure_quanta.q_res(chips)',
 PATH='I132',
 DRAWING='@SCM_LIB.SCM(SCH_1):PAGE46',
 PHYS_PAGE='46',
 XY='(-6550,-2450)',
 ROT='2',
 VER='2',
 PACK_TYPE='0402LF',
 LOCATION='R136',
 CDS_LIB='pure_quanta',
 CDS_PART_NAME='Q_RES_0402LF-10K,1%,1/16W,CHIPA',
 WATTAGE='1/16W',
 TOLERANCE='1%',
 MATERIAL='CHIP',
 VALUE='10K',
 PRIM_FILE='W:/<user>/logical/q_res/chips/chips.prt';

PART_NAME
 R137 'Q_RES_0402LF-33.2,1%,1/16W,CHIA':;

SECTION_NUMBER 1
 '@SCM_LIB.SCM(SCH_1):PAGE12_I385@PURE_QUANTA.Q_RES(CHIPS)':
 C_PATH='@scm_lib.scm(sch_1):page12_i385@pure_quanta.q_res(chips)',
 P_PATH='@scm_lib.scm(sch_1):page12_i385@pure_quanta.q_res(chips)',
 PATH='I385',
 DRAWING='@SCM_LIB.SCM(SCH_1):PAGE12',
 PHYS_PAGE='12',
 XY='(4125,550)',
 ROT='0',
 VER='1',
 PACK_TYPE='0402LF',
 LOCATION='R137',
 CDS_LIB='pure_quanta',
 CDS_PART_NAME='Q_RES_0402LF-33.2,1%,1/16W,CHIA',
 WATTAGE='1/16W',
 TOLERANCE='1%',
 MATERIAL='CHIP',
 VALUE='33.2',
 PRIM_FILE='W:/<user>/logical/q_res/chips/chips.prt';

PART_NAME
 R138 'Q_RES_0402LF-40.2,1%,1/16W,CHIA':;

SECTION_NUMBER 1
 '@SCM_LIB.SCM(SCH_1):PAGE12_I513@PURE_QUANTA.Q_RES(CHIPS)':
 C_PATH='@scm_lib.scm(sch_1):page12_i513@pure_quanta.q_res(chips)',
 P_PATH='@scm_lib.scm(sch_1):page12_i513@pure_quanta.q_res(chips)',
 PATH='I513',
 DRAWING='@SCM_LIB.SCM(SCH_1):PAGE12',
 PHYS_PAGE='12',
 XY='(4125,1550)',
 ROT='0',
 VER='1',
 PACK_TYPE='0402LF',
 LOCATION='R138',
 CDS_LIB='pure_quanta',
 CDS_PART_NAME='Q_RES_0402LF-40.2,1%,1/16W,CHIA',
 WATTAGE='1/16W',
 TOLERANCE='1%',
 MATERIAL='CHIP',
 VALUE='40.2',
 PRIM_FILE='W:/<user>/logical/q_res/chips/chips.prt';

PART_NAME
 R139 'Q_RES_0402LF-33.2,1%,1/16W,CHIA':;

SECTION_NUMBER 1
 '@SCM_LIB.SCM(SCH_1):PAGE12_I512@PURE_QUANTA.Q_RES(CHIPS)':
 C_PATH='@scm_lib.scm(sch_1):page12_i512@pure_quanta.q_res(chips)',
 P_PATH='@scm_lib.scm(sch_1):page12_i512@pure_quanta.q_res(chips)',
 PATH='I512',
 DRAWING='@SCM_LIB.SCM(SCH_1):PAGE12',
 PHYS_PAGE='12',
 XY='(4125,1500)',
 ROT='0',
 VER='1',
 PACK_TYPE='0402LF',
 LOCATION='R139',
 CDS_LIB='pure_quanta',
 CDS_PART_NAME='Q_RES_0402LF-33.2,1%,1/16W,CHIA',
 WATTAGE='1/16W',
 TOLERANCE='1%',
 MATERIAL='CHIP',
 VALUE='33.2',
 PRIM_FILE='W:/<user>/logical/q_res/chips/chips.prt';

PART_NAME
 R140 'Q_RES_0402LF-4.7K,1%,1/16W,EMPA':;

SECTION_NUMBER 1
 '@SCM_LIB.SCM(SCH_1):PAGE27_I228@PURE_QUANTA.Q_RES(CHIPS)':
 C_PATH='@scm_lib.scm(sch_1):page27_i228@pure_quanta.q_res(chips)',
 P_PATH='@scm_lib.scm(sch_1):page27_i228@pure_quanta.q_res(chips)',
 PATH='I228',
 DRAWING='@SCM_LIB.SCM(SCH_1):PAGE27',
 PHYS_PAGE='27',
 XY='(-3325,-150)',
 ROT='0',
 VER='2',
 PACK_TYPE='0402LF',
 LOCATION='R140',
 CDS_LIB='pure_quanta',
 CDS_PART_NAME='Q_RES_0402LF-4.7K,1%,1/16W,EMPA',
 WATTAGE='1/16W',
 TOLERANCE='1%',
 MATERIAL='EMPTY',
 VALUE='4.7K',
 PRIM_FILE='W:/<user>/logical/q_res/chips/chips.prt';

PART_NAME
 R142 'Q_RES_0402LF-33.2,1%,1/16W,CHIA':;

SECTION_NUMBER 1
 '@SCM_LIB.SCM(SCH_1):PAGE12_I88@PURE_QUANTA.Q_RES(CHIPS)':
 C_PATH='@scm_lib.scm(sch_1):page12_i88@pure_quanta.q_res(chips)',
 P_PATH='@scm_lib.scm(sch_1):page12_i88@pure_quanta.q_res(chips)',
 PATH='I88',
 DRAWING='@SCM_LIB.SCM(SCH_1):PAGE12',
 PHYS_PAGE='12',
 XY='(4125,1250)',
 ROT='0',
 VER='1',
 PACK_TYPE='0402LF',
 LOCATION='R142',
 CDS_LIB='pure_quanta',
 CDS_PART_NAME='Q_RES_0402LF-33.2,1%,1/16W,CHIA',
 WATTAGE='1/16W',
 TOLERANCE='1%',
 MATERIAL='CHIP',
 VALUE='33.2',
 PRIM_FILE='W:/<user>/logical/q_res/chips/chips.prt';

PART_NAME
 R143 'Q_RES_0402LF-33.2,1%,1/16W,CHIA':;

SECTION_NUMBER 1
 '@SCM_LIB.SCM(SCH_1):PAGE12_I89@PURE_QUANTA.Q_RES(CHIPS)':
 C_PATH='@scm_lib.scm(sch_1):page12_i89@pure_quanta.q_res(chips)',
 P_PATH='@scm_lib.scm(sch_1):page12_i89@pure_quanta.q_res(chips)',
 PATH='I89',
 DRAWING='@SCM_LIB.SCM(SCH_1):PAGE12',
 PHYS_PAGE='12',
 XY='(4125,1200)',
 ROT='0',
 VER='1',
 PACK_TYPE='0402LF',
 LOCATION='R143',
 CDS_LIB='pure_quanta',
 CDS_PART_NAME='Q_RES_0402LF-33.2,1%,1/16W,CHIA',
 WATTAGE='1/16W',
 TOLERANCE='1%',
 MATERIAL='CHIP',
 VALUE='33.2',
 PRIM_FILE='W:/<user>/logical/q_res/chips/chips.prt';

PART_NAME
 R144 'Q_RES_0402LF-33.2,1%,1/16W,CHIA':;

SECTION_NUMBER 1
 '@SCM_LIB.SCM(SCH_1):PAGE12_I386@PURE_QUANTA.Q_RES(CHIPS)':
 C_PATH='@scm_lib.scm(sch_1):page12_i386@pure_quanta.q_res(chips)',
 P_PATH='@scm_lib.scm(sch_1):page12_i386@pure_quanta.q_res(chips)',
 PATH='I386',
 DRAWING='@SCM_LIB.SCM(SCH_1):PAGE12',
 PHYS_PAGE='12',
 XY='(4125,500)',
 ROT='0',
 VER='1',
 PACK_TYPE='0402LF',
 LOCATION='R144',
 CDS_LIB='pure_quanta',
 CDS_PART_NAME='Q_RES_0402LF-33.2,1%,1/16W,CHIA',
 WATTAGE='1/16W',
 TOLERANCE='1%',
 MATERIAL='CHIP',
 VALUE='33.2',
 PRIM_FILE='W:/<user>/logical/q_res/chips/chips.prt';

PART_NAME
 R145 'Q_RES_0402LF-10K,1%,1/16W,CHIPA':;

SECTION_NUMBER 1
 '@SCM_LIB.SCM(SCH_1):PAGE27_I235@PURE_QUANTA.Q_RES(CHIPS)':
 C_PATH='@scm_lib.scm(sch_1):page27_i235@pure_quanta.q_res(chips)',
 P_PATH='@scm_lib.scm(sch_1):page27_i235@pure_quanta.q_res(chips)',
 PATH='I235',
 DRAWING='@SCM_LIB.SCM(SCH_1):PAGE27',
 PHYS_PAGE='27',
 XY='(-3625,2175)',
 ROT='0',
 VER='1',
 PACK_TYPE='0402LF',
 LOCATION='R145',
 CDS_LIB='pure_quanta',
 CDS_PART_NAME='Q_RES_0402LF-10K,1%,1/16W,CHIPA',
 WATTAGE='1/16W',
 TOLERANCE='1%',
 MATERIAL='CHIP',
 VALUE='10K',
 PRIM_FILE='W:/<user>/logical/q_res/chips/chips.prt';

PART_NAME
 R146 'Q_RES_0402LF-33.2,1%,1/16W,CHIA':;

SECTION_NUMBER 1
 '@SCM_LIB.SCM(SCH_1):PAGE12_I235@PURE_QUANTA.Q_RES(CHIPS)':
 C_PATH='@scm_lib.scm(sch_1):page12_i235@pure_quanta.q_res(chips)',
 P_PATH='@scm_lib.scm(sch_1):page12_i235@pure_quanta.q_res(chips)',
 PATH='I235',
 DRAWING='@SCM_LIB.SCM(SCH_1):PAGE12',
 PHYS_PAGE='12',
 XY='(4125,1050)',
 ROT='0',
 VER='1',
 PACK_TYPE='0402LF',
 LOCATION='R146',
 CDS_LIB='pure_quanta',
 CDS_PART_NAME='Q_RES_0402LF-33.2,1%,1/16W,CHIA',
 WATTAGE='1/16W',
 TOLERANCE='1%',
 MATERIAL='CHIP',
 VALUE='33.2',
 PRIM_FILE='W:/<user>/logical/q_res/chips/chips.prt';

PART_NAME
 R147 'Q_RES_0402LF-33.2,1%,1/16W,CHIA':;

SECTION_NUMBER 1
 '@SCM_LIB.SCM(SCH_1):PAGE12_I236@PURE_QUANTA.Q_RES(CHIPS)':
 C_PATH='@scm_lib.scm(sch_1):page12_i236@pure_quanta.q_res(chips)',
 P_PATH='@scm_lib.scm(sch_1):page12_i236@pure_quanta.q_res(chips)',
 PATH='I236',
 DRAWING='@SCM_LIB.SCM(SCH_1):PAGE12',
 PHYS_PAGE='12',
 XY='(4125,1000)',
 ROT='0',
 VER='1',
 PACK_TYPE='0402LF',
 LOCATION='R147',
 CDS_LIB='pure_quanta',
 CDS_PART_NAME='Q_RES_0402LF-33.2,1%,1/16W,CHIA',
 WATTAGE='1/16W',
 TOLERANCE='1%',
 MATERIAL='CHIP',
 VALUE='33.2',
 PRIM_FILE='W:/<user>/logical/q_res/chips/chips.prt';

PART_NAME
 R148 'Q_RES_0402LF-33.2,1%,1/16W,CHIA':;

SECTION_NUMBER 1
 '@SCM_LIB.SCM(SCH_1):PAGE12_I379@PURE_QUANTA.Q_RES(CHIPS)':
 C_PATH='@scm_lib.scm(sch_1):page12_i379@pure_quanta.q_res(chips)',
 P_PATH='@scm_lib.scm(sch_1):page12_i379@pure_quanta.q_res(chips)',
 PATH='I379',
 DRAWING='@SCM_LIB.SCM(SCH_1):PAGE12',
 PHYS_PAGE='12',
 XY='(-650,500)',
 ROT='0',
 VER='1',
 PACK_TYPE='0402LF',
 LOCATION='R148',
 CDS_LIB='pure_quanta',
 CDS_PART_NAME='Q_RES_0402LF-33.2,1%,1/16W,CHIA',
 WATTAGE='1/16W',
 TOLERANCE='1%',
 MATERIAL='CHIP',
 VALUE='33.2',
 PRIM_FILE='W:/<user>/logical/q_res/chips/chips.prt';

PART_NAME
 R149 'Q_RES_0402LF-10K,1%,1/16W,CHIPA':;

SECTION_NUMBER 1
 '@SCM_LIB.SCM(SCH_1):PAGE27_I236@PURE_QUANTA.Q_RES(CHIPS)':
 C_PATH='@scm_lib.scm(sch_1):page27_i236@pure_quanta.q_res(chips)',
 P_PATH='@scm_lib.scm(sch_1):page27_i236@pure_quanta.q_res(chips)',
 PATH='I236',
 DRAWING='@SCM_LIB.SCM(SCH_1):PAGE27',
 PHYS_PAGE='27',
 XY='(-3625,2075)',
 ROT='0',
 VER='1',
 PACK_TYPE='0402LF',
 LOCATION='R149',
 CDS_LIB='pure_quanta',
 CDS_PART_NAME='Q_RES_0402LF-10K,1%,1/16W,CHIPA',
 WATTAGE='1/16W',
 TOLERANCE='1%',
 MATERIAL='CHIP',
 VALUE='10K',
 PRIM_FILE='W:/<user>/logical/q_res/chips/chips.prt';

PART_NAME
 R150 'Q_RES_0402LF-33.2,1%,1/16W,CHIA':;

SECTION_NUMBER 1
 '@SCM_LIB.SCM(SCH_1):PAGE12_I380@PURE_QUANTA.Q_RES(CHIPS)':
 C_PATH='@scm_lib.scm(sch_1):page12_i380@pure_quanta.q_res(chips)',
 P_PATH='@scm_lib.scm(sch_1):page12_i380@pure_quanta.q_res(chips)',
 PATH='I380',
 DRAWING='@SCM_LIB.SCM(SCH_1):PAGE12',
 PHYS_PAGE='12',
 XY='(-650,450)',
 ROT='0',
 VER='1',
 PACK_TYPE='0402LF',
 LOCATION='R150',
 CDS_LIB='pure_quanta',
 CDS_PART_NAME='Q_RES_0402LF-33.2,1%,1/16W,CHIA',
 WATTAGE='1/16W',
 TOLERANCE='1%',
 MATERIAL='CHIP',
 VALUE='33.2',
 PRIM_FILE='W:/<user>/logical/q_res/chips/chips.prt';

PART_NAME
 R151 'Q_RES_0402LF-33.2,1%,1/16W,CHIA':;

SECTION_NUMBER 1
 '@SCM_LIB.SCM(SCH_1):PAGE12_I381@PURE_QUANTA.Q_RES(CHIPS)':
 C_PATH='@scm_lib.scm(sch_1):page12_i381@pure_quanta.q_res(chips)',
 P_PATH='@scm_lib.scm(sch_1):page12_i381@pure_quanta.q_res(chips)',
 PATH='I381',
 DRAWING='@SCM_LIB.SCM(SCH_1):PAGE12',
 PHYS_PAGE='12',
 XY='(-650,400)',
 ROT='0',
 VER='1',
 PACK_TYPE='0402LF',
 LOCATION='R151',
 CDS_LIB='pure_quanta',
 CDS_PART_NAME='Q_RES_0402LF-33.2,1%,1/16W,CHIA',
 WATTAGE='1/16W',
 TOLERANCE='1%',
 MATERIAL='CHIP',
 VALUE='33.2',
 PRIM_FILE='W:/<user>/logical/q_res/chips/chips.prt';

PART_NAME
 R152 'Q_RES_0402LF-33.2,1%,1/16W,CHIA':;

SECTION_NUMBER 1
 '@SCM_LIB.SCM(SCH_1):PAGE12_I249@PURE_QUANTA.Q_RES(CHIPS)':
 C_PATH='@scm_lib.scm(sch_1):page12_i249@pure_quanta.q_res(chips)',
 P_PATH='@scm_lib.scm(sch_1):page12_i249@pure_quanta.q_res(chips)',
 PATH='I249',
 DRAWING='@SCM_LIB.SCM(SCH_1):PAGE12',
 PHYS_PAGE='12',
 XY='(-650,200)',
 ROT='0',
 VER='1',
 PACK_TYPE='0402LF',
 LOCATION='R152',
 CDS_LIB='pure_quanta',
 CDS_PART_NAME='Q_RES_0402LF-33.2,1%,1/16W,CHIA',
 WATTAGE='1/16W',
 TOLERANCE='1%',
 MATERIAL='CHIP',
 VALUE='33.2',
 PRIM_FILE='W:/<user>/logical/q_res/chips/chips.prt';

PART_NAME
 R153 'Q_RES_0402LF-33.2,1%,1/16W,CHIA':;

SECTION_NUMBER 1
 '@SCM_LIB.SCM(SCH_1):PAGE12_I248@PURE_QUANTA.Q_RES(CHIPS)':
 C_PATH='@scm_lib.scm(sch_1):page12_i248@pure_quanta.q_res(chips)',
 P_PATH='@scm_lib.scm(sch_1):page12_i248@pure_quanta.q_res(chips)',
 PATH='I248',
 DRAWING='@SCM_LIB.SCM(SCH_1):PAGE12',
 PHYS_PAGE='12',
 XY='(-650,150)',
 ROT='0',
 VER='1',
 PACK_TYPE='0402LF',
 LOCATION='R153',
 CDS_LIB='pure_quanta',
 CDS_PART_NAME='Q_RES_0402LF-33.2,1%,1/16W,CHIA',
 WATTAGE='1/16W',
 TOLERANCE='1%',
 MATERIAL='CHIP',
 VALUE='33.2',
 PRIM_FILE='W:/<user>/logical/q_res/chips/chips.prt';

PART_NAME
 R154 'Q_RES_0402LF-0,5%,1/16W,EMPTY,A':;

SECTION_NUMBER 1
 '@SCM_LIB.SCM(SCH_1):PAGE13_I3@PURE_QUANTA.Q_RES(CHIPS)':
 C_PATH='@scm_lib.scm(sch_1):page13_i3@pure_quanta.q_res(chips)',
 P_PATH='@scm_lib.scm(sch_1):page13_i3@pure_quanta.q_res(chips)',
 PATH='I3',
 DRAWING='@SCM_LIB.SCM(SCH_1):PAGE13',
 PHYS_PAGE='13',
 XY='(-2875,-650)',
 ROT='0',
 VER='1',
 PACK_TYPE='0402LF',
 LOCATION='R154',
 CDS_LIB='pure_quanta',
 CDS_PART_NAME='Q_RES_0402LF-0,5%,1/16W,EMPTY,A',
 WATTAGE='1/16W',
 TOLERANCE='5%',
 MATERIAL='EMPTY',
 VALUE='0',
 PRIM_FILE='W:/<user>/logical/q_res/chips/chips.prt';

PART_NAME
 R155 'Q_RES_0402LF-0,5%,1/16W,CHIP,CA':;

SECTION_NUMBER 1
 '@SCM_LIB.SCM(SCH_1):PAGE13_I5@PURE_QUANTA.Q_RES(CHIPS)':
 C_PATH='@scm_lib.scm(sch_1):page13_i5@pure_quanta.q_res(chips)',
 P_PATH='@scm_lib.scm(sch_1):page13_i5@pure_quanta.q_res(chips)',
 PATH='I5',
 DRAWING='@SCM_LIB.SCM(SCH_1):PAGE13',
 PHYS_PAGE='13',
 XY='(-2800,0)',
 ROT='0',
 VER='1',
 PACK_TYPE='0402LF',
 LOCATION='R155',
 CDS_LIB='pure_quanta',
 CDS_PART_NAME='Q_RES_0402LF-0,5%,1/16W,CHIP,CA',
 WATTAGE='1/16W',
 TOLERANCE='5%',
 MATERIAL='CHIP',
 VALUE='0',
 PRIM_FILE='W:/<user>/logical/q_res/chips/chips.prt';

PART_NAME
 R156 'Q_RES_0402LF-0,5%,1/16W,EMPTY,A':;

SECTION_NUMBER 1
 '@SCM_LIB.SCM(SCH_1):PAGE13_I4@PURE_QUANTA.Q_RES(CHIPS)':
 C_PATH='@scm_lib.scm(sch_1):page13_i4@pure_quanta.q_res(chips)',
 P_PATH='@scm_lib.scm(sch_1):page13_i4@pure_quanta.q_res(chips)',
 PATH='I4',
 DRAWING='@SCM_LIB.SCM(SCH_1):PAGE13',
 PHYS_PAGE='13',
 XY='(-2800,-300)',
 ROT='0',
 VER='1',
 PACK_TYPE='0402LF',
 LOCATION='R156',
 CDS_LIB='pure_quanta',
 CDS_PART_NAME='Q_RES_0402LF-0,5%,1/16W,EMPTY,A',
 WATTAGE='1/16W',
 TOLERANCE='5%',
 MATERIAL='EMPTY',
 VALUE='0',
 PRIM_FILE='W:/<user>/logical/q_res/chips/chips.prt';

PART_NAME
 R157 'Q_RES_0402LF-33.2,1%,1/16W,CHIA':;

SECTION_NUMBER 1
 '@SCM_LIB.SCM(SCH_1):PAGE13_I18@PURE_QUANTA.Q_RES(CHIPS)':
 C_PATH='@scm_lib.scm(sch_1):page13_i18@pure_quanta.q_res(chips)',
 P_PATH='@scm_lib.scm(sch_1):page13_i18@pure_quanta.q_res(chips)',
 PATH='I18',
 DRAWING='@SCM_LIB.SCM(SCH_1):PAGE13',
 PHYS_PAGE='13',
 XY='(-2125,2175)',
 ROT='0',
 VER='1',
 PACK_TYPE='0402LF',
 LOCATION='R157',
 CDS_LIB='pure_quanta',
 CDS_PART_NAME='Q_RES_0402LF-33.2,1%,1/16W,CHIA',
 WATTAGE='1/16W',
 TOLERANCE='1%',
 MATERIAL='CHIP',
 VALUE='33.2',
 PRIM_FILE='W:/<user>/logical/q_res/chips/chips.prt';

PART_NAME
 R158 'Q_RES_0402LF-33.2,1%,1/16W,CHIA':;

SECTION_NUMBER 1
 '@SCM_LIB.SCM(SCH_1):PAGE13_I16@PURE_QUANTA.Q_RES(CHIPS)':
 C_PATH='@scm_lib.scm(sch_1):page13_i16@pure_quanta.q_res(chips)',
 P_PATH='@scm_lib.scm(sch_1):page13_i16@pure_quanta.q_res(chips)',
 PATH='I16',
 DRAWING='@SCM_LIB.SCM(SCH_1):PAGE13',
 PHYS_PAGE='13',
 XY='(-2125,2025)',
 ROT='0',
 VER='1',
 PACK_TYPE='0402LF',
 LOCATION='R158',
 CDS_LIB='pure_quanta',
 CDS_PART_NAME='Q_RES_0402LF-33.2,1%,1/16W,CHIA',
 WATTAGE='1/16W',
 TOLERANCE='1%',
 MATERIAL='CHIP',
 VALUE='33.2',
 PRIM_FILE='W:/<user>/logical/q_res/chips/chips.prt';

PART_NAME
 R159 'Q_RES_0402LF-33.2,1%,1/16W,CHIA':;

SECTION_NUMBER 1
 '@SCM_LIB.SCM(SCH_1):PAGE13_I17@PURE_QUANTA.Q_RES(CHIPS)':
 C_PATH='@scm_lib.scm(sch_1):page13_i17@pure_quanta.q_res(chips)',
 P_PATH='@scm_lib.scm(sch_1):page13_i17@pure_quanta.q_res(chips)',
 PATH='I17',
 DRAWING='@SCM_LIB.SCM(SCH_1):PAGE13',
 PHYS_PAGE='13',
 XY='(-2125,1975)',
 ROT='0',
 VER='1',
 PACK_TYPE='0402LF',
 LOCATION='R159',
 CDS_LIB='pure_quanta',
 CDS_PART_NAME='Q_RES_0402LF-33.2,1%,1/16W,CHIA',
 WATTAGE='1/16W',
 TOLERANCE='1%',
 MATERIAL='CHIP',
 VALUE='33.2',
 PRIM_FILE='W:/<user>/logical/q_res/chips/chips.prt';

PART_NAME
 R160 'Q_RES_0402LF-33.2,1%,1/16W,CHIA':;

SECTION_NUMBER 1
 '@SCM_LIB.SCM(SCH_1):PAGE13_I159@PURE_QUANTA.Q_RES(CHIPS)':
 C_PATH='@scm_lib.scm(sch_1):page13_i159@pure_quanta.q_res(chips)',
 P_PATH='@scm_lib.scm(sch_1):page13_i159@pure_quanta.q_res(chips)',
 PATH='I159',
 DRAWING='@SCM_LIB.SCM(SCH_1):PAGE13',
 PHYS_PAGE='13',
 XY='(-1775,2825)',
 ROT='0',
 VER='1',
 PACK_TYPE='0402LF',
 LOCATION='R160',
 CDS_LIB='pure_quanta',
 CDS_PART_NAME='Q_RES_0402LF-33.2,1%,1/16W,CHIA',
 WATTAGE='1/16W',
 TOLERANCE='1%',
 MATERIAL='CHIP',
 VALUE='33.2',
 PRIM_FILE='W:/<user>/logical/q_res/chips/chips.prt';

PART_NAME
 R161 'Q_RES_0402LF-4.7K,1%,1/16W,CHIA':;

SECTION_NUMBER 1
 '@SCM_LIB.SCM(SCH_1):PAGE11_I218@PURE_QUANTA.Q_RES(CHIPS)':
 C_PATH='@scm_lib.scm(sch_1):page11_i218@pure_quanta.q_res(chips)',
 P_PATH='@scm_lib.scm(sch_1):page11_i218@pure_quanta.q_res(chips)',
 PATH='I218',
 DRAWING='@SCM_LIB.SCM(SCH_1):PAGE11',
 PHYS_PAGE='11',
 XY='(-3325,5025)',
 ROT='0',
 VER='1',
 PACK_TYPE='0402LF',
 LOCATION='R161',
 CDS_LIB='pure_quanta',
 CDS_PART_NAME='Q_RES_0402LF-4.7K,1%,1/16W,CHIA',
 WATTAGE='1/16W',
 TOLERANCE='1%',
 MATERIAL='CHIP',
 VALUE='4.7K',
 PRIM_FILE='W:/<user>/logical/q_res/chips/chips.prt';

PART_NAME
 R162 'Q_RES_0402LF-33.2,1%,1/16W,CHIA':;

SECTION_NUMBER 1
 '@SCM_LIB.SCM(SCH_1):PAGE12_I245@PURE_QUANTA.Q_RES(CHIPS)':
 C_PATH='@scm_lib.scm(sch_1):page12_i245@pure_quanta.q_res(chips)',
 P_PATH='@scm_lib.scm(sch_1):page12_i245@pure_quanta.q_res(chips)',
 PATH='I245',
 DRAWING='@SCM_LIB.SCM(SCH_1):PAGE12',
 PHYS_PAGE='12',
 XY='(-650,300)',
 ROT='0',
 VER='1',
 PACK_TYPE='0402LF',
 LOCATION='R162',
 CDS_LIB='pure_quanta',
 CDS_PART_NAME='Q_RES_0402LF-33.2,1%,1/16W,CHIA',
 WATTAGE='1/16W',
 TOLERANCE='1%',
 MATERIAL='CHIP',
 VALUE='33.2',
 PRIM_FILE='W:/<user>/logical/q_res/chips/chips.prt';

PART_NAME
 R163 'Q_RES_0402LF-4.7K,1%,1/16W,CHIA':;

SECTION_NUMBER 1
 '@SCM_LIB.SCM(SCH_1):PAGE11_I212@PURE_QUANTA.Q_RES(CHIPS)':
 C_PATH='@scm_lib.scm(sch_1):page11_i212@pure_quanta.q_res(chips)',
 P_PATH='@scm_lib.scm(sch_1):page11_i212@pure_quanta.q_res(chips)',
 PATH='I212',
 DRAWING='@SCM_LIB.SCM(SCH_1):PAGE11',
 PHYS_PAGE='11',
 XY='(-3325,5625)',
 ROT='0',
 VER='1',
 PACK_TYPE='0402LF',
 LOCATION='R163',
 CDS_LIB='pure_quanta',
 CDS_PART_NAME='Q_RES_0402LF-4.7K,1%,1/16W,CHIA',
 WATTAGE='1/16W',
 TOLERANCE='1%',
 MATERIAL='CHIP',
 VALUE='4.7K',
 PRIM_FILE='W:/<user>/logical/q_res/chips/chips.prt';

PART_NAME
 R164 'Q_RES_0402LF-100,1%,1/16W,EMPTA':;

SECTION_NUMBER 1
 '@SCM_LIB.SCM(SCH_1):PAGE27_I244@PURE_QUANTA.Q_RES(CHIPS)':
 C_PATH='@scm_lib.scm(sch_1):page27_i244@pure_quanta.q_res(chips)',
 P_PATH='@scm_lib.scm(sch_1):page27_i244@pure_quanta.q_res(chips)',
 PATH='I244',
 DRAWING='@SCM_LIB.SCM(SCH_1):PAGE27',
 PHYS_PAGE='27',
 XY='(-2825,-1000)',
 ROT='0',
 VER='2',
 PACK_TYPE='0402LF',
 CDS_LIB='pure_quanta',
 CDS_PART_NAME='Q_RES_0402LF-100,1%,1/16W,EMPTA',
 WATTAGE='1/16W',
 TOLERANCE='1%',
 MATERIAL='EMPTY',
 VALUE='100',
 PRIM_FILE='W:/<user>/logical/q_res/chips/chips.prt';

PART_NAME
 R165 'Q_RES_0402LF-33.2,1%,1/16W,CHIA':;

SECTION_NUMBER 1
 '@SCM_LIB.SCM(SCH_1):PAGE12_I315@PURE_QUANTA.Q_RES(CHIPS)':
 C_PATH='@scm_lib.scm(sch_1):page12_i315@pure_quanta.q_res(chips)',
 P_PATH='@scm_lib.scm(sch_1):page12_i315@pure_quanta.q_res(chips)',
 PATH='I315',
 DRAWING='@SCM_LIB.SCM(SCH_1):PAGE12',
 PHYS_PAGE='12',
 XY='(4125,1750)',
 ROT='0',
 VER='1',
 PACK_TYPE='0402LF',
 LOCATION='R165',
 CDS_LIB='pure_quanta',
 CDS_PART_NAME='Q_RES_0402LF-33.2,1%,1/16W,CHIA',
 WATTAGE='1/16W',
 TOLERANCE='1%',
 MATERIAL='CHIP',
 VALUE='33.2',
 PRIM_FILE='W:/<user>/logical/q_res/chips/chips.prt';

PART_NAME
 R166 'Q_RES_0402LF-33.2,1%,1/16W,CHIA':;

SECTION_NUMBER 1
 '@SCM_LIB.SCM(SCH_1):PAGE13_I50@PURE_QUANTA.Q_RES(CHIPS)':
 C_PATH='@scm_lib.scm(sch_1):page13_i50@pure_quanta.q_res(chips)',
 P_PATH='@scm_lib.scm(sch_1):page13_i50@pure_quanta.q_res(chips)',
 PATH='I50',
 DRAWING='@SCM_LIB.SCM(SCH_1):PAGE13',
 PHYS_PAGE='13',
 XY='(-1750,3025)',
 ROT='0',
 VER='1',
 PACK_TYPE='0402LF',
 LOCATION='R166',
 CDS_LIB='pure_quanta',
 CDS_PART_NAME='Q_RES_0402LF-33.2,1%,1/16W,CHIA',
 WATTAGE='1/16W',
 TOLERANCE='1%',
 MATERIAL='CHIP',
 VALUE='33.2',
 PRIM_FILE='W:/<user>/logical/q_res/chips/chips.prt';

PART_NAME
 R167 'Q_RES_0402LF-330,1%,1/16W,CHIPA':;

SECTION_NUMBER 1
 '@SCM_LIB.SCM(SCH_1):PAGE13_I33@PURE_QUANTA.Q_RES(CHIPS)':
 C_PATH='@scm_lib.scm(sch_1):page13_i33@pure_quanta.q_res(chips)',
 P_PATH='@scm_lib.scm(sch_1):page13_i33@pure_quanta.q_res(chips)',
 PATH='I33',
 DRAWING='@SCM_LIB.SCM(SCH_1):PAGE13',
 PHYS_PAGE='13',
 XY='(-325,-525)',
 ROT='0',
 VER='1',
 PACK_TYPE='0402LF',
 LOCATION='R167',
 CDS_LIB='pure_quanta',
 CDS_PART_NAME='Q_RES_0402LF-330,1%,1/16W,CHIPA',
 WATTAGE='1/16W',
 TOLERANCE='1%',
 MATERIAL='CHIP',
 VALUE='330',
 PRIM_FILE='W:/<user>/logical/q_res/chips/chips.prt';

PART_NAME
 R168 'Q_RES_0402LF-33.2,1%,1/16W,CHIA':;

SECTION_NUMBER 1
 '@SCM_LIB.SCM(SCH_1):PAGE12_I268@PURE_QUANTA.Q_RES(CHIPS)':
 C_PATH='@scm_lib.scm(sch_1):page12_i268@pure_quanta.q_res(chips)',
 P_PATH='@scm_lib.scm(sch_1):page12_i268@pure_quanta.q_res(chips)',
 PATH='I268',
 DRAWING='@SCM_LIB.SCM(SCH_1):PAGE12',
 PHYS_PAGE='12',
 XY='(-775,-1150)',
 ROT='0',
 VER='1',
 PACK_TYPE='0402LF',
 LOCATION='R168',
 CDS_LIB='pure_quanta',
 CDS_PART_NAME='Q_RES_0402LF-33.2,1%,1/16W,CHIA',
 WATTAGE='1/16W',
 TOLERANCE='1%',
 MATERIAL='CHIP',
 VALUE='33.2',
 PRIM_FILE='W:/<user>/logical/q_res/chips/chips.prt';

PART_NAME
 R169 'Q_RES_0402LF-4.7K,1%,1/16W,CHIA':;

SECTION_NUMBER 1
 '@SCM_LIB.SCM(SCH_1):PAGE11_I256@PURE_QUANTA.Q_RES(CHIPS)':
 C_PATH='@scm_lib.scm(sch_1):page11_i256@pure_quanta.q_res(chips)',
 P_PATH='@scm_lib.scm(sch_1):page11_i256@pure_quanta.q_res(chips)',
 PATH='I256',
 DRAWING='@SCM_LIB.SCM(SCH_1):PAGE11',
 PHYS_PAGE='11',
 XY='(-3325,2525)',
 ROT='0',
 VER='1',
 PACK_TYPE='0402LF',
 LOCATION='R169',
 CDS_LIB='pure_quanta',
 CDS_PART_NAME='Q_RES_0402LF-4.7K,1%,1/16W,CHIA',
 WATTAGE='1/16W',
 TOLERANCE='1%',
 MATERIAL='CHIP',
 VALUE='4.7K',
 PRIM_FILE='W:/<user>/logical/q_res/chips/chips.prt';

PART_NAME
 R170 'Q_RES_0402LF-33.2,1%,1/16W,CHIA':;

SECTION_NUMBER 1
 '@SCM_LIB.SCM(SCH_1):PAGE13_I67@PURE_QUANTA.Q_RES(CHIPS)':
 C_PATH='@scm_lib.scm(sch_1):page13_i67@pure_quanta.q_res(chips)',
 P_PATH='@scm_lib.scm(sch_1):page13_i67@pure_quanta.q_res(chips)',
 PATH='I67',
 DRAWING='@SCM_LIB.SCM(SCH_1):PAGE13',
 PHYS_PAGE='13',
 XY='(2875,2025)',
 ROT='0',
 VER='1',
 PACK_TYPE='0402LF',
 LOCATION='R170',
 CDS_LIB='pure_quanta',
 CDS_PART_NAME='Q_RES_0402LF-33.2,1%,1/16W,CHIA',
 WATTAGE='1/16W',
 TOLERANCE='1%',
 MATERIAL='CHIP',
 VALUE='33.2',
 PRIM_FILE='W:/<user>/logical/q_res/chips/chips.prt';

PART_NAME
 R171 'Q_RES_0402LF-22,1%,1/16W,CHIP,A':;

SECTION_NUMBER 1
 '@SCM_LIB.SCM(SCH_1):PAGE13_I451@PURE_QUANTA.Q_RES(CHIPS)':
 C_PATH='@scm_lib.scm(sch_1):page13_i451@pure_quanta.q_res(chips)',
 P_PATH='@scm_lib.scm(sch_1):page13_i451@pure_quanta.q_res(chips)',
 PATH='I451',
 DRAWING='@SCM_LIB.SCM(SCH_1):PAGE13',
 PHYS_PAGE='13',
 XY='(3150,1775)',
 ROT='0',
 VER='1',
 PACK_TYPE='0402LF',
 LOCATION='R171',
 CDS_LIB='pure_quanta',
 CDS_PART_NAME='Q_RES_0402LF-22,1%,1/16W,CHIP,A',
 WATTAGE='1/16W',
 TOLERANCE='1%',
 MATERIAL='CHIP',
 VALUE='22',
 PRIM_FILE='W:/<user>/logical/q_res/chips/chips.prt';

PART_NAME
 R172 'Q_RES_0402LF-22,1%,1/16W,CHIP,A':;

SECTION_NUMBER 1
 '@SCM_LIB.SCM(SCH_1):PAGE13_I452@PURE_QUANTA.Q_RES(CHIPS)':
 C_PATH='@scm_lib.scm(sch_1):page13_i452@pure_quanta.q_res(chips)',
 P_PATH='@scm_lib.scm(sch_1):page13_i452@pure_quanta.q_res(chips)',
 PATH='I452',
 DRAWING='@SCM_LIB.SCM(SCH_1):PAGE13',
 PHYS_PAGE='13',
 XY='(3150,1725)',
 ROT='0',
 VER='1',
 PACK_TYPE='0402LF',
 LOCATION='R172',
 CDS_LIB='pure_quanta',
 CDS_PART_NAME='Q_RES_0402LF-22,1%,1/16W,CHIP,A',
 WATTAGE='1/16W',
 TOLERANCE='1%',
 MATERIAL='CHIP',
 VALUE='22',
 PRIM_FILE='W:/<user>/logical/q_res/chips/chips.prt';

PART_NAME
 R173 'Q_RES_0402LF-22,1%,1/16W,CHIP,A':;

SECTION_NUMBER 1
 '@SCM_LIB.SCM(SCH_1):PAGE13_I453@PURE_QUANTA.Q_RES(CHIPS)':
 C_PATH='@scm_lib.scm(sch_1):page13_i453@pure_quanta.q_res(chips)',
 P_PATH='@scm_lib.scm(sch_1):page13_i453@pure_quanta.q_res(chips)',
 PATH='I453',
 DRAWING='@SCM_LIB.SCM(SCH_1):PAGE13',
 PHYS_PAGE='13',
 XY='(3150,1675)',
 ROT='0',
 VER='1',
 PACK_TYPE='0402LF',
 LOCATION='R173',
 CDS_LIB='pure_quanta',
 CDS_PART_NAME='Q_RES_0402LF-22,1%,1/16W,CHIP,A',
 WATTAGE='1/16W',
 TOLERANCE='1%',
 MATERIAL='CHIP',
 VALUE='22',
 PRIM_FILE='W:/<user>/logical/q_res/chips/chips.prt';

PART_NAME
 R174 'Q_RES_0402LF-33.2,1%,1/16W,CHIA':;

SECTION_NUMBER 1
 '@SCM_LIB.SCM(SCH_1):PAGE44_I331@PURE_QUANTA.Q_RES(CHIPS)':
 C_PATH='@scm_lib.scm(sch_1):page44_i331@pure_quanta.q_res(chips)',
 P_PATH='@scm_lib.scm(sch_1):page44_i331@pure_quanta.q_res(chips)',
 PATH='I331',
 DRAWING='@SCM_LIB.SCM(SCH_1):PAGE44',
 PHYS_PAGE='44',
 XY='(-2625,2675)',
 ROT='0',
 VER='1',
 PACK_TYPE='0402LF',
 LOCATION='R174',
 CDS_LIB='pure_quanta',
 CDS_PART_NAME='Q_RES_0402LF-33.2,1%,1/16W,CHIA',
 WATTAGE='1/16W',
 TOLERANCE='1%',
 MATERIAL='CHIP',
 VALUE='33.2',
 PRIM_FILE='W:/<user>/logical/q_res/chips/chips.prt';

PART_NAME
 R175 'Q_RES_0402LF-33.2,1%,1/16W,CHIA':;

SECTION_NUMBER 1
 '@SCM_LIB.SCM(SCH_1):PAGE44_I330@PURE_QUANTA.Q_RES(CHIPS)':
 C_PATH='@scm_lib.scm(sch_1):page44_i330@pure_quanta.q_res(chips)',
 P_PATH='@scm_lib.scm(sch_1):page44_i330@pure_quanta.q_res(chips)',
 PATH='I330',
 DRAWING='@SCM_LIB.SCM(SCH_1):PAGE44',
 PHYS_PAGE='44',
 XY='(-2625,2625)',
 ROT='0',
 VER='1',
 PACK_TYPE='0402LF',
 LOCATION='R175',
 CDS_LIB='pure_quanta',
 CDS_PART_NAME='Q_RES_0402LF-33.2,1%,1/16W,CHIA',
 WATTAGE='1/16W',
 TOLERANCE='1%',
 MATERIAL='CHIP',
 VALUE='33.2',
 PRIM_FILE='W:/<user>/logical/q_res/chips/chips.prt';

PART_NAME
 R176 'Q_RES_0402LF-33.2,1%,1/16W,CHIA':;

SECTION_NUMBER 1
 '@SCM_LIB.SCM(SCH_1):PAGE44_I332@PURE_QUANTA.Q_RES(CHIPS)':
 C_PATH='@scm_lib.scm(sch_1):page44_i332@pure_quanta.q_res(chips)',
 P_PATH='@scm_lib.scm(sch_1):page44_i332@pure_quanta.q_res(chips)',
 PATH='I332',
 DRAWING='@SCM_LIB.SCM(SCH_1):PAGE44',
 PHYS_PAGE='44',
 XY='(-2625,2575)',
 ROT='0',
 VER='1',
 PACK_TYPE='0402LF',
 LOCATION='R176',
 CDS_LIB='pure_quanta',
 CDS_PART_NAME='Q_RES_0402LF-33.2,1%,1/16W,CHIA',
 WATTAGE='1/16W',
 TOLERANCE='1%',
 MATERIAL='CHIP',
 VALUE='33.2',
 PRIM_FILE='W:/<user>/logical/q_res/chips/chips.prt';

PART_NAME
 R177 'Q_RES_0402LF-33.2,1%,1/16W,CHIA':;

SECTION_NUMBER 1
 '@SCM_LIB.SCM(SCH_1):PAGE13_I87@PURE_QUANTA.Q_RES(CHIPS)':
 C_PATH='@scm_lib.scm(sch_1):page13_i87@pure_quanta.q_res(chips)',
 P_PATH='@scm_lib.scm(sch_1):page13_i87@pure_quanta.q_res(chips)',
 PATH='I87',
 DRAWING='@SCM_LIB.SCM(SCH_1):PAGE13',
 SEC_TYPE='0402LF',
 PHYS_PAGE='13',
 XY='(3650,3325)',
 ROT='0',
 VER='1',
 PACK_TYPE='0402LF',
 LOCATION='R177',
 SEC='1',
 CDS_LIB='pure_quanta',
 CDS_PART_NAME='Q_RES_0402LF-33.2,1%,1/16W,CHIA',
 WATTAGE='1/16W',
 TOLERANCE='1%',
 MATERIAL='CHIP',
 VALUE='33.2',
 PRIM_FILE='W:/<user>/logical/q_res/chips/chips.prt';

PART_NAME
 R178 'Q_RES_0402LF-33.2,1%,1/16W,CHIA':;

SECTION_NUMBER 1
 '@SCM_LIB.SCM(SCH_1):PAGE13_I94@PURE_QUANTA.Q_RES(CHIPS)':
 C_PATH='@scm_lib.scm(sch_1):page13_i94@pure_quanta.q_res(chips)',
 P_PATH='@scm_lib.scm(sch_1):page13_i94@pure_quanta.q_res(chips)',
 PATH='I94',
 DRAWING='@SCM_LIB.SCM(SCH_1):PAGE13',
 PHYS_PAGE='13',
 XY='(3350,4325)',
 ROT='0',
 VER='1',
 PACK_TYPE='0402LF',
 LOCATION='R178',
 CDS_LIB='pure_quanta',
 CDS_PART_NAME='Q_RES_0402LF-33.2,1%,1/16W,CHIA',
 WATTAGE='1/16W',
 TOLERANCE='1%',
 MATERIAL='CHIP',
 VALUE='33.2',
 PRIM_FILE='W:/<user>/logical/q_res/chips/chips.prt';

PART_NAME
 R179 'Q_RES_0402LF-33.2,1%,1/16W,CHIA':;

SECTION_NUMBER 1
 '@SCM_LIB.SCM(SCH_1):PAGE13_I95@PURE_QUANTA.Q_RES(CHIPS)':
 C_PATH='@scm_lib.scm(sch_1):page13_i95@pure_quanta.q_res(chips)',
 P_PATH='@scm_lib.scm(sch_1):page13_i95@pure_quanta.q_res(chips)',
 PATH='I95',
 DRAWING='@SCM_LIB.SCM(SCH_1):PAGE13',
 PHYS_PAGE='13',
 XY='(3350,4275)',
 ROT='0',
 VER='1',
 PACK_TYPE='0402LF',
 LOCATION='R179',
 CDS_LIB='pure_quanta',
 CDS_PART_NAME='Q_RES_0402LF-33.2,1%,1/16W,CHIA',
 WATTAGE='1/16W',
 TOLERANCE='1%',
 MATERIAL='CHIP',
 VALUE='33.2',
 PRIM_FILE='W:/<user>/logical/q_res/chips/chips.prt';

PART_NAME
 R180 'Q_RES_0402LF-33.2,1%,1/16W,CHIA':;

SECTION_NUMBER 1
 '@SCM_LIB.SCM(SCH_1):PAGE13_I96@PURE_QUANTA.Q_RES(CHIPS)':
 C_PATH='@scm_lib.scm(sch_1):page13_i96@pure_quanta.q_res(chips)',
 P_PATH='@scm_lib.scm(sch_1):page13_i96@pure_quanta.q_res(chips)',
 PATH='I96',
 DRAWING='@SCM_LIB.SCM(SCH_1):PAGE13',
 PHYS_PAGE='13',
 XY='(3350,4225)',
 ROT='0',
 VER='1',
 PACK_TYPE='0402LF',
 LOCATION='R180',
 CDS_LIB='pure_quanta',
 CDS_PART_NAME='Q_RES_0402LF-33.2,1%,1/16W,CHIA',
 WATTAGE='1/16W',
 TOLERANCE='1%',
 MATERIAL='CHIP',
 VALUE='33.2',
 PRIM_FILE='W:/<user>/logical/q_res/chips/chips.prt';

PART_NAME
 R181 'Q_RES_0402LF-4.7K,1%,1/16W,CHIA':;

SECTION_NUMBER 1
 '@SCM_LIB.SCM(SCH_1):PAGE25_I170@PURE_QUANTA.Q_RES(CHIPS)':
 C_PATH='@scm_lib.scm(sch_1):page25_i170@pure_quanta.q_res(chips)',
 P_PATH='@scm_lib.scm(sch_1):page25_i170@pure_quanta.q_res(chips)',
 PATH='I170',
 DRAWING='@SCM_LIB.SCM(SCH_1):PAGE25',
 PHYS_PAGE='25',
 XY='(350,3900)',
 ROT='0',
 VER='2',
 PACK_TYPE='0402LF',
 LOCATION='R181',
 CDS_LIB='pure_quanta',
 CDS_PART_NAME='Q_RES_0402LF-4.7K,1%,1/16W,CHIA',
 WATTAGE='1/16W',
 TOLERANCE='1%',
 MATERIAL='CHIP',
 VALUE='4.7K',
 PRIM_FILE='W:/<user>/logical/q_res/chips/chips.prt';

PART_NAME
 R182 'Q_RES_0402LF-0,5%,1/16W,CHIP,CA':;

SECTION_NUMBER 1
 '@SCM_LIB.SCM(SCH_1):PAGE25_I142@PURE_QUANTA.Q_RES(CHIPS)':
 C_PATH='@scm_lib.scm(sch_1):page25_i142@pure_quanta.q_res(chips)',
 P_PATH='@scm_lib.scm(sch_1):page25_i142@pure_quanta.q_res(chips)',
 PATH='I142',
 DRAWING='@SCM_LIB.SCM(SCH_1):PAGE25',
 PHYS_PAGE='25',
 XY='(2000,3600)',
 ROT='0',
 VER='1',
 PACK_TYPE='0402LF',
 CDS_LIB='pure_quanta',
 CDS_PART_NAME='Q_RES_0402LF-0,5%,1/16W,CHIP,CA',
 WATTAGE='1/16W',
 TOLERANCE='5%',
 MATERIAL='CHIP',
 VALUE='0',
 PRIM_FILE='W:/<user>/logical/q_res/chips/chips.prt';

PART_NAME
 R183 'Q_RES_0402LF-0,5%,1/16W,CHIP,CA':;

SECTION_NUMBER 1
 '@SCM_LIB.SCM(SCH_1):PAGE34_I139@PURE_QUANTA.Q_RES(CHIPS)':
 C_PATH='@scm_lib.scm(sch_1):page34_i139@pure_quanta.q_res(chips)',
 P_PATH='@scm_lib.scm(sch_1):page34_i139@pure_quanta.q_res(chips)',
 PATH='I139',
 DRAWING='@SCM_LIB.SCM(SCH_1):PAGE34',
 PHYS_PAGE='34',
 XY='(-8200,1850)',
 ROT='0',
 VER='1',
 PACK_TYPE='0402LF',
 CDS_LIB='pure_quanta',
 CDS_PART_NAME='Q_RES_0402LF-0,5%,1/16W,CHIP,CA',
 WATTAGE='1/16W',
 TOLERANCE='5%',
 MATERIAL='CHIP',
 VALUE='0',
 PRIM_FILE='W:/<user>/logical/q_res/chips/chips.prt';

PART_NAME
 R184 'Q_RES_0402LF-110,1%,1/16W,CHIPA':;

SECTION_NUMBER 1
 '@SCM_LIB.SCM(SCH_1):PAGE14_I232@PURE_QUANTA.Q_RES(CHIPS)':
 C_PATH='@scm_lib.scm(sch_1):page14_i232@pure_quanta.q_res(chips)',
 P_PATH='@scm_lib.scm(sch_1):page14_i232@pure_quanta.q_res(chips)',
 PATH='I232',
 DRAWING='@SCM_LIB.SCM(SCH_1):PAGE14',
 PHYS_PAGE='14',
 XY='(-2150,3425)',
 ROT='0',
 VER='1',
 PACK_TYPE='0402LF',
 LOCATION='R184',
 CDS_LIB='pure_quanta',
 CDS_PART_NAME='Q_RES_0402LF-110,1%,1/16W,CHIPA',
 WATTAGE='1/16W',
 TOLERANCE='1%',
 MATERIAL='CHIP',
 VALUE='110',
 PRIM_FILE='W:/<user>/logical/q_res/chips/chips.prt';

PART_NAME
 R185 'Q_RES_0402LF-33.2,1%,1/16W,CHIA':;

SECTION_NUMBER 1
 '@SCM_LIB.SCM(SCH_1):PAGE14_I236@PURE_QUANTA.Q_RES(CHIPS)':
 C_PATH='@scm_lib.scm(sch_1):page14_i236@pure_quanta.q_res(chips)',
 P_PATH='@scm_lib.scm(sch_1):page14_i236@pure_quanta.q_res(chips)',
 PATH='I236',
 DRAWING='@SCM_LIB.SCM(SCH_1):PAGE14',
 PHYS_PAGE='14',
 XY='(-2150,3375)',
 ROT='0',
 VER='1',
 PACK_TYPE='0402LF',
 LOCATION='R185',
 CDS_LIB='pure_quanta',
 CDS_PART_NAME='Q_RES_0402LF-33.2,1%,1/16W,CHIA',
 WATTAGE='1/16W',
 TOLERANCE='1%',
 MATERIAL='CHIP',
 VALUE='33.2',
 PRIM_FILE='W:/<user>/logical/q_res/chips/chips.prt';

PART_NAME
 R186 'Q_RES_0402LF-110,1%,1/16W,CHIPA':;

SECTION_NUMBER 1
 '@SCM_LIB.SCM(SCH_1):PAGE14_I233@PURE_QUANTA.Q_RES(CHIPS)':
 C_PATH='@scm_lib.scm(sch_1):page14_i233@pure_quanta.q_res(chips)',
 P_PATH='@scm_lib.scm(sch_1):page14_i233@pure_quanta.q_res(chips)',
 PATH='I233',
 DRAWING='@SCM_LIB.SCM(SCH_1):PAGE14',
 PHYS_PAGE='14',
 XY='(-2150,3275)',
 ROT='0',
 VER='1',
 PACK_TYPE='0402LF',
 LOCATION='R186',
 CDS_LIB='pure_quanta',
 CDS_PART_NAME='Q_RES_0402LF-110,1%,1/16W,CHIPA',
 WATTAGE='1/16W',
 TOLERANCE='1%',
 MATERIAL='CHIP',
 VALUE='110',
 PRIM_FILE='W:/<user>/logical/q_res/chips/chips.prt';

PART_NAME
 R187 'Q_RES_0402LF-33.2,1%,1/16W,CHIA':;

SECTION_NUMBER 1
 '@SCM_LIB.SCM(SCH_1):PAGE14_I237@PURE_QUANTA.Q_RES(CHIPS)':
 C_PATH='@scm_lib.scm(sch_1):page14_i237@pure_quanta.q_res(chips)',
 P_PATH='@scm_lib.scm(sch_1):page14_i237@pure_quanta.q_res(chips)',
 PATH='I237',
 DRAWING='@SCM_LIB.SCM(SCH_1):PAGE14',
 PHYS_PAGE='14',
 XY='(-2150,3225)',
 ROT='0',
 VER='1',
 PACK_TYPE='0402LF',
 LOCATION='R187',
 CDS_LIB='pure_quanta',
 CDS_PART_NAME='Q_RES_0402LF-33.2,1%,1/16W,CHIA',
 WATTAGE='1/16W',
 TOLERANCE='1%',
 MATERIAL='CHIP',
 VALUE='33.2',
 PRIM_FILE='W:/<user>/logical/q_res/chips/chips.prt';

PART_NAME
 R188 'Q_RES_0402LF-1K,1%,1/16W,CHIP,A':;

SECTION_NUMBER 1
 '@SCM_LIB.SCM(SCH_1):PAGE14_I183@PURE_QUANTA.Q_RES(CHIPS)':
 C_PATH='@scm_lib.scm(sch_1):page14_i183@pure_quanta.q_res(chips)',
 P_PATH='@scm_lib.scm(sch_1):page14_i183@pure_quanta.q_res(chips)',
 PATH='I183',
 DRAWING='@SCM_LIB.SCM(SCH_1):PAGE14',
 PHYS_PAGE='14',
 XY='(-275,1800)',
 ROT='0',
 VER='1',
 PACK_TYPE='0402LF',
 LOCATION='R188',
 CDS_LIB='pure_quanta',
 CDS_PART_NAME='Q_RES_0402LF-1K,1%,1/16W,CHIP,A',
 WATTAGE='1/16W',
 TOLERANCE='1%',
 MATERIAL='CHIP',
 VALUE='1K',
 PRIM_FILE='W:/<user>/logical/q_res/chips/chips.prt';

PART_NAME
 R189 'Q_RES_0402LF-1K,1%,1/16W,CHIP,A':;

SECTION_NUMBER 1
 '@SCM_LIB.SCM(SCH_1):PAGE14_I188@PURE_QUANTA.Q_RES(CHIPS)':
 C_PATH='@scm_lib.scm(sch_1):page14_i188@pure_quanta.q_res(chips)',
 P_PATH='@scm_lib.scm(sch_1):page14_i188@pure_quanta.q_res(chips)',
 PATH='I188',
 DRAWING='@SCM_LIB.SCM(SCH_1):PAGE14',
 PHYS_PAGE='14',
 XY='(-275,1700)',
 ROT='0',
 VER='1',
 PACK_TYPE='0402LF',
 LOCATION='R189',
 CDS_LIB='pure_quanta',
 CDS_PART_NAME='Q_RES_0402LF-1K,1%,1/16W,CHIP,A',
 WATTAGE='1/16W',
 TOLERANCE='1%',
 MATERIAL='CHIP',
 VALUE='1K',
 PRIM_FILE='W:/<user>/logical/q_res/chips/chips.prt';

PART_NAME
 R190 'Q_RES_0402LF-1K,1%,1/16W,CHIP,A':;

SECTION_NUMBER 1
 '@SCM_LIB.SCM(SCH_1):PAGE14_I173@PURE_QUANTA.Q_RES(CHIPS)':
 C_PATH='@scm_lib.scm(sch_1):page14_i173@pure_quanta.q_res(chips)',
 P_PATH='@scm_lib.scm(sch_1):page14_i173@pure_quanta.q_res(chips)',
 PATH='I173',
 DRAWING='@SCM_LIB.SCM(SCH_1):PAGE14',
 PHYS_PAGE='14',
 XY='(-275,2000)',
 ROT='0',
 VER='1',
 PACK_TYPE='0402LF',
 LOCATION='R190',
 CDS_LIB='pure_quanta',
 CDS_PART_NAME='Q_RES_0402LF-1K,1%,1/16W,CHIP,A',
 WATTAGE='1/16W',
 TOLERANCE='1%',
 MATERIAL='CHIP',
 VALUE='1K',
 PRIM_FILE='W:/<user>/logical/q_res/chips/chips.prt';

PART_NAME
 R191 'Q_RES_0402LF-1K,1%,1/16W,CHIP,A':;

SECTION_NUMBER 1
 '@SCM_LIB.SCM(SCH_1):PAGE14_I174@PURE_QUANTA.Q_RES(CHIPS)':
 C_PATH='@scm_lib.scm(sch_1):page14_i174@pure_quanta.q_res(chips)',
 P_PATH='@scm_lib.scm(sch_1):page14_i174@pure_quanta.q_res(chips)',
 PATH='I174',
 DRAWING='@SCM_LIB.SCM(SCH_1):PAGE14',
 PHYS_PAGE='14',
 XY='(-275,1900)',
 ROT='0',
 VER='1',
 PACK_TYPE='0402LF',
 LOCATION='R191',
 CDS_LIB='pure_quanta',
 CDS_PART_NAME='Q_RES_0402LF-1K,1%,1/16W,CHIP,A',
 WATTAGE='1/16W',
 TOLERANCE='1%',
 MATERIAL='CHIP',
 VALUE='1K',
 PRIM_FILE='W:/<user>/logical/q_res/chips/chips.prt';

PART_NAME
 R192 'Q_RES_0402LF-49.9,1%,1/16W,CHIA':;

SECTION_NUMBER 1
 '@SCM_LIB.SCM(SCH_1):PAGE22_I41@PURE_QUANTA.Q_RES(CHIPS)':
 C_PATH='@scm_lib.scm(sch_1):page22_i41@pure_quanta.q_res(chips)',
 P_PATH='@scm_lib.scm(sch_1):page22_i41@pure_quanta.q_res(chips)',
 PATH='I41',
 DRAWING='@SCM_LIB.SCM(SCH_1):PAGE22',
 PHYS_PAGE='22',
 XY='(450,1100)',
 ROT='0',
 VER='1',
 PACK_TYPE='0402LF',
 LOCATION='R192',
 CDS_LIB='pure_quanta',
 CDS_PART_NAME='Q_RES_0402LF-49.9,1%,1/16W,CHIA',
 WATTAGE='1/16W',
 TOLERANCE='1%',
 MATERIAL='CHIP',
 VALUE='49.9',
 PRIM_FILE='W:/<user>/logical/q_res/chips/chips.prt';

PART_NAME
 R193 'Q_RES_0402LF-100K,1%,1/16W,CHIA':;

SECTION_NUMBER 1
 '@SCM_LIB.SCM(SCH_1):PAGE29_I166@PURE_QUANTA.Q_RES(CHIPS)':
 C_PATH='@scm_lib.scm(sch_1):page29_i166@pure_quanta.q_res(chips)',
 P_PATH='@scm_lib.scm(sch_1):page29_i166@pure_quanta.q_res(chips)',
 PATH='I166',
 DRAWING='@SCM_LIB.SCM(SCH_1):PAGE29',
 PHYS_PAGE='29',
 XY='(1275,3800)',
 ROT='0',
 VER='2',
 PACK_TYPE='0402LF',
 LOCATION='R193',
 CDS_LIB='pure_quanta',
 CDS_PART_NAME='Q_RES_0402LF-100K,1%,1/16W,CHIA',
 WATTAGE='1/16W',
 TOLERANCE='1%',
 MATERIAL='CHIP',
 VALUE='100K',
 PRIM_FILE='W:/<user>/logical/q_res/chips/chips.prt';

PART_NAME
 R194 'Q_RES_0402LF-1K,1%,1/16W,CHIP,A':;

SECTION_NUMBER 1
 '@SCM_LIB.SCM(SCH_1):PAGE14_I171@PURE_QUANTA.Q_RES(CHIPS)':
 C_PATH='@scm_lib.scm(sch_1):page14_i171@pure_quanta.q_res(chips)',
 P_PATH='@scm_lib.scm(sch_1):page14_i171@pure_quanta.q_res(chips)',
 PATH='I171',
 DRAWING='@SCM_LIB.SCM(SCH_1):PAGE14',
 PHYS_PAGE='14',
 XY='(-275,2200)',
 ROT='0',
 VER='1',
 PACK_TYPE='0402LF',
 LOCATION='R194',
 CDS_LIB='pure_quanta',
 CDS_PART_NAME='Q_RES_0402LF-1K,1%,1/16W,CHIP,A',
 WATTAGE='1/16W',
 TOLERANCE='1%',
 MATERIAL='CHIP',
 VALUE='1K',
 PRIM_FILE='W:/<user>/logical/q_res/chips/chips.prt';

PART_NAME
 R195 'Q_RES_0402LF-1K,1%,1/16W,CHIP,A':;

SECTION_NUMBER 1
 '@SCM_LIB.SCM(SCH_1):PAGE14_I172@PURE_QUANTA.Q_RES(CHIPS)':
 C_PATH='@scm_lib.scm(sch_1):page14_i172@pure_quanta.q_res(chips)',
 P_PATH='@scm_lib.scm(sch_1):page14_i172@pure_quanta.q_res(chips)',
 PATH='I172',
 DRAWING='@SCM_LIB.SCM(SCH_1):PAGE14',
 PHYS_PAGE='14',
 XY='(-275,2100)',
 ROT='0',
 VER='1',
 PACK_TYPE='0402LF',
 LOCATION='R195',
 CDS_LIB='pure_quanta',
 CDS_PART_NAME='Q_RES_0402LF-1K,1%,1/16W,CHIP,A',
 WATTAGE='1/16W',
 TOLERANCE='1%',
 MATERIAL='CHIP',
 VALUE='1K',
 PRIM_FILE='W:/<user>/logical/q_res/chips/chips.prt';

PART_NAME
 R196 'Q_RES_0402LF-1K,1%,1/16W,CHIP,A':;

SECTION_NUMBER 1
 '@SCM_LIB.SCM(SCH_1):PAGE14_I189@PURE_QUANTA.Q_RES(CHIPS)':
 C_PATH='@scm_lib.scm(sch_1):page14_i189@pure_quanta.q_res(chips)',
 P_PATH='@scm_lib.scm(sch_1):page14_i189@pure_quanta.q_res(chips)',
 PATH='I189',
 DRAWING='@SCM_LIB.SCM(SCH_1):PAGE14',
 PHYS_PAGE='14',
 XY='(-275,1575)',
 ROT='0',
 VER='1',
 PACK_TYPE='0402LF',
 LOCATION='R196',
 CDS_LIB='pure_quanta',
 CDS_PART_NAME='Q_RES_0402LF-1K,1%,1/16W,CHIP,A',
 WATTAGE='1/16W',
 TOLERANCE='1%',
 MATERIAL='CHIP',
 VALUE='1K',
 PRIM_FILE='W:/<user>/logical/q_res/chips/chips.prt';

PART_NAME
 R197 'Q_RES_0402LF-1K,1%,1/16W,CHIP,A':;

SECTION_NUMBER 1
 '@SCM_LIB.SCM(SCH_1):PAGE14_I190@PURE_QUANTA.Q_RES(CHIPS)':
 C_PATH='@scm_lib.scm(sch_1):page14_i190@pure_quanta.q_res(chips)',
 P_PATH='@scm_lib.scm(sch_1):page14_i190@pure_quanta.q_res(chips)',
 PATH='I190',
 DRAWING='@SCM_LIB.SCM(SCH_1):PAGE14',
 PHYS_PAGE='14',
 XY='(-275,1475)',
 ROT='0',
 VER='1',
 PACK_TYPE='0402LF',
 LOCATION='R197',
 CDS_LIB='pure_quanta',
 CDS_PART_NAME='Q_RES_0402LF-1K,1%,1/16W,CHIP,A',
 WATTAGE='1/16W',
 TOLERANCE='1%',
 MATERIAL='CHIP',
 VALUE='1K',
 PRIM_FILE='W:/<user>/logical/q_res/chips/chips.prt';

PART_NAME
 R198 'Q_RES_0402LF-110,1%,1/16W,CHIPA':;

SECTION_NUMBER 1
 '@SCM_LIB.SCM(SCH_1):PAGE14_I234@PURE_QUANTA.Q_RES(CHIPS)':
 C_PATH='@scm_lib.scm(sch_1):page14_i234@pure_quanta.q_res(chips)',
 P_PATH='@scm_lib.scm(sch_1):page14_i234@pure_quanta.q_res(chips)',
 PATH='I234',
 DRAWING='@SCM_LIB.SCM(SCH_1):PAGE14',
 PHYS_PAGE='14',
 XY='(3100,3425)',
 ROT='0',
 VER='1',
 PACK_TYPE='0402LF',
 LOCATION='R198',
 CDS_LIB='pure_quanta',
 CDS_PART_NAME='Q_RES_0402LF-110,1%,1/16W,CHIPA',
 WATTAGE='1/16W',
 TOLERANCE='1%',
 MATERIAL='CHIP',
 VALUE='110',
 PRIM_FILE='W:/<user>/logical/q_res/chips/chips.prt';

PART_NAME
 R199 'Q_RES_0402LF-33.2,1%,1/16W,CHIA':;

SECTION_NUMBER 1
 '@SCM_LIB.SCM(SCH_1):PAGE14_I238@PURE_QUANTA.Q_RES(CHIPS)':
 C_PATH='@scm_lib.scm(sch_1):page14_i238@pure_quanta.q_res(chips)',
 P_PATH='@scm_lib.scm(sch_1):page14_i238@pure_quanta.q_res(chips)',
 PATH='I238',
 DRAWING='@SCM_LIB.SCM(SCH_1):PAGE14',
 PHYS_PAGE='14',
 XY='(3100,3375)',
 ROT='0',
 VER='1',
 PACK_TYPE='0402LF',
 LOCATION='R199',
 CDS_LIB='pure_quanta',
 CDS_PART_NAME='Q_RES_0402LF-33.2,1%,1/16W,CHIA',
 WATTAGE='1/16W',
 TOLERANCE='1%',
 MATERIAL='CHIP',
 VALUE='33.2',
 PRIM_FILE='W:/<user>/logical/q_res/chips/chips.prt';

PART_NAME
 R200 'Q_RES_0402LF-110,1%,1/16W,CHIPA':;

SECTION_NUMBER 1
 '@SCM_LIB.SCM(SCH_1):PAGE14_I235@PURE_QUANTA.Q_RES(CHIPS)':
 C_PATH='@scm_lib.scm(sch_1):page14_i235@pure_quanta.q_res(chips)',
 P_PATH='@scm_lib.scm(sch_1):page14_i235@pure_quanta.q_res(chips)',
 PATH='I235',
 DRAWING='@SCM_LIB.SCM(SCH_1):PAGE14',
 PHYS_PAGE='14',
 XY='(3100,3275)',
 ROT='0',
 VER='1',
 PACK_TYPE='0402LF',
 LOCATION='R200',
 CDS_LIB='pure_quanta',
 CDS_PART_NAME='Q_RES_0402LF-110,1%,1/16W,CHIPA',
 WATTAGE='1/16W',
 TOLERANCE='1%',
 MATERIAL='CHIP',
 VALUE='110',
 PRIM_FILE='W:/<user>/logical/q_res/chips/chips.prt';

PART_NAME
 R201 'Q_RES_0402LF-33.2,1%,1/16W,CHIA':;

SECTION_NUMBER 1
 '@SCM_LIB.SCM(SCH_1):PAGE14_I239@PURE_QUANTA.Q_RES(CHIPS)':
 C_PATH='@scm_lib.scm(sch_1):page14_i239@pure_quanta.q_res(chips)',
 P_PATH='@scm_lib.scm(sch_1):page14_i239@pure_quanta.q_res(chips)',
 PATH='I239',
 DRAWING='@SCM_LIB.SCM(SCH_1):PAGE14',
 PHYS_PAGE='14',
 XY='(3100,3225)',
 ROT='0',
 VER='1',
 PACK_TYPE='0402LF',
 LOCATION='R201',
 CDS_LIB='pure_quanta',
 CDS_PART_NAME='Q_RES_0402LF-33.2,1%,1/16W,CHIA',
 WATTAGE='1/16W',
 TOLERANCE='1%',
 MATERIAL='CHIP',
 VALUE='33.2',
 PRIM_FILE='W:/<user>/logical/q_res/chips/chips.prt';

PART_NAME
 R202 'Q_RES_0402LF-10K,1%,1/16W,EMPTA':;

SECTION_NUMBER 1
 '@SCM_LIB.SCM(SCH_1):PAGE32_I140@PURE_QUANTA.Q_RES(CHIPS)':
 C_PATH='@scm_lib.scm(sch_1):page32_i140@pure_quanta.q_res(chips)',
 P_PATH='@scm_lib.scm(sch_1):page32_i140@pure_quanta.q_res(chips)',
 PATH='I140',
 DRAWING='@SCM_LIB.SCM(SCH_1):PAGE32',
 PHYS_PAGE='32',
 XY='(-2425,-100)',
 ROT='0',
 VER='1',
 PACK_TYPE='0402LF',
 LOCATION='R202',
 CDS_LIB='pure_quanta',
 CDS_PART_NAME='Q_RES_0402LF-10K,1%,1/16W,EMPTA',
 WATTAGE='1/16W',
 TOLERANCE='1%',
 MATERIAL='EMPTY',
 VALUE='10K',
 PRIM_FILE='W:/<user>/logical/q_res/chips/chips.prt';

PART_NAME
 R203 'Q_RES_0402LF-10K,1%,1/16W,CHIPA':;

SECTION_NUMBER 1
 '@SCM_LIB.SCM(SCH_1):PAGE32_I117@PURE_QUANTA.Q_RES(CHIPS)':
 C_PATH='@scm_lib.scm(sch_1):page32_i117@pure_quanta.q_res(chips)',
 P_PATH='@scm_lib.scm(sch_1):page32_i117@pure_quanta.q_res(chips)',
 PATH='I117',
 DRAWING='@SCM_LIB.SCM(SCH_1):PAGE32',
 PHYS_PAGE='32',
 XY='(-2425,425)',
 ROT='0',
 VER='1',
 PACK_TYPE='0402LF',
 LOCATION='R203',
 CDS_LIB='pure_quanta',
 CDS_PART_NAME='Q_RES_0402LF-10K,1%,1/16W,CHIPA',
 WATTAGE='1/16W',
 TOLERANCE='1%',
 MATERIAL='CHIP',
 VALUE='10K',
 PRIM_FILE='W:/<user>/logical/q_res/chips/chips.prt';

PART_NAME
 R204 'Q_RES_0402LF-10K,1%,1/16W,CHIPA':;

SECTION_NUMBER 1
 '@SCM_LIB.SCM(SCH_1):PAGE32_I120@PURE_QUANTA.Q_RES(CHIPS)':
 C_PATH='@scm_lib.scm(sch_1):page32_i120@pure_quanta.q_res(chips)',
 P_PATH='@scm_lib.scm(sch_1):page32_i120@pure_quanta.q_res(chips)',
 PATH='I120',
 DRAWING='@SCM_LIB.SCM(SCH_1):PAGE32',
 PHYS_PAGE='32',
 XY='(-2425,350)',
 ROT='0',
 VER='1',
 PACK_TYPE='0402LF',
 LOCATION='R204',
 CDS_LIB='pure_quanta',
 CDS_PART_NAME='Q_RES_0402LF-10K,1%,1/16W,CHIPA',
 WATTAGE='1/16W',
 TOLERANCE='1%',
 MATERIAL='CHIP',
 VALUE='10K',
 PRIM_FILE='W:/<user>/logical/q_res/chips/chips.prt';

PART_NAME
 R205 'Q_RES_0402LF-20K,1%,1/16W,CHIPA':;

SECTION_NUMBER 1
 '@SCM_LIB.SCM(SCH_1):PAGE29_I184@PURE_QUANTA.Q_RES(CHIPS)':
 C_PATH='@scm_lib.scm(sch_1):page29_i184@pure_quanta.q_res(chips)',
 P_PATH='@scm_lib.scm(sch_1):page29_i184@pure_quanta.q_res(chips)',
 PATH='I184',
 DRAWING='@SCM_LIB.SCM(SCH_1):PAGE29',
 SEC_TYPE='0402LF',
 PHYS_PAGE='29',
 XY='(3775,125)',
 ROT='2',
 VER='2',
 PACK_TYPE='0402LF',
 LOCATION='R205',
 SEC='1',
 CDS_LIB='pure_quanta',
 CDS_PART_NAME='Q_RES_0402LF-20K,1%,1/16W,CHIPA',
 WATTAGE='1/16W',
 TOLERANCE='1%',
 MATERIAL='CHIP',
 VALUE='20K',
 PRIM_FILE='W:/<user>/logical/q_res/chips/chips.prt';

PART_NAME
 R206 'Q_RES_0402LF-10K,1%,1/16W,CHIPA':;

SECTION_NUMBER 1
 '@SCM_LIB.SCM(SCH_1):PAGE32_I143@PURE_QUANTA.Q_RES(CHIPS)':
 C_PATH='@scm_lib.scm(sch_1):page32_i143@pure_quanta.q_res(chips)',
 P_PATH='@scm_lib.scm(sch_1):page32_i143@pure_quanta.q_res(chips)',
 PATH='I143',
 DRAWING='@SCM_LIB.SCM(SCH_1):PAGE32',
 PHYS_PAGE='32',
 XY='(-2400,-200)',
 ROT='0',
 VER='1',
 PACK_TYPE='0402LF',
 LOCATION='R206',
 CDS_LIB='pure_quanta',
 CDS_PART_NAME='Q_RES_0402LF-10K,1%,1/16W,CHIPA',
 WATTAGE='1/16W',
 TOLERANCE='1%',
 MATERIAL='CHIP',
 VALUE='10K',
 PRIM_FILE='W:/<user>/logical/q_res/chips/chips.prt';

PART_NAME
 R207 'Q_RES_0402LF-0,5%,1/16W,CHIP,CA':;

SECTION_NUMBER 1
 '@SCM_LIB.SCM(SCH_1):PAGE15_I4@PURE_QUANTA.Q_RES(CHIPS)':
 C_PATH='@scm_lib.scm(sch_1):page15_i4@pure_quanta.q_res(chips)',
 P_PATH='@scm_lib.scm(sch_1):page15_i4@pure_quanta.q_res(chips)',
 PATH='I4',
 DRAWING='@SCM_LIB.SCM(SCH_1):PAGE15',
 PHYS_PAGE='15',
 XY='(2425,-550)',
 ROT='0',
 VER='1',
 PACK_TYPE='0402LF',
 LOCATION='R207',
 CDS_LIB='pure_quanta',
 CDS_PART_NAME='Q_RES_0402LF-0,5%,1/16W,CHIP,CA',
 WATTAGE='1/16W',
 TOLERANCE='5%',
 MATERIAL='CHIP',
 VALUE='0',
 PRIM_FILE='W:/<user>/logical/q_res/chips/chips.prt';

PART_NAME
 R208 'Q_RES_0402LF-0,5%,1/16W,EMPTY,A':;

SECTION_NUMBER 1
 '@SCM_LIB.SCM(SCH_1):PAGE15_I2@PURE_QUANTA.Q_RES(CHIPS)':
 C_PATH='@scm_lib.scm(sch_1):page15_i2@pure_quanta.q_res(chips)',
 P_PATH='@scm_lib.scm(sch_1):page15_i2@pure_quanta.q_res(chips)',
 PATH='I2',
 DRAWING='@SCM_LIB.SCM(SCH_1):PAGE15',
 PHYS_PAGE='15',
 XY='(2425,-850)',
 ROT='0',
 VER='1',
 PACK_TYPE='0402LF',
 LOCATION='R208',
 CDS_LIB='pure_quanta',
 CDS_PART_NAME='Q_RES_0402LF-0,5%,1/16W,EMPTY,A',
 WATTAGE='1/16W',
 TOLERANCE='5%',
 MATERIAL='EMPTY',
 VALUE='0',
 PRIM_FILE='W:/<user>/logical/q_res/chips/chips.prt';

PART_NAME
 R209 'Q_RES_0402LF-10K,1%,1/16W,EMPTA':;

SECTION_NUMBER 1
 '@SCM_LIB.SCM(SCH_1):PAGE15_I19@PURE_QUANTA.Q_RES(CHIPS)':
 C_PATH='@scm_lib.scm(sch_1):page15_i19@pure_quanta.q_res(chips)',
 P_PATH='@scm_lib.scm(sch_1):page15_i19@pure_quanta.q_res(chips)',
 PATH='I19',
 DRAWING='@SCM_LIB.SCM(SCH_1):PAGE15',
 PHYS_PAGE='15',
 XY='(5700,-1150)',
 ROT='0',
 VER='1',
 PACK_TYPE='0402LF',
 LOCATION='R209',
 CDS_LIB='pure_quanta',
 CDS_PART_NAME='Q_RES_0402LF-10K,1%,1/16W,EMPTA',
 WATTAGE='1/16W',
 TOLERANCE='1%',
 MATERIAL='EMPTY',
 VALUE='10K',
 PRIM_FILE='W:/<user>/logical/q_res/chips/chips.prt';

PART_NAME
 R210 'Q_RES_0402LF-1K,1%,1/16W,CHIP,A':;

SECTION_NUMBER 1
 '@SCM_LIB.SCM(SCH_1):PAGE15_I47@PURE_QUANTA.Q_RES(CHIPS)':
 C_PATH='@scm_lib.scm(sch_1):page15_i47@pure_quanta.q_res(chips)',
 P_PATH='@scm_lib.scm(sch_1):page15_i47@pure_quanta.q_res(chips)',
 PATH='I47',
 DRAWING='@SCM_LIB.SCM(SCH_1):PAGE15',
 SEC_TYPE='0402LF',
 PHYS_PAGE='15',
 XY='(-1850,3975)',
 ROT='0',
 VER='1',
 PACK_TYPE='0402LF',
 LOCATION='R210',
 SEC='1',
 CDS_LIB='pure_quanta',
 CDS_PART_NAME='Q_RES_0402LF-1K,1%,1/16W,CHIP,A',
 WATTAGE='1/16W',
 TOLERANCE='1%',
 MATERIAL='CHIP',
 VALUE='1K',
 PRIM_FILE='W:/<user>/logical/q_res/chips/chips.prt';

PART_NAME
 R211 'Q_RES_0402LF-10K,1%,1/16W,CHIPA':;

SECTION_NUMBER 1
 '@SCM_LIB.SCM(SCH_1):PAGE15_I51@PURE_QUANTA.Q_RES(CHIPS)':
 C_PATH='@scm_lib.scm(sch_1):page15_i51@pure_quanta.q_res(chips)',
 P_PATH='@scm_lib.scm(sch_1):page15_i51@pure_quanta.q_res(chips)',
 PATH='I51',
 DRAWING='@SCM_LIB.SCM(SCH_1):PAGE15',
 PHYS_PAGE='15',
 XY='(-1025,4350)',
 ROT='2',
 VER='2',
 PACK_TYPE='0402LF',
 LOCATION='R211',
 CDS_LIB='pure_quanta',
 CDS_PART_NAME='Q_RES_0402LF-10K,1%,1/16W,CHIPA',
 WATTAGE='1/16W',
 TOLERANCE='1%',
 MATERIAL='CHIP',
 VALUE='10K',
 PRIM_FILE='W:/<user>/logical/q_res/chips/chips.prt';

PART_NAME
 R212 'Q_RES_0402LF-4.7K,1%,1/16W,CHIA':;

SECTION_NUMBER 1
 '@SCM_LIB.SCM(SCH_1):PAGE15_I21@PURE_QUANTA.Q_RES(CHIPS)':
 C_PATH='@scm_lib.scm(sch_1):page15_i21@pure_quanta.q_res(chips)',
 P_PATH='@scm_lib.scm(sch_1):page15_i21@pure_quanta.q_res(chips)',
 PATH='I21',
 DRAWING='@SCM_LIB.SCM(SCH_1):PAGE15',
 PHYS_PAGE='15',
 XY='(-500,625)',
 ROT='0',
 VER='2',
 PACK_TYPE='0402LF',
 LOCATION='R212',
 CDS_LIB='pure_quanta',
 CDS_PART_NAME='Q_RES_0402LF-4.7K,1%,1/16W,CHIA',
 WATTAGE='1/16W',
 TOLERANCE='1%',
 MATERIAL='CHIP',
 VALUE='4.7K',
 PRIM_FILE='W:/<user>/logical/q_res/chips/chips.prt';

PART_NAME
 R213 'Q_RES_0402LF-0,5%,1/16W,CHIP,CA':;

SECTION_NUMBER 1
 '@SCM_LIB.SCM(SCH_1):PAGE15_I34@PURE_QUANTA.Q_RES(CHIPS)':
 C_PATH='@scm_lib.scm(sch_1):page15_i34@pure_quanta.q_res(chips)',
 P_PATH='@scm_lib.scm(sch_1):page15_i34@pure_quanta.q_res(chips)',
 PATH='I34',
 DRAWING='@SCM_LIB.SCM(SCH_1):PAGE15',
 PHYS_PAGE='15',
 XY='(4700,-350)',
 ROT='0',
 VER='1',
 PACK_TYPE='0402LF',
 LOCATION='R213',
 CDS_LIB='pure_quanta',
 CDS_PART_NAME='Q_RES_0402LF-0,5%,1/16W,CHIP,CA',
 WATTAGE='1/16W',
 TOLERANCE='5%',
 MATERIAL='CHIP',
 VALUE='0',
 PRIM_FILE='W:/<user>/logical/q_res/chips/chips.prt';

PART_NAME
 R214 'Q_RES_0402LF-0,5%,1/16W,EMPTY,A':;

SECTION_NUMBER 1
 '@SCM_LIB.SCM(SCH_1):PAGE15_I32@PURE_QUANTA.Q_RES(CHIPS)':
 C_PATH='@scm_lib.scm(sch_1):page15_i32@pure_quanta.q_res(chips)',
 P_PATH='@scm_lib.scm(sch_1):page15_i32@pure_quanta.q_res(chips)',
 PATH='I32',
 DRAWING='@SCM_LIB.SCM(SCH_1):PAGE15',
 PHYS_PAGE='15',
 XY='(4700,-650)',
 ROT='0',
 VER='1',
 PACK_TYPE='0402LF',
 LOCATION='R214',
 CDS_LIB='pure_quanta',
 CDS_PART_NAME='Q_RES_0402LF-0,5%,1/16W,EMPTY,A',
 WATTAGE='1/16W',
 TOLERANCE='5%',
 MATERIAL='EMPTY',
 VALUE='0',
 PRIM_FILE='W:/<user>/logical/q_res/chips/chips.prt';

PART_NAME
 R215 'Q_RES_0402LF-33.2,1%,1/16W,CHIA':;

SECTION_NUMBER 1
 '@SCM_LIB.SCM(SCH_1):PAGE15_I42@PURE_QUANTA.Q_RES(CHIPS)':
 C_PATH='@scm_lib.scm(sch_1):page15_i42@pure_quanta.q_res(chips)',
 P_PATH='@scm_lib.scm(sch_1):page15_i42@pure_quanta.q_res(chips)',
 PATH='I42',
 DRAWING='@SCM_LIB.SCM(SCH_1):PAGE15',
 PHYS_PAGE='15',
 XY='(1750,525)',
 ROT='0',
 VER='1',
 PACK_TYPE='0402LF',
 LOCATION='R215',
 CDS_LIB='pure_quanta',
 CDS_PART_NAME='Q_RES_0402LF-33.2,1%,1/16W,CHIA',
 WATTAGE='1/16W',
 TOLERANCE='1%',
 MATERIAL='CHIP',
 VALUE='33.2',
 PRIM_FILE='W:/<user>/logical/q_res/chips/chips.prt';

PART_NAME
 R216 'Q_RES_0402LF-49.9,1%,1/16W,CHIA':;

SECTION_NUMBER 1
 '@SCM_LIB.SCM(SCH_1):PAGE15_I389@PURE_QUANTA.Q_RES(CHIPS)':
 C_PATH='@scm_lib.scm(sch_1):page15_i389@pure_quanta.q_res(chips)',
 P_PATH='@scm_lib.scm(sch_1):page15_i389@pure_quanta.q_res(chips)',
 PATH='I389',
 DRAWING='@SCM_LIB.SCM(SCH_1):PAGE15',
 PHYS_PAGE='15',
 XY='(3125,2325)',
 ROT='0',
 VER='1',
 PACK_TYPE='0402LF',
 LOCATION='R216',
 CDS_LIB='pure_quanta',
 CDS_PART_NAME='Q_RES_0402LF-49.9,1%,1/16W,CHIA',
 WATTAGE='1/16W',
 TOLERANCE='1%',
 MATERIAL='CHIP',
 VALUE='49.9',
 PRIM_FILE='W:/<user>/logical/q_res/chips/chips.prt';

PART_NAME
 R217 'Q_RES_0402LF-0,5%,1/16W,CHIP,CA':;

SECTION_NUMBER 1
 '@SCM_LIB.SCM(SCH_1):PAGE15_I92@PURE_QUANTA.Q_RES(CHIPS)':
 C_PATH='@scm_lib.scm(sch_1):page15_i92@pure_quanta.q_res(chips)',
 P_PATH='@scm_lib.scm(sch_1):page15_i92@pure_quanta.q_res(chips)',
 PATH='I92',
 DRAWING='@SCM_LIB.SCM(SCH_1):PAGE15',
 PHYS_PAGE='15',
 XY='(3300,2825)',
 ROT='0',
 VER='1',
 PACK_TYPE='0402LF',
 LOCATION='R217',
 CDS_LIB='pure_quanta',
 CDS_PART_NAME='Q_RES_0402LF-0,5%,1/16W,CHIP,CA',
 WATTAGE='1/16W',
 TOLERANCE='5%',
 MATERIAL='CHIP',
 VALUE='0',
 PRIM_FILE='W:/<user>/logical/q_res/chips/chips.prt';

PART_NAME
 R218 'Q_RES_0402LF-0,5%,1/16W,CHIP,CA':;

SECTION_NUMBER 1
 '@SCM_LIB.SCM(SCH_1):PAGE15_I93@PURE_QUANTA.Q_RES(CHIPS)':
 C_PATH='@scm_lib.scm(sch_1):page15_i93@pure_quanta.q_res(chips)',
 P_PATH='@scm_lib.scm(sch_1):page15_i93@pure_quanta.q_res(chips)',
 PATH='I93',
 DRAWING='@SCM_LIB.SCM(SCH_1):PAGE15',
 PHYS_PAGE='15',
 XY='(3300,2775)',
 ROT='0',
 VER='1',
 PACK_TYPE='0402LF',
 LOCATION='R218',
 CDS_LIB='pure_quanta',
 CDS_PART_NAME='Q_RES_0402LF-0,5%,1/16W,CHIP,CA',
 WATTAGE='1/16W',
 TOLERANCE='5%',
 MATERIAL='CHIP',
 VALUE='0',
 PRIM_FILE='W:/<user>/logical/q_res/chips/chips.prt';

PART_NAME
 R219 'Q_RES_0402LF-100K,1%,1/16W,EMPA':;

SECTION_NUMBER 1
 '@SCM_LIB.SCM(SCH_1):PAGE29_I170@PURE_QUANTA.Q_RES(CHIPS)':
 C_PATH='@scm_lib.scm(sch_1):page29_i170@pure_quanta.q_res(chips)',
 P_PATH='@scm_lib.scm(sch_1):page29_i170@pure_quanta.q_res(chips)',
 PATH='I170',
 DRAWING='@SCM_LIB.SCM(SCH_1):PAGE29',
 PHYS_PAGE='29',
 XY='(4100,1975)',
 ROT='2',
 VER='2',
 PACK_TYPE='0402LF',
 LOCATION='R219',
 CDS_LIB='pure_quanta',
 CDS_PART_NAME='Q_RES_0402LF-100K,1%,1/16W,EMPA',
 WATTAGE='1/16W',
 TOLERANCE='1%',
 MATERIAL='EMPTY',
 VALUE='100K',
 PRIM_FILE='W:/<user>/logical/q_res/chips/chips.prt';

PART_NAME
 R220 'Q_RES_0402LF-0,5%,1/16W,CHIP,CA':;

SECTION_NUMBER 1
 '@SCM_LIB.SCM(SCH_1):PAGE36_I46@PURE_QUANTA.Q_RES(CHIPS)':
 C_PATH='@scm_lib.scm(sch_1):page36_i46@pure_quanta.q_res(chips)',
 P_PATH='@scm_lib.scm(sch_1):page36_i46@pure_quanta.q_res(chips)',
 PATH='I46',
 DRAWING='@SCM_LIB.SCM(SCH_1):PAGE36',
 PHYS_PAGE='36',
 XY='(-2575,4525)',
 ROT='0',
 VER='1',
 PACK_TYPE='0402LF',
 CDS_LIB='pure_quanta',
 CDS_PART_NAME='Q_RES_0402LF-0,5%,1/16W,CHIP,CA',
 WATTAGE='1/16W',
 TOLERANCE='5%',
 MATERIAL='CHIP',
 VALUE='0',
 PRIM_FILE='W:/<user>/logical/q_res/chips/chips.prt';

PART_NAME
 R221 'Q_RES_0402LF-33.2,1%,1/16W,CHIA':;

SECTION_NUMBER 1
 '@SCM_LIB.SCM(SCH_1):PAGE32_I81@PURE_QUANTA.Q_RES(CHIPS)':
 C_PATH='@scm_lib.scm(sch_1):page32_i81@pure_quanta.q_res(chips)',
 P_PATH='@scm_lib.scm(sch_1):page32_i81@pure_quanta.q_res(chips)',
 PATH='I81',
 DRAWING='@SCM_LIB.SCM(SCH_1):PAGE32',
 PHYS_PAGE='32',
 XY='(-425,1875)',
 ROT='0',
 VER='1',
 PACK_TYPE='0402LF',
 LOCATION='R221',
 CDS_LIB='pure_quanta',
 CDS_PART_NAME='Q_RES_0402LF-33.2,1%,1/16W,CHIA',
 WATTAGE='1/16W',
 TOLERANCE='1%',
 MATERIAL='CHIP',
 VALUE='33.2',
 PRIM_FILE='W:/<user>/logical/q_res/chips/chips.prt';

PART_NAME
 R222 'Q_RES_0402LF-33.2,1%,1/16W,CHIA':;

SECTION_NUMBER 1
 '@SCM_LIB.SCM(SCH_1):PAGE32_I80@PURE_QUANTA.Q_RES(CHIPS)':
 C_PATH='@scm_lib.scm(sch_1):page32_i80@pure_quanta.q_res(chips)',
 P_PATH='@scm_lib.scm(sch_1):page32_i80@pure_quanta.q_res(chips)',
 PATH='I80',
 DRAWING='@SCM_LIB.SCM(SCH_1):PAGE32',
 PHYS_PAGE='32',
 XY='(-425,1825)',
 ROT='0',
 VER='1',
 PACK_TYPE='0402LF',
 LOCATION='R222',
 CDS_LIB='pure_quanta',
 CDS_PART_NAME='Q_RES_0402LF-33.2,1%,1/16W,CHIA',
 WATTAGE='1/16W',
 TOLERANCE='1%',
 MATERIAL='CHIP',
 VALUE='33.2',
 PRIM_FILE='W:/<user>/logical/q_res/chips/chips.prt';

PART_NAME
 R223 'Q_RES_0402LF-33.2,1%,1/16W,CHIA':;

SECTION_NUMBER 1
 '@SCM_LIB.SCM(SCH_1):PAGE32_I78@PURE_QUANTA.Q_RES(CHIPS)':
 C_PATH='@scm_lib.scm(sch_1):page32_i78@pure_quanta.q_res(chips)',
 P_PATH='@scm_lib.scm(sch_1):page32_i78@pure_quanta.q_res(chips)',
 PATH='I78',
 DRAWING='@SCM_LIB.SCM(SCH_1):PAGE32',
 PHYS_PAGE='32',
 XY='(-425,1775)',
 ROT='0',
 VER='1',
 PACK_TYPE='0402LF',
 LOCATION='R223',
 CDS_LIB='pure_quanta',
 CDS_PART_NAME='Q_RES_0402LF-33.2,1%,1/16W,CHIA',
 WATTAGE='1/16W',
 TOLERANCE='1%',
 MATERIAL='CHIP',
 VALUE='33.2',
 PRIM_FILE='W:/<user>/logical/q_res/chips/chips.prt';

PART_NAME
 R224 'Q_RES_0402LF-33.2,1%,1/16W,CHIA':;

SECTION_NUMBER 1
 '@SCM_LIB.SCM(SCH_1):PAGE32_I87@PURE_QUANTA.Q_RES(CHIPS)':
 C_PATH='@scm_lib.scm(sch_1):page32_i87@pure_quanta.q_res(chips)',
 P_PATH='@scm_lib.scm(sch_1):page32_i87@pure_quanta.q_res(chips)',
 PATH='I87',
 DRAWING='@SCM_LIB.SCM(SCH_1):PAGE32',
 PHYS_PAGE='32',
 XY='(-425,1675)',
 ROT='0',
 VER='1',
 PACK_TYPE='0402LF',
 LOCATION='R224',
 CDS_LIB='pure_quanta',
 CDS_PART_NAME='Q_RES_0402LF-33.2,1%,1/16W,CHIA',
 WATTAGE='1/16W',
 TOLERANCE='1%',
 MATERIAL='CHIP',
 VALUE='33.2',
 PRIM_FILE='W:/<user>/logical/q_res/chips/chips.prt';

PART_NAME
 R225 'Q_RES_0402LF-100,1%,1/16W,CHIPA':;

SECTION_NUMBER 1
 '@SCM_LIB.SCM(SCH_1):PAGE15_I405@PURE_QUANTA.Q_RES(CHIPS)':
 C_PATH='@scm_lib.scm(sch_1):page15_i405@pure_quanta.q_res(chips)',
 P_PATH='@scm_lib.scm(sch_1):page15_i405@pure_quanta.q_res(chips)',
 PATH='I405',
 DRAWING='@SCM_LIB.SCM(SCH_1):PAGE15',
 PHYS_PAGE='15',
 XY='(4100,3550)',
 ROT='0',
 VER='1',
 PACK_TYPE='0402LF',
 LOCATION='R225',
 CDS_LIB='pure_quanta',
 CDS_PART_NAME='Q_RES_0402LF-100,1%,1/16W,CHIPA',
 WATTAGE='1/16W',
 TOLERANCE='1%',
 MATERIAL='CHIP',
 VALUE='100',
 PRIM_FILE='W:/<user>/logical/q_res/chips/chips.prt';

PART_NAME
 R226 'Q_RES_0402LF-10K,1%,1/16W,CHIPA':;

SECTION_NUMBER 1
 '@SCM_LIB.SCM(SCH_1):PAGE32_I103@PURE_QUANTA.Q_RES(CHIPS)':
 C_PATH='@scm_lib.scm(sch_1):page32_i103@pure_quanta.q_res(chips)',
 P_PATH='@scm_lib.scm(sch_1):page32_i103@pure_quanta.q_res(chips)',
 PATH='I103',
 DRAWING='@SCM_LIB.SCM(SCH_1):PAGE32',
 PHYS_PAGE='32',
 XY='(-200,450)',
 ROT='0',
 VER='1',
 PACK_TYPE='0402LF',
 LOCATION='R226',
 CDS_LIB='pure_quanta',
 CDS_PART_NAME='Q_RES_0402LF-10K,1%,1/16W,CHIPA',
 WATTAGE='1/16W',
 TOLERANCE='1%',
 MATERIAL='CHIP',
 VALUE='10K',
 PRIM_FILE='W:/<user>/logical/q_res/chips/chips.prt';

PART_NAME
 R227 'Q_RES_0402LF-10K,1%,1/16W,CHIPA':;

SECTION_NUMBER 1
 '@SCM_LIB.SCM(SCH_1):PAGE32_I104@PURE_QUANTA.Q_RES(CHIPS)':
 C_PATH='@scm_lib.scm(sch_1):page32_i104@pure_quanta.q_res(chips)',
 P_PATH='@scm_lib.scm(sch_1):page32_i104@pure_quanta.q_res(chips)',
 PATH='I104',
 DRAWING='@SCM_LIB.SCM(SCH_1):PAGE32',
 PHYS_PAGE='32',
 XY='(-200,250)',
 ROT='0',
 VER='1',
 PACK_TYPE='0402LF',
 LOCATION='R227',
 CDS_LIB='pure_quanta',
 CDS_PART_NAME='Q_RES_0402LF-10K,1%,1/16W,CHIPA',
 WATTAGE='1/16W',
 TOLERANCE='1%',
 MATERIAL='CHIP',
 VALUE='10K',
 PRIM_FILE='W:/<user>/logical/q_res/chips/chips.prt';

PART_NAME
 R228 'Q_RES_0402LF-10K,1%,1/16W,EMPTA':;

SECTION_NUMBER 1
 '@SCM_LIB.SCM(SCH_1):PAGE32_I107@PURE_QUANTA.Q_RES(CHIPS)':
 C_PATH='@scm_lib.scm(sch_1):page32_i107@pure_quanta.q_res(chips)',
 P_PATH='@scm_lib.scm(sch_1):page32_i107@pure_quanta.q_res(chips)',
 PATH='I107',
 DRAWING='@SCM_LIB.SCM(SCH_1):PAGE32',
 PHYS_PAGE='32',
 XY='(-200,-350)',
 ROT='0',
 VER='1',
 PACK_TYPE='0402LF',
 LOCATION='R228',
 CDS_LIB='pure_quanta',
 CDS_PART_NAME='Q_RES_0402LF-10K,1%,1/16W,EMPTA',
 WATTAGE='1/16W',
 TOLERANCE='1%',
 MATERIAL='EMPTY',
 VALUE='10K',
 PRIM_FILE='W:/<user>/logical/q_res/chips/chips.prt';

PART_NAME
 R229 'Q_RES_0402LF-4.7K,1%,1/16W,EMPA':;

SECTION_NUMBER 1
 '@SCM_LIB.SCM(SCH_1):PAGE32_I106@PURE_QUANTA.Q_RES(CHIPS)':
 C_PATH='@scm_lib.scm(sch_1):page32_i106@pure_quanta.q_res(chips)',
 P_PATH='@scm_lib.scm(sch_1):page32_i106@pure_quanta.q_res(chips)',
 PATH='I106',
 DRAWING='@SCM_LIB.SCM(SCH_1):PAGE32',
 PHYS_PAGE='32',
 XY='(-200,-225)',
 ROT='0',
 VER='1',
 PACK_TYPE='0402LF',
 LOCATION='R229',
 CDS_LIB='pure_quanta',
 CDS_PART_NAME='Q_RES_0402LF-4.7K,1%,1/16W,EMPA',
 WATTAGE='1/16W',
 TOLERANCE='1%',
 MATERIAL='EMPTY',
 VALUE='4.7K',
 PRIM_FILE='W:/<user>/logical/q_res/chips/chips.prt';

PART_NAME
 R230 'Q_RES_0402LF-10K,1%,1/16W,CHIPA':;

SECTION_NUMBER 1
 '@SCM_LIB.SCM(SCH_1):PAGE32_I105@PURE_QUANTA.Q_RES(CHIPS)':
 C_PATH='@scm_lib.scm(sch_1):page32_i105@pure_quanta.q_res(chips)',
 P_PATH='@scm_lib.scm(sch_1):page32_i105@pure_quanta.q_res(chips)',
 PATH='I105',
 DRAWING='@SCM_LIB.SCM(SCH_1):PAGE32',
 PHYS_PAGE='32',
 XY='(-200,125)',
 ROT='0',
 VER='1',
 PACK_TYPE='0402LF',
 LOCATION='R230',
 CDS_LIB='pure_quanta',
 CDS_PART_NAME='Q_RES_0402LF-10K,1%,1/16W,CHIPA',
 WATTAGE='1/16W',
 TOLERANCE='1%',
 MATERIAL='CHIP',
 VALUE='10K',
 PRIM_FILE='W:/<user>/logical/q_res/chips/chips.prt';

PART_NAME
 R231 'Q_RES_0402LF-0,5%,1/16W,CHIP,CA':;

SECTION_NUMBER 1
 '@SCM_LIB.SCM(SCH_1):PAGE17_I131@PURE_QUANTA.Q_RES(CHIPS)':
 C_PATH='@scm_lib.scm(sch_1):page17_i131@pure_quanta.q_res(chips)',
 P_PATH='@scm_lib.scm(sch_1):page17_i131@pure_quanta.q_res(chips)',
 PATH='I131',
 DRAWING='@SCM_LIB.SCM(SCH_1):PAGE17',
 PHYS_PAGE='17',
 XY='(-975,2050)',
 ROT='0',
 VER='1',
 PACK_TYPE='0402LF',
 LOCATION='R231',
 CDS_LIB='pure_quanta',
 CDS_PART_NAME='Q_RES_0402LF-0,5%,1/16W,CHIP,CA',
 WATTAGE='1/16W',
 TOLERANCE='5%',
 MATERIAL='CHIP',
 VALUE='0',
 PRIM_FILE='W:/<user>/logical/q_res/chips/chips.prt';

PART_NAME
 R232 'Q_RES_0402LF-0,5%,1/16W,EMPTY,A':;

SECTION_NUMBER 1
 '@SCM_LIB.SCM(SCH_1):PAGE17_I136@PURE_QUANTA.Q_RES(CHIPS)':
 C_PATH='@scm_lib.scm(sch_1):page17_i136@pure_quanta.q_res(chips)',
 P_PATH='@scm_lib.scm(sch_1):page17_i136@pure_quanta.q_res(chips)',
 PATH='I136',
 DRAWING='@SCM_LIB.SCM(SCH_1):PAGE17',
 PHYS_PAGE='17',
 XY='(-875,1775)',
 ROT='0',
 VER='1',
 PACK_TYPE='0402LF',
 LOCATION='R232',
 CDS_LIB='pure_quanta',
 CDS_PART_NAME='Q_RES_0402LF-0,5%,1/16W,EMPTY,A',
 WATTAGE='1/16W',
 TOLERANCE='5%',
 MATERIAL='EMPTY',
 VALUE='0',
 PRIM_FILE='W:/<user>/logical/q_res/chips/chips.prt';

PART_NAME
 R233 'Q_RES_0402LF-49.9K,1%,1/16W,CHA':;

SECTION_NUMBER 1
 '@SCM_LIB.SCM(SCH_1):PAGE16_I87@PURE_QUANTA.Q_RES(CHIPS)':
 C_PATH='@scm_lib.scm(sch_1):page16_i87@pure_quanta.q_res(chips)',
 P_PATH='@scm_lib.scm(sch_1):page16_i87@pure_quanta.q_res(chips)',
 PATH='I87',
 DRAWING='@SCM_LIB.SCM(SCH_1):PAGE16',
 PHYS_PAGE='16',
 XY='(-1450,3850)',
 ROT='0',
 VER='1',
 PACK_TYPE='0402LF',
 LOCATION='R233',
 CDS_LIB='pure_quanta',
 CDS_PART_NAME='Q_RES_0402LF-49.9K,1%,1/16W,CHA',
 WATTAGE='1/16W',
 TOLERANCE='1%',
 MATERIAL='CHIP',
 VALUE='49.9K',
 PRIM_FILE='W:/<user>/logical/q_res/chips/chips.prt';

PART_NAME
 R234 'Q_RES_0402LF-49.9K,1%,1/16W,CHA':;

SECTION_NUMBER 1
 '@SCM_LIB.SCM(SCH_1):PAGE16_I86@PURE_QUANTA.Q_RES(CHIPS)':
 C_PATH='@scm_lib.scm(sch_1):page16_i86@pure_quanta.q_res(chips)',
 P_PATH='@scm_lib.scm(sch_1):page16_i86@pure_quanta.q_res(chips)',
 PATH='I86',
 DRAWING='@SCM_LIB.SCM(SCH_1):PAGE16',
 PHYS_PAGE='16',
 XY='(-1450,3600)',
 ROT='0',
 VER='1',
 PACK_TYPE='0402LF',
 LOCATION='R234',
 CDS_LIB='pure_quanta',
 CDS_PART_NAME='Q_RES_0402LF-49.9K,1%,1/16W,CHA',
 WATTAGE='1/16W',
 TOLERANCE='1%',
 MATERIAL='CHIP',
 VALUE='49.9K',
 PRIM_FILE='W:/<user>/logical/q_res/chips/chips.prt';

PART_NAME
 R235 'Q_RES_0402LF-2.74K,1%,1/16W,CHA':;

SECTION_NUMBER 1
 '@SCM_LIB.SCM(SCH_1):PAGE16_I187@PURE_QUANTA.Q_RES(CHIPS)':
 C_PATH='@scm_lib.scm(sch_1):page16_i187@pure_quanta.q_res(chips)',
 P_PATH='@scm_lib.scm(sch_1):page16_i187@pure_quanta.q_res(chips)',
 PATH='I187',
 DRAWING='@SCM_LIB.SCM(SCH_1):PAGE16',
 PHYS_PAGE='16',
 XY='(-1450,3250)',
 ROT='0',
 VER='1',
 PACK_TYPE='0402LF',
 LOCATION='R235',
 CDS_LIB='pure_quanta',
 CDS_PART_NAME='Q_RES_0402LF-2.74K,1%,1/16W,CHA',
 WATTAGE='1/16W',
 TOLERANCE='1%',
 MATERIAL='CHIP',
 VALUE='2.74K',
 PRIM_FILE='W:/<user>/logical/q_res/chips/chips.prt';

PART_NAME
 R236 'Q_RES_0402LF-33.2,1%,1/16W,CHIA':;

SECTION_NUMBER 1
 '@SCM_LIB.SCM(SCH_1):PAGE12_I244@PURE_QUANTA.Q_RES(CHIPS)':
 C_PATH='@scm_lib.scm(sch_1):page12_i244@pure_quanta.q_res(chips)',
 P_PATH='@scm_lib.scm(sch_1):page12_i244@pure_quanta.q_res(chips)',
 PATH='I244',
 DRAWING='@SCM_LIB.SCM(SCH_1):PAGE12',
 PHYS_PAGE='12',
 XY='(-650,250)',
 ROT='0',
 VER='1',
 PACK_TYPE='0402LF',
 LOCATION='R236',
 CDS_LIB='pure_quanta',
 CDS_PART_NAME='Q_RES_0402LF-33.2,1%,1/16W,CHIA',
 WATTAGE='1/16W',
 TOLERANCE='1%',
 MATERIAL='CHIP',
 VALUE='33.2',
 PRIM_FILE='W:/<user>/logical/q_res/chips/chips.prt';

PART_NAME
 R237 'Q_RES_0402LF-33.2,1%,1/16W,CHIA':;

SECTION_NUMBER 1
 '@SCM_LIB.SCM(SCH_1):PAGE13_I156@PURE_QUANTA.Q_RES(CHIPS)':
 C_PATH='@scm_lib.scm(sch_1):page13_i156@pure_quanta.q_res(chips)',
 P_PATH='@scm_lib.scm(sch_1):page13_i156@pure_quanta.q_res(chips)',
 PATH='I156',
 DRAWING='@SCM_LIB.SCM(SCH_1):PAGE13',
 PHYS_PAGE='13',
 XY='(-2125,2225)',
 ROT='0',
 VER='1',
 PACK_TYPE='0402LF',
 LOCATION='R237',
 CDS_LIB='pure_quanta',
 CDS_PART_NAME='Q_RES_0402LF-33.2,1%,1/16W,CHIA',
 WATTAGE='1/16W',
 TOLERANCE='1%',
 MATERIAL='CHIP',
 VALUE='33.2',
 PRIM_FILE='W:/<user>/logical/q_res/chips/chips.prt';

PART_NAME
 R238 'Q_RES_0402LF-4.7K,1%,1/16W,CHIA':;

SECTION_NUMBER 1
 '@SCM_LIB.SCM(SCH_1):PAGE13_I184@PURE_QUANTA.Q_RES(CHIPS)':
 C_PATH='@scm_lib.scm(sch_1):page13_i184@pure_quanta.q_res(chips)',
 P_PATH='@scm_lib.scm(sch_1):page13_i184@pure_quanta.q_res(chips)',
 PATH='I184',
 DRAWING='@SCM_LIB.SCM(SCH_1):PAGE13',
 PHYS_PAGE='13',
 XY='(2750,375)',
 ROT='0',
 VER='1',
 PACK_TYPE='0402LF',
 LOCATION='R238',
 CDS_LIB='pure_quanta',
 CDS_PART_NAME='Q_RES_0402LF-4.7K,1%,1/16W,CHIA',
 WATTAGE='1/16W',
 TOLERANCE='1%',
 MATERIAL='CHIP',
 VALUE='4.7K',
 PRIM_FILE='W:/<user>/logical/q_res/chips/chips.prt';

PART_NAME
 R239 'Q_RES_0402LF-4.7K,1%,1/16W,CHIA':;

SECTION_NUMBER 1
 '@SCM_LIB.SCM(SCH_1):PAGE13_I185@PURE_QUANTA.Q_RES(CHIPS)':
 C_PATH='@scm_lib.scm(sch_1):page13_i185@pure_quanta.q_res(chips)',
 P_PATH='@scm_lib.scm(sch_1):page13_i185@pure_quanta.q_res(chips)',
 PATH='I185',
 DRAWING='@SCM_LIB.SCM(SCH_1):PAGE13',
 PHYS_PAGE='13',
 XY='(2750,325)',
 ROT='0',
 VER='1',
 PACK_TYPE='0402LF',
 LOCATION='R239',
 CDS_LIB='pure_quanta',
 CDS_PART_NAME='Q_RES_0402LF-4.7K,1%,1/16W,CHIA',
 WATTAGE='1/16W',
 TOLERANCE='1%',
 MATERIAL='CHIP',
 VALUE='4.7K',
 PRIM_FILE='W:/<user>/logical/q_res/chips/chips.prt';

PART_NAME
 R240 'Q_RES_0402LF-4.7K,1%,1/16W,CHIA':;

SECTION_NUMBER 1
 '@SCM_LIB.SCM(SCH_1):PAGE13_I187@PURE_QUANTA.Q_RES(CHIPS)':
 C_PATH='@scm_lib.scm(sch_1):page13_i187@pure_quanta.q_res(chips)',
 P_PATH='@scm_lib.scm(sch_1):page13_i187@pure_quanta.q_res(chips)',
 PATH='I187',
 DRAWING='@SCM_LIB.SCM(SCH_1):PAGE13',
 PHYS_PAGE='13',
 XY='(2750,275)',
 ROT='0',
 VER='1',
 PACK_TYPE='0402LF',
 LOCATION='R240',
 CDS_LIB='pure_quanta',
 CDS_PART_NAME='Q_RES_0402LF-4.7K,1%,1/16W,CHIA',
 WATTAGE='1/16W',
 TOLERANCE='1%',
 MATERIAL='CHIP',
 VALUE='4.7K',
 PRIM_FILE='W:/<user>/logical/q_res/chips/chips.prt';

PART_NAME
 R241 'Q_RES_0402LF-4.7K,1%,1/16W,CHIA':;

SECTION_NUMBER 1
 '@SCM_LIB.SCM(SCH_1):PAGE13_I186@PURE_QUANTA.Q_RES(CHIPS)':
 C_PATH='@scm_lib.scm(sch_1):page13_i186@pure_quanta.q_res(chips)',
 P_PATH='@scm_lib.scm(sch_1):page13_i186@pure_quanta.q_res(chips)',
 PATH='I186',
 DRAWING='@SCM_LIB.SCM(SCH_1):PAGE13',
 PHYS_PAGE='13',
 XY='(2750,225)',
 ROT='0',
 VER='1',
 PACK_TYPE='0402LF',
 LOCATION='R241',
 CDS_LIB='pure_quanta',
 CDS_PART_NAME='Q_RES_0402LF-4.7K,1%,1/16W,CHIA',
 WATTAGE='1/16W',
 TOLERANCE='1%',
 MATERIAL='CHIP',
 VALUE='4.7K',
 PRIM_FILE='W:/<user>/logical/q_res/chips/chips.prt';

PART_NAME
 R242 'Q_RES_0402LF-33.2,1%,1/16W,CHIA':;

SECTION_NUMBER 1
 '@SCM_LIB.SCM(SCH_1):PAGE13_I384@PURE_QUANTA.Q_RES(CHIPS)':
 C_PATH='@scm_lib.scm(sch_1):page13_i384@pure_quanta.q_res(chips)',
 P_PATH='@scm_lib.scm(sch_1):page13_i384@pure_quanta.q_res(chips)',
 PATH='I384',
 DRAWING='@SCM_LIB.SCM(SCH_1):PAGE13',
 PHYS_PAGE='13',
 XY='(3275,1325)',
 ROT='0',
 VER='1',
 PACK_TYPE='0402LF',
 LOCATION='R242',
 CDS_LIB='pure_quanta',
 CDS_PART_NAME='Q_RES_0402LF-33.2,1%,1/16W,CHIA',
 WATTAGE='1/16W',
 TOLERANCE='1%',
 MATERIAL='CHIP',
 VALUE='33.2',
 PRIM_FILE='W:/<user>/logical/q_res/chips/chips.prt';

PART_NAME
 R243 'Q_RES_0402LF-33.2,1%,1/16W,CHIA':;

SECTION_NUMBER 1
 '@SCM_LIB.SCM(SCH_1):PAGE10_I293@PURE_QUANTA.Q_RES(CHIPS)':
 C_PATH='@scm_lib.scm(sch_1):page10_i293@pure_quanta.q_res(chips)',
 P_PATH='@scm_lib.scm(sch_1):page10_i293@pure_quanta.q_res(chips)',
 PATH='I293',
 DRAWING='@SCM_LIB.SCM(SCH_1):PAGE10',
 SEC_TYPE='0402LF',
 PHYS_PAGE='10',
 XY='(-10325,-50)',
 ROT='0',
 VER='1',
 PACK_TYPE='0402LF',
 LOCATION='R243',
 SEC='1',
 CDS_LIB='pure_quanta',
 CDS_PART_NAME='Q_RES_0402LF-33.2,1%,1/16W,CHIA',
 WATTAGE='1/16W',
 TOLERANCE='1%',
 MATERIAL='CHIP',
 VALUE='33.2',
 PRIM_FILE='W:/<user>/logical/q_res/chips/chips.prt';

PART_NAME
 R244 'Q_RES_0402LF-1.8K,1%,1/16W,CHIA':;

SECTION_NUMBER 1
 '@SCM_LIB.SCM(SCH_1):PAGE27_I147@PURE_QUANTA.Q_RES(CHIPS)':
 C_PATH='@scm_lib.scm(sch_1):page27_i147@pure_quanta.q_res(chips)',
 P_PATH='@scm_lib.scm(sch_1):page27_i147@pure_quanta.q_res(chips)',
 PATH='I147',
 DRAWING='@SCM_LIB.SCM(SCH_1):PAGE27',
 PHYS_PAGE='27',
 XY='(-3625,4175)',
 ROT='0',
 VER='1',
 PACK_TYPE='0402LF',
 LOCATION='R244',
 CDS_LIB='pure_quanta',
 CDS_PART_NAME='Q_RES_0402LF-1.8K,1%,1/16W,CHIA',
 WATTAGE='1/16W',
 TOLERANCE='1%',
 MATERIAL='CHIP',
 VALUE='1.8K',
 PRIM_FILE='W:/<user>/logical/q_res/chips/chips.prt';

PART_NAME
 R245 'Q_RES_0402LF-1.8K,1%,1/16W,CHIA':;

SECTION_NUMBER 1
 '@SCM_LIB.SCM(SCH_1):PAGE27_I146@PURE_QUANTA.Q_RES(CHIPS)':
 C_PATH='@scm_lib.scm(sch_1):page27_i146@pure_quanta.q_res(chips)',
 P_PATH='@scm_lib.scm(sch_1):page27_i146@pure_quanta.q_res(chips)',
 PATH='I146',
 DRAWING='@SCM_LIB.SCM(SCH_1):PAGE27',
 PHYS_PAGE='27',
 XY='(-3625,4075)',
 ROT='0',
 VER='1',
 PACK_TYPE='0402LF',
 LOCATION='R245',
 CDS_LIB='pure_quanta',
 CDS_PART_NAME='Q_RES_0402LF-1.8K,1%,1/16W,CHIA',
 WATTAGE='1/16W',
 TOLERANCE='1%',
 MATERIAL='CHIP',
 VALUE='1.8K',
 PRIM_FILE='W:/<user>/logical/q_res/chips/chips.prt';

PART_NAME
 R246 'Q_RES_0402LF-2.2K,5%,1/16W,CHIA':;

SECTION_NUMBER 1
 '@SCM_LIB.SCM(SCH_1):PAGE27_I145@PURE_QUANTA.Q_RES(CHIPS)':
 C_PATH='@scm_lib.scm(sch_1):page27_i145@pure_quanta.q_res(chips)',
 P_PATH='@scm_lib.scm(sch_1):page27_i145@pure_quanta.q_res(chips)',
 PATH='I145',
 DRAWING='@SCM_LIB.SCM(SCH_1):PAGE27',
 PHYS_PAGE='27',
 XY='(-3625,3975)',
 ROT='0',
 VER='1',
 PACK_TYPE='0402LF',
 LOCATION='R246',
 CDS_LIB='pure_quanta',
 CDS_PART_NAME='Q_RES_0402LF-2.2K,5%,1/16W,CHIA',
 WATTAGE='1/16W',
 TOLERANCE='5%',
 MATERIAL='CHIP',
 VALUE='2.2K',
 PRIM_FILE='W:/<user>/logical/q_res/chips/chips.prt';

PART_NAME
 R247 'Q_RES_0402LF-2.2K,5%,1/16W,CHIA':;

SECTION_NUMBER 1
 '@SCM_LIB.SCM(SCH_1):PAGE27_I109@PURE_QUANTA.Q_RES(CHIPS)':
 C_PATH='@scm_lib.scm(sch_1):page27_i109@pure_quanta.q_res(chips)',
 P_PATH='@scm_lib.scm(sch_1):page27_i109@pure_quanta.q_res(chips)',
 PATH='I109',
 DRAWING='@SCM_LIB.SCM(SCH_1):PAGE27',
 PHYS_PAGE='27',
 XY='(-3625,3875)',
 ROT='0',
 VER='1',
 PACK_TYPE='0402LF',
 LOCATION='R247',
 CDS_LIB='pure_quanta',
 CDS_PART_NAME='Q_RES_0402LF-2.2K,5%,1/16W,CHIA',
 WATTAGE='1/16W',
 TOLERANCE='5%',
 MATERIAL='CHIP',
 VALUE='2.2K',
 PRIM_FILE='W:/<user>/logical/q_res/chips/chips.prt';

PART_NAME
 R248 'Q_RES_0402LF-2.2K,5%,1/16W,CHIA':;

SECTION_NUMBER 1
 '@SCM_LIB.SCM(SCH_1):PAGE27_I107@PURE_QUANTA.Q_RES(CHIPS)':
 C_PATH='@scm_lib.scm(sch_1):page27_i107@pure_quanta.q_res(chips)',
 P_PATH='@scm_lib.scm(sch_1):page27_i107@pure_quanta.q_res(chips)',
 PATH='I107',
 DRAWING='@SCM_LIB.SCM(SCH_1):PAGE27',
 PHYS_PAGE='27',
 XY='(-3625,3775)',
 ROT='0',
 VER='1',
 PACK_TYPE='0402LF',
 LOCATION='R248',
 CDS_LIB='pure_quanta',
 CDS_PART_NAME='Q_RES_0402LF-2.2K,5%,1/16W,CHIA',
 WATTAGE='1/16W',
 TOLERANCE='5%',
 MATERIAL='CHIP',
 VALUE='2.2K',
 PRIM_FILE='W:/<user>/logical/q_res/chips/chips.prt';

PART_NAME
 R249 'Q_RES_0402LF-2.2K,5%,1/16W,CHIA':;

SECTION_NUMBER 1
 '@SCM_LIB.SCM(SCH_1):PAGE27_I108@PURE_QUANTA.Q_RES(CHIPS)':
 C_PATH='@scm_lib.scm(sch_1):page27_i108@pure_quanta.q_res(chips)',
 P_PATH='@scm_lib.scm(sch_1):page27_i108@pure_quanta.q_res(chips)',
 PATH='I108',
 DRAWING='@SCM_LIB.SCM(SCH_1):PAGE27',
 PHYS_PAGE='27',
 XY='(-3625,3675)',
 ROT='0',
 VER='1',
 PACK_TYPE='0402LF',
 LOCATION='R249',
 CDS_LIB='pure_quanta',
 CDS_PART_NAME='Q_RES_0402LF-2.2K,5%,1/16W,CHIA',
 WATTAGE='1/16W',
 TOLERANCE='5%',
 MATERIAL='CHIP',
 VALUE='2.2K',
 PRIM_FILE='W:/<user>/logical/q_res/chips/chips.prt';

PART_NAME
 R250 'Q_RES_0402LF-402,1%,1/16W,CHIPA':;

SECTION_NUMBER 1
 '@SCM_LIB.SCM(SCH_1):PAGE27_I106@PURE_QUANTA.Q_RES(CHIPS)':
 C_PATH='@scm_lib.scm(sch_1):page27_i106@pure_quanta.q_res(chips)',
 P_PATH='@scm_lib.scm(sch_1):page27_i106@pure_quanta.q_res(chips)',
 PATH='I106',
 DRAWING='@SCM_LIB.SCM(SCH_1):PAGE27',
 PHYS_PAGE='27',
 XY='(-3625,3575)',
 ROT='0',
 VER='1',
 PACK_TYPE='0402LF',
 LOCATION='R250',
 CDS_LIB='pure_quanta',
 CDS_PART_NAME='Q_RES_0402LF-402,1%,1/16W,CHIPA',
 WATTAGE='1/16W',
 TOLERANCE='1%',
 MATERIAL='CHIP',
 VALUE='402',
 PRIM_FILE='W:/<user>/logical/q_res/chips/chips.prt';

PART_NAME
 R251 'Q_RES_0402LF-499,1%,1/16W,CHIPA':;

SECTION_NUMBER 1
 '@SCM_LIB.SCM(SCH_1):PAGE27_I247@PURE_QUANTA.Q_RES(CHIPS)':
 C_PATH='@scm_lib.scm(sch_1):page27_i247@pure_quanta.q_res(chips)',
 P_PATH='@scm_lib.scm(sch_1):page27_i247@pure_quanta.q_res(chips)',
 PATH='I247',
 DRAWING='@SCM_LIB.SCM(SCH_1):PAGE27',
 PHYS_PAGE='27',
 XY='(-3625,3475)',
 ROT='0',
 VER='1',
 PACK_TYPE='0402LF',
 LOCATION='R251',
 CDS_LIB='pure_quanta',
 CDS_PART_NAME='Q_RES_0402LF-499,1%,1/16W,CHIPA',
 WATTAGE='1/16W',
 TOLERANCE='1%',
 MATERIAL='CHIP',
 VALUE='499',
 PRIM_FILE='W:/<user>/logical/q_res/chips/chips.prt';

PART_NAME
 R252 'Q_RES_0402LF-2.2K,5%,1/16W,CHIA':;

SECTION_NUMBER 1
 '@SCM_LIB.SCM(SCH_1):PAGE27_I105@PURE_QUANTA.Q_RES(CHIPS)':
 C_PATH='@scm_lib.scm(sch_1):page27_i105@pure_quanta.q_res(chips)',
 P_PATH='@scm_lib.scm(sch_1):page27_i105@pure_quanta.q_res(chips)',
 PATH='I105',
 DRAWING='@SCM_LIB.SCM(SCH_1):PAGE27',
 PHYS_PAGE='27',
 XY='(-3625,3375)',
 ROT='0',
 VER='1',
 PACK_TYPE='0402LF',
 LOCATION='R252',
 CDS_LIB='pure_quanta',
 CDS_PART_NAME='Q_RES_0402LF-2.2K,5%,1/16W,CHIA',
 WATTAGE='1/16W',
 TOLERANCE='5%',
 MATERIAL='CHIP',
 VALUE='2.2K',
 PRIM_FILE='W:/<user>/logical/q_res/chips/chips.prt';

PART_NAME
 R253 'Q_RES_0402LF-2.2K,5%,1/16W,CHIA':;

SECTION_NUMBER 1
 '@SCM_LIB.SCM(SCH_1):PAGE27_I103@PURE_QUANTA.Q_RES(CHIPS)':
 C_PATH='@scm_lib.scm(sch_1):page27_i103@pure_quanta.q_res(chips)',
 P_PATH='@scm_lib.scm(sch_1):page27_i103@pure_quanta.q_res(chips)',
 PATH='I103',
 DRAWING='@SCM_LIB.SCM(SCH_1):PAGE27',
 PHYS_PAGE='27',
 XY='(-3625,3275)',
 ROT='0',
 VER='1',
 PACK_TYPE='0402LF',
 LOCATION='R253',
 CDS_LIB='pure_quanta',
 CDS_PART_NAME='Q_RES_0402LF-2.2K,5%,1/16W,CHIA',
 WATTAGE='1/16W',
 TOLERANCE='5%',
 MATERIAL='CHIP',
 VALUE='2.2K',
 PRIM_FILE='W:/<user>/logical/q_res/chips/chips.prt';

PART_NAME
 R254 'Q_RES_0402LF-10K,1%,1/16W,CHIPA':;

SECTION_NUMBER 1
 '@SCM_LIB.SCM(SCH_1):PAGE27_I101@PURE_QUANTA.Q_RES(CHIPS)':
 C_PATH='@scm_lib.scm(sch_1):page27_i101@pure_quanta.q_res(chips)',
 P_PATH='@scm_lib.scm(sch_1):page27_i101@pure_quanta.q_res(chips)',
 PATH='I101',
 DRAWING='@SCM_LIB.SCM(SCH_1):PAGE27',
 PHYS_PAGE='27',
 XY='(-3625,3175)',
 ROT='0',
 VER='1',
 PACK_TYPE='0402LF',
 LOCATION='R254',
 CDS_LIB='pure_quanta',
 CDS_PART_NAME='Q_RES_0402LF-10K,1%,1/16W,CHIPA',
 WATTAGE='1/16W',
 TOLERANCE='1%',
 MATERIAL='CHIP',
 VALUE='10K',
 PRIM_FILE='W:/<user>/logical/q_res/chips/chips.prt';

PART_NAME
 R255 'Q_RES_0402LF-10K,1%,1/16W,CHIPA':;

SECTION_NUMBER 1
 '@SCM_LIB.SCM(SCH_1):PAGE27_I102@PURE_QUANTA.Q_RES(CHIPS)':
 C_PATH='@scm_lib.scm(sch_1):page27_i102@pure_quanta.q_res(chips)',
 P_PATH='@scm_lib.scm(sch_1):page27_i102@pure_quanta.q_res(chips)',
 PATH='I102',
 DRAWING='@SCM_LIB.SCM(SCH_1):PAGE27',
 PHYS_PAGE='27',
 XY='(-3625,3075)',
 ROT='0',
 VER='1',
 PACK_TYPE='0402LF',
 LOCATION='R255',
 CDS_LIB='pure_quanta',
 CDS_PART_NAME='Q_RES_0402LF-10K,1%,1/16W,CHIPA',
 WATTAGE='1/16W',
 TOLERANCE='1%',
 MATERIAL='CHIP',
 VALUE='10K',
 PRIM_FILE='W:/<user>/logical/q_res/chips/chips.prt';

PART_NAME
 R256 'Q_RES_0402LF-2.2K,5%,1/16W,CHIA':;

SECTION_NUMBER 1
 '@SCM_LIB.SCM(SCH_1):PAGE27_I100@PURE_QUANTA.Q_RES(CHIPS)':
 C_PATH='@scm_lib.scm(sch_1):page27_i100@pure_quanta.q_res(chips)',
 P_PATH='@scm_lib.scm(sch_1):page27_i100@pure_quanta.q_res(chips)',
 PATH='I100',
 DRAWING='@SCM_LIB.SCM(SCH_1):PAGE27',
 PHYS_PAGE='27',
 XY='(-3625,2975)',
 ROT='0',
 VER='1',
 PACK_TYPE='0402LF',
 LOCATION='R256',
 CDS_LIB='pure_quanta',
 CDS_PART_NAME='Q_RES_0402LF-2.2K,5%,1/16W,CHIA',
 WATTAGE='1/16W',
 TOLERANCE='5%',
 MATERIAL='CHIP',
 VALUE='2.2K',
 PRIM_FILE='W:/<user>/logical/q_res/chips/chips.prt';

PART_NAME
 R257 'Q_RES_0402LF-2.2K,5%,1/16W,CHIA':;

SECTION_NUMBER 1
 '@SCM_LIB.SCM(SCH_1):PAGE27_I99@PURE_QUANTA.Q_RES(CHIPS)':
 C_PATH='@scm_lib.scm(sch_1):page27_i99@pure_quanta.q_res(chips)',
 P_PATH='@scm_lib.scm(sch_1):page27_i99@pure_quanta.q_res(chips)',
 PATH='I99',
 DRAWING='@SCM_LIB.SCM(SCH_1):PAGE27',
 PHYS_PAGE='27',
 XY='(-3625,2875)',
 ROT='0',
 VER='1',
 PACK_TYPE='0402LF',
 LOCATION='R257',
 CDS_LIB='pure_quanta',
 CDS_PART_NAME='Q_RES_0402LF-2.2K,5%,1/16W,CHIA',
 WATTAGE='1/16W',
 TOLERANCE='5%',
 MATERIAL='CHIP',
 VALUE='2.2K',
 PRIM_FILE='W:/<user>/logical/q_res/chips/chips.prt';

PART_NAME
 R258 'Q_RES_0402LF-2.2K,5%,1/16W,CHIA':;

SECTION_NUMBER 1
 '@SCM_LIB.SCM(SCH_1):PAGE27_I98@PURE_QUANTA.Q_RES(CHIPS)':
 C_PATH='@scm_lib.scm(sch_1):page27_i98@pure_quanta.q_res(chips)',
 P_PATH='@scm_lib.scm(sch_1):page27_i98@pure_quanta.q_res(chips)',
 PATH='I98',
 DRAWING='@SCM_LIB.SCM(SCH_1):PAGE27',
 PHYS_PAGE='27',
 XY='(-3625,2775)',
 ROT='0',
 VER='1',
 PACK_TYPE='0402LF',
 LOCATION='R258',
 CDS_LIB='pure_quanta',
 CDS_PART_NAME='Q_RES_0402LF-2.2K,5%,1/16W,CHIA',
 WATTAGE='1/16W',
 TOLERANCE='5%',
 MATERIAL='CHIP',
 VALUE='2.2K',
 PRIM_FILE='W:/<user>/logical/q_res/chips/chips.prt';

PART_NAME
 R259 'Q_RES_0402LF-2.2K,5%,1/16W,CHIA':;

SECTION_NUMBER 1
 '@SCM_LIB.SCM(SCH_1):PAGE27_I96@PURE_QUANTA.Q_RES(CHIPS)':
 C_PATH='@scm_lib.scm(sch_1):page27_i96@pure_quanta.q_res(chips)',
 P_PATH='@scm_lib.scm(sch_1):page27_i96@pure_quanta.q_res(chips)',
 PATH='I96',
 DRAWING='@SCM_LIB.SCM(SCH_1):PAGE27',
 PHYS_PAGE='27',
 XY='(-3625,2675)',
 ROT='0',
 VER='1',
 PACK_TYPE='0402LF',
 LOCATION='R259',
 CDS_LIB='pure_quanta',
 CDS_PART_NAME='Q_RES_0402LF-2.2K,5%,1/16W,CHIA',
 WATTAGE='1/16W',
 TOLERANCE='5%',
 MATERIAL='CHIP',
 VALUE='2.2K',
 PRIM_FILE='W:/<user>/logical/q_res/chips/chips.prt';

PART_NAME
 R260 'Q_RES_0402LF-10K,1%,1/16W,CHIPA':;

SECTION_NUMBER 1
 '@SCM_LIB.SCM(SCH_1):PAGE27_I97@PURE_QUANTA.Q_RES(CHIPS)':
 C_PATH='@scm_lib.scm(sch_1):page27_i97@pure_quanta.q_res(chips)',
 P_PATH='@scm_lib.scm(sch_1):page27_i97@pure_quanta.q_res(chips)',
 PATH='I97',
 DRAWING='@SCM_LIB.SCM(SCH_1):PAGE27',
 PHYS_PAGE='27',
 XY='(-3625,2575)',
 ROT='0',
 VER='1',
 PACK_TYPE='0402LF',
 LOCATION='R260',
 CDS_LIB='pure_quanta',
 CDS_PART_NAME='Q_RES_0402LF-10K,1%,1/16W,CHIPA',
 WATTAGE='1/16W',
 TOLERANCE='1%',
 MATERIAL='CHIP',
 VALUE='10K',
 PRIM_FILE='W:/<user>/logical/q_res/chips/chips.prt';

PART_NAME
 R261 'Q_RES_0402LF-10K,1%,1/16W,CHIPA':;

SECTION_NUMBER 1
 '@SCM_LIB.SCM(SCH_1):PAGE27_I94@PURE_QUANTA.Q_RES(CHIPS)':
 C_PATH='@scm_lib.scm(sch_1):page27_i94@pure_quanta.q_res(chips)',
 P_PATH='@scm_lib.scm(sch_1):page27_i94@pure_quanta.q_res(chips)',
 PATH='I94',
 DRAWING='@SCM_LIB.SCM(SCH_1):PAGE27',
 PHYS_PAGE='27',
 XY='(-3625,2475)',
 ROT='0',
 VER='1',
 PACK_TYPE='0402LF',
 LOCATION='R261',
 CDS_LIB='pure_quanta',
 CDS_PART_NAME='Q_RES_0402LF-10K,1%,1/16W,CHIPA',
 WATTAGE='1/16W',
 TOLERANCE='1%',
 MATERIAL='CHIP',
 VALUE='10K',
 PRIM_FILE='W:/<user>/logical/q_res/chips/chips.prt';

PART_NAME
 R262 'Q_RES_0402LF-10K,1%,1/16W,CHIPA':;

SECTION_NUMBER 1
 '@SCM_LIB.SCM(SCH_1):PAGE27_I93@PURE_QUANTA.Q_RES(CHIPS)':
 C_PATH='@scm_lib.scm(sch_1):page27_i93@pure_quanta.q_res(chips)',
 P_PATH='@scm_lib.scm(sch_1):page27_i93@pure_quanta.q_res(chips)',
 PATH='I93',
 DRAWING='@SCM_LIB.SCM(SCH_1):PAGE27',
 PHYS_PAGE='27',
 XY='(-3625,2375)',
 ROT='0',
 VER='1',
 PACK_TYPE='0402LF',
 LOCATION='R262',
 CDS_LIB='pure_quanta',
 CDS_PART_NAME='Q_RES_0402LF-10K,1%,1/16W,CHIPA',
 WATTAGE='1/16W',
 TOLERANCE='1%',
 MATERIAL='CHIP',
 VALUE='10K',
 PRIM_FILE='W:/<user>/logical/q_res/chips/chips.prt';

PART_NAME
 R263 'Q_RES_0402LF-33.2,1%,1/16W,CHIA':;

SECTION_NUMBER 1
 '@SCM_LIB.SCM(SCH_1):PAGE35_I141@PURE_QUANTA.Q_RES(CHIPS)':
 C_PATH='@scm_lib.scm(sch_1):page35_i141@pure_quanta.q_res(chips)',
 P_PATH='@scm_lib.scm(sch_1):page35_i141@pure_quanta.q_res(chips)',
 PATH='I141',
 DRAWING='@SCM_LIB.SCM(SCH_1):PAGE35',
 PHYS_PAGE='35',
 XY='(-7300,4050)',
 ROT='0',
 VER='1',
 PACK_TYPE='0402LF',
 LOCATION='R263',
 CDS_LIB='pure_quanta',
 CDS_PART_NAME='Q_RES_0402LF-33.2,1%,1/16W,CHIA',
 WATTAGE='1/16W',
 TOLERANCE='1%',
 MATERIAL='CHIP',
 VALUE='33.2',
 PRIM_FILE='W:/<user>/logical/q_res/chips/chips.prt';

PART_NAME
 R264 'Q_RES_0402LF-2.2K,5%,1/16W,CHIA':;

SECTION_NUMBER 1
 '@SCM_LIB.SCM(SCH_1):PAGE27_I89@PURE_QUANTA.Q_RES(CHIPS)':
 C_PATH='@scm_lib.scm(sch_1):page27_i89@pure_quanta.q_res(chips)',
 P_PATH='@scm_lib.scm(sch_1):page27_i89@pure_quanta.q_res(chips)',
 PATH='I89',
 DRAWING='@SCM_LIB.SCM(SCH_1):PAGE27',
 PHYS_PAGE='27',
 XY='(-3625,1775)',
 ROT='0',
 VER='1',
 PACK_TYPE='0402LF',
 LOCATION='R264',
 CDS_LIB='pure_quanta',
 CDS_PART_NAME='Q_RES_0402LF-2.2K,5%,1/16W,CHIA',
 WATTAGE='1/16W',
 TOLERANCE='5%',
 MATERIAL='CHIP',
 VALUE='2.2K',
 PRIM_FILE='W:/<user>/logical/q_res/chips/chips.prt';

PART_NAME
 R265 'Q_RES_0402LF-2.2K,5%,1/16W,CHIA':;

SECTION_NUMBER 1
 '@SCM_LIB.SCM(SCH_1):PAGE27_I88@PURE_QUANTA.Q_RES(CHIPS)':
 C_PATH='@scm_lib.scm(sch_1):page27_i88@pure_quanta.q_res(chips)',
 P_PATH='@scm_lib.scm(sch_1):page27_i88@pure_quanta.q_res(chips)',
 PATH='I88',
 DRAWING='@SCM_LIB.SCM(SCH_1):PAGE27',
 PHYS_PAGE='27',
 XY='(-3625,1675)',
 ROT='0',
 VER='1',
 PACK_TYPE='0402LF',
 LOCATION='R265',
 CDS_LIB='pure_quanta',
 CDS_PART_NAME='Q_RES_0402LF-2.2K,5%,1/16W,CHIA',
 WATTAGE='1/16W',
 TOLERANCE='5%',
 MATERIAL='CHIP',
 VALUE='2.2K',
 PRIM_FILE='W:/<user>/logical/q_res/chips/chips.prt';

PART_NAME
 R266 'Q_RES_0402LF-4.7K,1%,1/16W,EMPA':;

SECTION_NUMBER 1
 '@SCM_LIB.SCM(SCH_1):PAGE27_I95@PURE_QUANTA.Q_RES(CHIPS)':
 C_PATH='@scm_lib.scm(sch_1):page27_i95@pure_quanta.q_res(chips)',
 P_PATH='@scm_lib.scm(sch_1):page27_i95@pure_quanta.q_res(chips)',
 PATH='I95',
 DRAWING='@SCM_LIB.SCM(SCH_1):PAGE27',
 PHYS_PAGE='27',
 XY='(-3625,1350)',
 ROT='0',
 VER='1',
 PACK_TYPE='0402LF',
 LOCATION='R266',
 CDS_LIB='pure_quanta',
 CDS_PART_NAME='Q_RES_0402LF-4.7K,1%,1/16W,EMPA',
 WATTAGE='1/16W',
 TOLERANCE='1%',
 MATERIAL='EMPTY',
 VALUE='4.7K',
 PRIM_FILE='W:/<user>/logical/q_res/chips/chips.prt';

PART_NAME
 R267 'Q_RES_0402LF-4.7K,1%,1/16W,EMPA':;

SECTION_NUMBER 1
 '@SCM_LIB.SCM(SCH_1):PAGE27_I85@PURE_QUANTA.Q_RES(CHIPS)':
 C_PATH='@scm_lib.scm(sch_1):page27_i85@pure_quanta.q_res(chips)',
 P_PATH='@scm_lib.scm(sch_1):page27_i85@pure_quanta.q_res(chips)',
 PATH='I85',
 DRAWING='@SCM_LIB.SCM(SCH_1):PAGE27',
 PHYS_PAGE='27',
 XY='(-3625,1275)',
 ROT='0',
 VER='1',
 PACK_TYPE='0402LF',
 LOCATION='R267',
 CDS_LIB='pure_quanta',
 CDS_PART_NAME='Q_RES_0402LF-4.7K,1%,1/16W,EMPA',
 WATTAGE='1/16W',
 TOLERANCE='1%',
 MATERIAL='EMPTY',
 VALUE='4.7K',
 PRIM_FILE='W:/<user>/logical/q_res/chips/chips.prt';

PART_NAME
 R268 'Q_RES_0402LF-4.7K,1%,1/16W,CHIA':;

SECTION_NUMBER 1
 '@SCM_LIB.SCM(SCH_1):PAGE27_I86@PURE_QUANTA.Q_RES(CHIPS)':
 C_PATH='@scm_lib.scm(sch_1):page27_i86@pure_quanta.q_res(chips)',
 P_PATH='@scm_lib.scm(sch_1):page27_i86@pure_quanta.q_res(chips)',
 PATH='I86',
 DRAWING='@SCM_LIB.SCM(SCH_1):PAGE27',
 PHYS_PAGE='27',
 XY='(-3625,1200)',
 ROT='0',
 VER='1',
 PACK_TYPE='0402LF',
 LOCATION='R268',
 CDS_LIB='pure_quanta',
 CDS_PART_NAME='Q_RES_0402LF-4.7K,1%,1/16W,CHIA',
 WATTAGE='1/16W',
 TOLERANCE='1%',
 MATERIAL='CHIP',
 VALUE='4.7K',
 PRIM_FILE='W:/<user>/logical/q_res/chips/chips.prt';

PART_NAME
 R269 'Q_RES_0402LF-4.7K,1%,1/16W,CHIA':;

SECTION_NUMBER 1
 '@SCM_LIB.SCM(SCH_1):PAGE27_I84@PURE_QUANTA.Q_RES(CHIPS)':
 C_PATH='@scm_lib.scm(sch_1):page27_i84@pure_quanta.q_res(chips)',
 P_PATH='@scm_lib.scm(sch_1):page27_i84@pure_quanta.q_res(chips)',
 PATH='I84',
 DRAWING='@SCM_LIB.SCM(SCH_1):PAGE27',
 PHYS_PAGE='27',
 XY='(-3625,1125)',
 ROT='0',
 VER='1',
 PACK_TYPE='0402LF',
 LOCATION='R269',
 CDS_LIB='pure_quanta',
 CDS_PART_NAME='Q_RES_0402LF-4.7K,1%,1/16W,CHIA',
 WATTAGE='1/16W',
 TOLERANCE='1%',
 MATERIAL='CHIP',
 VALUE='4.7K',
 PRIM_FILE='W:/<user>/logical/q_res/chips/chips.prt';

PART_NAME
 R270 'Q_RES_0402LF-33.2,1%,1/16W,CHIA':;

SECTION_NUMBER 1
 '@SCM_LIB.SCM(SCH_1):PAGE34_I164@PURE_QUANTA.Q_RES(CHIPS)':
 C_PATH='@scm_lib.scm(sch_1):page34_i164@pure_quanta.q_res(chips)',
 P_PATH='@scm_lib.scm(sch_1):page34_i164@pure_quanta.q_res(chips)',
 PATH='I164',
 DRAWING='@SCM_LIB.SCM(SCH_1):PAGE34',
 PHYS_PAGE='34',
 XY='(-2550,4600)',
 ROT='0',
 VER='1',
 PACK_TYPE='0402LF',
 LOCATION='R270',
 CDS_LIB='pure_quanta',
 CDS_PART_NAME='Q_RES_0402LF-33.2,1%,1/16W,CHIA',
 WATTAGE='1/16W',
 TOLERANCE='1%',
 MATERIAL='CHIP',
 VALUE='33.2',
 PRIM_FILE='W:/<user>/logical/q_res/chips/chips.prt';

PART_NAME
 R271 'Q_RES_0402LF-0,5%,1/16W,CHIP,CA':;

SECTION_NUMBER 1
 '@SCM_LIB.SCM(SCH_1):PAGE35_I88@PURE_QUANTA.Q_RES(CHIPS)':
 C_PATH='@scm_lib.scm(sch_1):page35_i88@pure_quanta.q_res(chips)',
 P_PATH='@scm_lib.scm(sch_1):page35_i88@pure_quanta.q_res(chips)',
 PATH='I88',
 DRAWING='@SCM_LIB.SCM(SCH_1):PAGE35',
 SEC_TYPE='0402LF',
 PHYS_PAGE='35',
 XY='(-7300,4600)',
 ROT='0',
 VER='1',
 PACK_TYPE='0402LF',
 LOCATION='R271',
 SEC='1',
 CDS_LIB='pure_quanta',
 CDS_PART_NAME='Q_RES_0402LF-0,5%,1/16W,CHIP,CA',
 WATTAGE='1/16W',
 TOLERANCE='5%',
 MATERIAL='CHIP',
 VALUE='0',
 PRIM_FILE='W:/<user>/logical/q_res/chips/chips.prt';

PART_NAME
 R272 'Q_RES_0402LF-0,5%,1/16W,CHIP,CA':;

SECTION_NUMBER 1
 '@SCM_LIB.SCM(SCH_1):PAGE34_I165@PURE_QUANTA.Q_RES(CHIPS)':
 C_PATH='@scm_lib.scm(sch_1):page34_i165@pure_quanta.q_res(chips)',
 P_PATH='@scm_lib.scm(sch_1):page34_i165@pure_quanta.q_res(chips)',
 PATH='I165',
 DRAWING='@SCM_LIB.SCM(SCH_1):PAGE34',
 PHYS_PAGE='34',
 XY='(-2725,5100)',
 ROT='0',
 VER='1',
 PACK_TYPE='0402LF',
 LOCATION='R272',
 CDS_LIB='pure_quanta',
 CDS_PART_NAME='Q_RES_0402LF-0,5%,1/16W,CHIP,CA',
 WATTAGE='1/16W',
 TOLERANCE='5%',
 MATERIAL='CHIP',
 VALUE='0',
 PRIM_FILE='W:/<user>/logical/q_res/chips/chips.prt';

PART_NAME
 R273 'Q_RES_0402LF-100K,1%,1/16W,CHIA':;

SECTION_NUMBER 1
 '@SCM_LIB.SCM(SCH_1):PAGE13_I340@PURE_QUANTA.Q_RES(CHIPS)':
 C_PATH='@scm_lib.scm(sch_1):page13_i340@pure_quanta.q_res(chips)',
 P_PATH='@scm_lib.scm(sch_1):page13_i340@pure_quanta.q_res(chips)',
 PATH='I340',
 DRAWING='@SCM_LIB.SCM(SCH_1):PAGE13',
 SEC_TYPE='0402LF',
 PHYS_PAGE='13',
 XY='(-2275,1025)',
 ROT='2',
 VER='1',
 PACK_TYPE='0402LF',
 LOCATION='R273',
 SEC='1',
 CDS_LIB='pure_quanta',
 CDS_PART_NAME='Q_RES_0402LF-100K,1%,1/16W,CHIA',
 WATTAGE='1/16W',
 TOLERANCE='1%',
 MATERIAL='CHIP',
 VALUE='100K',
 PRIM_FILE='W:/<user>/logical/q_res/chips/chips.prt';

PART_NAME
 R274 'Q_RES_0402LF-100K,1%,1/16W,EMPA':;

SECTION_NUMBER 1
 '@SCM_LIB.SCM(SCH_1):PAGE29_I157@PURE_QUANTA.Q_RES(CHIPS)':
 C_PATH='@scm_lib.scm(sch_1):page29_i157@pure_quanta.q_res(chips)',
 P_PATH='@scm_lib.scm(sch_1):page29_i157@pure_quanta.q_res(chips)',
 PATH='I157',
 DRAWING='@SCM_LIB.SCM(SCH_1):PAGE29',
 PHYS_PAGE='29',
 XY='(4225,3800)',
 ROT='0',
 VER='2',
 PACK_TYPE='0402LF',
 LOCATION='R274',
 CDS_LIB='pure_quanta',
 CDS_PART_NAME='Q_RES_0402LF-100K,1%,1/16W,EMPA',
 WATTAGE='1/16W',
 TOLERANCE='1%',
 MATERIAL='EMPTY',
 VALUE='100K',
 PRIM_FILE='W:/<user>/logical/q_res/chips/chips.prt';

PART_NAME
 R275 'Q_RES_0402LF-0,5%,1/16W,CHIP,CA':;

SECTION_NUMBER 1
 '@SCM_LIB.SCM(SCH_1):PAGE54_I99@PURE_QUANTA.Q_RES(CHIPS)':
 C_PATH='@scm_lib.scm(sch_1):page54_i99@pure_quanta.q_res(chips)',
 P_PATH='@scm_lib.scm(sch_1):page54_i99@pure_quanta.q_res(chips)',
 PATH='I99',
 DRAWING='@SCM_LIB.SCM(SCH_1):PAGE54',
 PHYS_PAGE='54',
 XY='(-2025,1625)',
 ROT='0',
 VER='1',
 PACK_TYPE='0402LF',
 LOCATION='R275',
 CDS_LIB='pure_quanta',
 CDS_PART_NAME='Q_RES_0402LF-0,5%,1/16W,CHIP,CA',
 WATTAGE='1/16W',
 TOLERANCE='5%',
 MATERIAL='CHIP',
 VALUE='0',
 PRIM_FILE='W:/<user>/logical/q_res/chips/chips.prt';

PART_NAME
 R276 'Q_RES_0402LF-0,5%,1/16W,CHIP,CA':;

SECTION_NUMBER 1
 '@SCM_LIB.SCM(SCH_1):PAGE55_I50@PURE_QUANTA.Q_RES(CHIPS)':
 C_PATH='@scm_lib.scm(sch_1):page55_i50@pure_quanta.q_res(chips)',
 P_PATH='@scm_lib.scm(sch_1):page55_i50@pure_quanta.q_res(chips)',
 PATH='I50',
 DRAWING='@SCM_LIB.SCM(SCH_1):PAGE55',
 PHYS_PAGE='55',
 XY='(1750,1075)',
 ROT='0',
 VER='1',
 PACK_TYPE='0402LF',
 LOCATION='R276',
 CDS_LIB='pure_quanta',
 CDS_PART_NAME='Q_RES_0402LF-0,5%,1/16W,CHIP,CA',
 WATTAGE='1/16W',
 TOLERANCE='5%',
 MATERIAL='CHIP',
 VALUE='0',
 PRIM_FILE='W:/<user>/logical/q_res/chips/chips.prt';

PART_NAME
 R277 'Q_RES_0402LF-0,5%,1/16W,CHIP,CA':;

SECTION_NUMBER 1
 '@SCM_LIB.SCM(SCH_1):PAGE56_I54@PURE_QUANTA.Q_RES(CHIPS)':
 C_PATH='@scm_lib.scm(sch_1):page56_i54@pure_quanta.q_res(chips)',
 P_PATH='@scm_lib.scm(sch_1):page56_i54@pure_quanta.q_res(chips)',
 PATH='I54',
 DRAWING='@SCM_LIB.SCM(SCH_1):PAGE56',
 PHYS_PAGE='56',
 XY='(-100,825)',
 ROT='0',
 VER='1',
 PACK_TYPE='0402LF',
 LOCATION='R277',
 CDS_LIB='pure_quanta',
 CDS_PART_NAME='Q_RES_0402LF-0,5%,1/16W,CHIP,CA',
 WATTAGE='1/16W',
 TOLERANCE='5%',
 MATERIAL='CHIP',
 VALUE='0',
 PRIM_FILE='W:/<user>/logical/q_res/chips/chips.prt';

PART_NAME
 R278 'Q_RES_0402LF-0,5%,1/16W,EMPTY,A':;

SECTION_NUMBER 1
 '@SCM_LIB.SCM(SCH_1):PAGE17_I101@PURE_QUANTA.Q_RES(CHIPS)':
 C_PATH='@scm_lib.scm(sch_1):page17_i101@pure_quanta.q_res(chips)',
 P_PATH='@scm_lib.scm(sch_1):page17_i101@pure_quanta.q_res(chips)',
 PATH='I101',
 DRAWING='@SCM_LIB.SCM(SCH_1):PAGE17',
 PHYS_PAGE='17',
 XY='(3350,3925)',
 ROT='0',
 VER='1',
 PACK_TYPE='0402LF',
 LOCATION='R278',
 CDS_LIB='pure_quanta',
 CDS_PART_NAME='Q_RES_0402LF-0,5%,1/16W,EMPTY,A',
 WATTAGE='1/16W',
 TOLERANCE='5%',
 MATERIAL='EMPTY',
 VALUE='0',
 PRIM_FILE='W:/<user>/logical/q_res/chips/chips.prt';

PART_NAME
 R279 'Q_RES_0402LF-0,5%,1/16W,CHIP,CA':;

SECTION_NUMBER 1
 '@SCM_LIB.SCM(SCH_1):PAGE17_I95@PURE_QUANTA.Q_RES(CHIPS)':
 C_PATH='@scm_lib.scm(sch_1):page17_i95@pure_quanta.q_res(chips)',
 P_PATH='@scm_lib.scm(sch_1):page17_i95@pure_quanta.q_res(chips)',
 PATH='I95',
 DRAWING='@SCM_LIB.SCM(SCH_1):PAGE17',
 PHYS_PAGE='17',
 XY='(3350,3625)',
 ROT='0',
 VER='1',
 PACK_TYPE='0402LF',
 LOCATION='R279',
 CDS_LIB='pure_quanta',
 CDS_PART_NAME='Q_RES_0402LF-0,5%,1/16W,CHIP,CA',
 WATTAGE='1/16W',
 TOLERANCE='5%',
 MATERIAL='CHIP',
 VALUE='0',
 PRIM_FILE='W:/<user>/logical/q_res/chips/chips.prt';

PART_NAME
 R280 'Q_RES_0402LF-0,5%,1/16W,EMPTY,A':;

SECTION_NUMBER 1
 '@SCM_LIB.SCM(SCH_1):PAGE17_I94@PURE_QUANTA.Q_RES(CHIPS)':
 C_PATH='@scm_lib.scm(sch_1):page17_i94@pure_quanta.q_res(chips)',
 P_PATH='@scm_lib.scm(sch_1):page17_i94@pure_quanta.q_res(chips)',
 PATH='I94',
 DRAWING='@SCM_LIB.SCM(SCH_1):PAGE17',
 PHYS_PAGE='17',
 XY='(3350,3175)',
 ROT='0',
 VER='1',
 PACK_TYPE='0402LF',
 LOCATION='R280',
 CDS_LIB='pure_quanta',
 CDS_PART_NAME='Q_RES_0402LF-0,5%,1/16W,EMPTY,A',
 WATTAGE='1/16W',
 TOLERANCE='5%',
 MATERIAL='EMPTY',
 VALUE='0',
 PRIM_FILE='W:/<user>/logical/q_res/chips/chips.prt';

PART_NAME
 R281 'Q_RES_0402LF-0,5%,1/16W,CHIP,CA':;

SECTION_NUMBER 1
 '@SCM_LIB.SCM(SCH_1):PAGE17_I92@PURE_QUANTA.Q_RES(CHIPS)':
 C_PATH='@scm_lib.scm(sch_1):page17_i92@pure_quanta.q_res(chips)',
 P_PATH='@scm_lib.scm(sch_1):page17_i92@pure_quanta.q_res(chips)',
 PATH='I92',
 DRAWING='@SCM_LIB.SCM(SCH_1):PAGE17',
 PHYS_PAGE='17',
 XY='(3350,2875)',
 ROT='0',
 VER='1',
 PACK_TYPE='0402LF',
 LOCATION='R281',
 CDS_LIB='pure_quanta',
 CDS_PART_NAME='Q_RES_0402LF-0,5%,1/16W,CHIP,CA',
 WATTAGE='1/16W',
 TOLERANCE='5%',
 MATERIAL='CHIP',
 VALUE='0',
 PRIM_FILE='W:/<user>/logical/q_res/chips/chips.prt';

PART_NAME
 R282 'Q_RES_0402LF-0,5%,1/16W,CHIP,CA':;

SECTION_NUMBER 1
 '@SCM_LIB.SCM(SCH_1):PAGE22_I100@PURE_QUANTA.Q_RES(CHIPS)':
 C_PATH='@scm_lib.scm(sch_1):page22_i100@pure_quanta.q_res(chips)',
 P_PATH='@scm_lib.scm(sch_1):page22_i100@pure_quanta.q_res(chips)',
 PATH='I100',
 DRAWING='@SCM_LIB.SCM(SCH_1):PAGE22',
 PHYS_PAGE='22',
 XY='(-3700,2350)',
 ROT='0',
 VER='2',
 PACK_TYPE='0402LF',
 LOCATION='R282',
 CDS_LIB='pure_quanta',
 CDS_PART_NAME='Q_RES_0402LF-0,5%,1/16W,CHIP,CA',
 WATTAGE='1/16W',
 TOLERANCE='5%',
 MATERIAL='CHIP',
 VALUE='0',
 PRIM_FILE='W:/<user>/logical/q_res/chips/chips.prt';

PART_NAME
 R283 'Q_RES_0402LF-75,1%,1/16W,CHIP,A':;

SECTION_NUMBER 1
 '@SCM_LIB.SCM(SCH_1):PAGE49_I88@PURE_QUANTA.Q_RES(CHIPS)':
 C_PATH='@scm_lib.scm(sch_1):page49_i88@pure_quanta.q_res(chips)',
 P_PATH='@scm_lib.scm(sch_1):page49_i88@pure_quanta.q_res(chips)',
 PATH='I88',
 DRAWING='@SCM_LIB.SCM(SCH_1):PAGE49',
 PHYS_PAGE='49',
 XY='(-2275,2925)',
 ROT='0',
 VER='1',
 PACK_TYPE='0402LF',
 LOCATION='R283',
 CDS_LIB='pure_quanta',
 CDS_PART_NAME='Q_RES_0402LF-75,1%,1/16W,CHIP,A',
 WATTAGE='1/16W',
 TOLERANCE='1%',
 MATERIAL='CHIP',
 VALUE='75',
 PRIM_FILE='W:/<user>/logical/q_res/chips/chips.prt';

PART_NAME
 R284 'Q_RES_0402LF-75,1%,1/16W,CHIP,A':;

SECTION_NUMBER 1
 '@SCM_LIB.SCM(SCH_1):PAGE49_I89@PURE_QUANTA.Q_RES(CHIPS)':
 C_PATH='@scm_lib.scm(sch_1):page49_i89@pure_quanta.q_res(chips)',
 P_PATH='@scm_lib.scm(sch_1):page49_i89@pure_quanta.q_res(chips)',
 PATH='I89',
 DRAWING='@SCM_LIB.SCM(SCH_1):PAGE49',
 PHYS_PAGE='49',
 XY='(-2275,2450)',
 ROT='0',
 VER='1',
 PACK_TYPE='0402LF',
 LOCATION='R284',
 CDS_LIB='pure_quanta',
 CDS_PART_NAME='Q_RES_0402LF-75,1%,1/16W,CHIP,A',
 WATTAGE='1/16W',
 TOLERANCE='1%',
 MATERIAL='CHIP',
 VALUE='75',
 PRIM_FILE='W:/<user>/logical/q_res/chips/chips.prt';

PART_NAME
 R285 'Q_RES_0402LF-4.7K,1%,1/16W,CHIA':;

SECTION_NUMBER 1
 '@SCM_LIB.SCM(SCH_1):PAGE32_I141@PURE_QUANTA.Q_RES(CHIPS)':
 C_PATH='@scm_lib.scm(sch_1):page32_i141@pure_quanta.q_res(chips)',
 P_PATH='@scm_lib.scm(sch_1):page32_i141@pure_quanta.q_res(chips)',
 PATH='I141',
 DRAWING='@SCM_LIB.SCM(SCH_1):PAGE32',
 PHYS_PAGE='32',
 XY='(-575,4050)',
 ROT='0',
 VER='1',
 PACK_TYPE='0402LF',
 CDS_LIB='pure_quanta',
 CDS_PART_NAME='Q_RES_0402LF-4.7K,1%,1/16W,CHIA',
 WATTAGE='1/16W',
 TOLERANCE='1%',
 MATERIAL='CHIP',
 VALUE='4.7K',
 PRIM_FILE='W:/<user>/logical/q_res/chips/chips.prt';

PART_NAME
 R286 'Q_RES_0402LF-316,1%,1/16W,CHIPA':;

SECTION_NUMBER 1
 '@SCM_LIB.SCM(SCH_1):PAGE50_I224@PURE_QUANTA.Q_RES(CHIPS)':
 C_PATH='@scm_lib.scm(sch_1):page50_i224@pure_quanta.q_res(chips)',
 P_PATH='@scm_lib.scm(sch_1):page50_i224@pure_quanta.q_res(chips)',
 PATH='I224',
 DRAWING='@SCM_LIB.SCM(SCH_1):PAGE50',
 PHYS_PAGE='50',
 XY='(-25,1625)',
 ROT='0',
 VER='1',
 PACK_TYPE='0402LF',
 CDS_LIB='pure_quanta',
 CDS_PART_NAME='Q_RES_0402LF-316,1%,1/16W,CHIPA',
 WATTAGE='1/16W',
 TOLERANCE='1%',
 MATERIAL='CHIP',
 VALUE='316',
 PRIM_FILE='W:/<user>/logical/q_res/chips/chips.prt';

PART_NAME
 R287 'Q_RES_0402LF-499,1%,1/16W,CHIPA':;

SECTION_NUMBER 1
 '@SCM_LIB.SCM(SCH_1):PAGE22_I5@PURE_QUANTA.Q_RES(CHIPS)':
 C_PATH='@scm_lib.scm(sch_1):page22_i5@pure_quanta.q_res(chips)',
 P_PATH='@scm_lib.scm(sch_1):page22_i5@pure_quanta.q_res(chips)',
 PATH='I5',
 DRAWING='@SCM_LIB.SCM(SCH_1):PAGE22',
 PHYS_PAGE='22',
 XY='(-575,4400)',
 ROT='0',
 VER='2',
 PACK_TYPE='0402LF',
 LOCATION='R287',
 CDS_LIB='pure_quanta',
 CDS_PART_NAME='Q_RES_0402LF-499,1%,1/16W,CHIPA',
 WATTAGE='1/16W',
 TOLERANCE='1%',
 MATERIAL='CHIP',
 VALUE='499',
 PRIM_FILE='W:/<user>/logical/q_res/chips/chips.prt';

PART_NAME
 R288 'Q_RES_0402LF-10K,1%,1/16W,CHIPA':;

SECTION_NUMBER 1
 '@SCM_LIB.SCM(SCH_1):PAGE36_I50@PURE_QUANTA.Q_RES(CHIPS)':
 C_PATH='@scm_lib.scm(sch_1):page36_i50@pure_quanta.q_res(chips)',
 P_PATH='@scm_lib.scm(sch_1):page36_i50@pure_quanta.q_res(chips)',
 PATH='I50',
 DRAWING='@SCM_LIB.SCM(SCH_1):PAGE36',
 PHYS_PAGE='36',
 XY='(-2750,3700)',
 ROT='0',
 VER='2',
 PACK_TYPE='0402LF',
 CDS_LIB='pure_quanta',
 CDS_PART_NAME='Q_RES_0402LF-10K,1%,1/16W,CHIPA',
 WATTAGE='1/16W',
 TOLERANCE='1%',
 MATERIAL='CHIP',
 VALUE='10K',
 PRIM_FILE='W:/<user>/logical/q_res/chips/chips.prt';

PART_NAME
 R289 'Q_RES_0402LF-10K,1%,1/16W,CHIPA':;

SECTION_NUMBER 1
 '@SCM_LIB.SCM(SCH_1):PAGE22_I7@PURE_QUANTA.Q_RES(CHIPS)':
 C_PATH='@scm_lib.scm(sch_1):page22_i7@pure_quanta.q_res(chips)',
 P_PATH='@scm_lib.scm(sch_1):page22_i7@pure_quanta.q_res(chips)',
 PATH='I7',
 DRAWING='@SCM_LIB.SCM(SCH_1):PAGE22',
 PHYS_PAGE='22',
 XY='(225,4400)',
 ROT='0',
 VER='2',
 PACK_TYPE='0402LF',
 LOCATION='R289',
 CDS_LIB='pure_quanta',
 CDS_PART_NAME='Q_RES_0402LF-10K,1%,1/16W,CHIPA',
 WATTAGE='1/16W',
 TOLERANCE='1%',
 MATERIAL='CHIP',
 VALUE='10K',
 PRIM_FILE='W:/<user>/logical/q_res/chips/chips.prt';

PART_NAME
 R290 'Q_RES_0402LF-47K,1%,1/16W,CHIPA':;

SECTION_NUMBER 1
 '@SCM_LIB.SCM(SCH_1):PAGE22_I8@PURE_QUANTA.Q_RES(CHIPS)':
 C_PATH='@scm_lib.scm(sch_1):page22_i8@pure_quanta.q_res(chips)',
 P_PATH='@scm_lib.scm(sch_1):page22_i8@pure_quanta.q_res(chips)',
 PATH='I8',
 DRAWING='@SCM_LIB.SCM(SCH_1):PAGE22',
 PHYS_PAGE='22',
 XY='(3225,3750)',
 ROT='0',
 VER='1',
 PACK_TYPE='0402LF',
 LOCATION='R290',
 CDS_LIB='pure_quanta',
 CDS_PART_NAME='Q_RES_0402LF-47K,1%,1/16W,CHIPA',
 WATTAGE='1/16W',
 TOLERANCE='1%',
 MATERIAL='CHIP',
 VALUE='47K',
 PRIM_FILE='W:/<user>/logical/q_res/chips/chips.prt';

PART_NAME
 R291 'Q_RES_0402LF-4.7K,1%,1/16W,CHIA':;

SECTION_NUMBER 1
 '@SCM_LIB.SCM(SCH_1):PAGE22_I9@PURE_QUANTA.Q_RES(CHIPS)':
 C_PATH='@scm_lib.scm(sch_1):page22_i9@pure_quanta.q_res(chips)',
 P_PATH='@scm_lib.scm(sch_1):page22_i9@pure_quanta.q_res(chips)',
 PATH='I9',
 DRAWING='@SCM_LIB.SCM(SCH_1):PAGE22',
 PHYS_PAGE='22',
 XY='(4000,4050)',
 ROT='0',
 VER='2',
 PACK_TYPE='0402LF',
 LOCATION='R291',
 CDS_LIB='pure_quanta',
 CDS_PART_NAME='Q_RES_0402LF-4.7K,1%,1/16W,CHIA',
 WATTAGE='1/16W',
 TOLERANCE='1%',
 MATERIAL='CHIP',
 VALUE='4.7K',
 PRIM_FILE='W:/<user>/logical/q_res/chips/chips.prt';

PART_NAME
 R292 'Q_RES_0402LF-0,5%,1/16W,CHIP,CA':;

SECTION_NUMBER 1
 '@SCM_LIB.SCM(SCH_1):PAGE51_I51@PURE_QUANTA.Q_RES(CHIPS)':
 C_PATH='@scm_lib.scm(sch_1):page51_i51@pure_quanta.q_res(chips)',
 P_PATH='@scm_lib.scm(sch_1):page51_i51@pure_quanta.q_res(chips)',
 PATH='I51',
 DRAWING='@SCM_LIB.SCM(SCH_1):PAGE51',
 PHYS_PAGE='51',
 XY='(4275,1175)',
 ROT='0',
 VER='1',
 PACK_TYPE='0402LF',
 LOCATION='R292',
 CDS_LIB='pure_quanta',
 CDS_PART_NAME='Q_RES_0402LF-0,5%,1/16W,CHIP,CA',
 WATTAGE='1/16W',
 TOLERANCE='5%',
 MATERIAL='CHIP',
 VALUE='0',
 PRIM_FILE='W:/<user>/logical/q_res/chips/chips.prt';

PART_NAME
 R293 'Q_RES_0402LF-0,5%,1/16W,CHIP,CA':;

SECTION_NUMBER 1
 '@SCM_LIB.SCM(SCH_1):PAGE52_I95@PURE_QUANTA.Q_RES(CHIPS)':
 C_PATH='@scm_lib.scm(sch_1):page52_i95@pure_quanta.q_res(chips)',
 P_PATH='@scm_lib.scm(sch_1):page52_i95@pure_quanta.q_res(chips)',
 PATH='I95',
 DRAWING='@SCM_LIB.SCM(SCH_1):PAGE52',
 PHYS_PAGE='52',
 XY='(2975,1825)',
 ROT='0',
 VER='1',
 PACK_TYPE='0402LF',
 LOCATION='R293',
 CDS_LIB='pure_quanta',
 CDS_PART_NAME='Q_RES_0402LF-0,5%,1/16W,CHIP,CA',
 WATTAGE='1/16W',
 TOLERANCE='5%',
 MATERIAL='CHIP',
 VALUE='0',
 PRIM_FILE='W:/<user>/logical/q_res/chips/chips.prt';

PART_NAME
 R294 'Q_RES_0402LF-0,5%,1/16W,CHIP,CA':;

SECTION_NUMBER 1
 '@SCM_LIB.SCM(SCH_1):PAGE28_I108@PURE_QUANTA.Q_RES(CHIPS)':
 C_PATH='@scm_lib.scm(sch_1):page28_i108@pure_quanta.q_res(chips)',
 P_PATH='@scm_lib.scm(sch_1):page28_i108@pure_quanta.q_res(chips)',
 PATH='I108',
 DRAWING='@SCM_LIB.SCM(SCH_1):PAGE28',
 PHYS_PAGE='28',
 XY='(-1125,2125)',
 ROT='0',
 VER='1',
 PACK_TYPE='0402LF',
 LOCATION='R294',
 CDS_LIB='pure_quanta',
 CDS_PART_NAME='Q_RES_0402LF-0,5%,1/16W,CHIP,CA',
 WATTAGE='1/16W',
 TOLERANCE='5%',
 MATERIAL='CHIP',
 VALUE='0',
 PRIM_FILE='W:/<user>/logical/q_res/chips/chips.prt';

PART_NAME
 R295 'Q_RES_0402LF-10K,1%,1/16W,CHIPA':;

SECTION_NUMBER 1
 '@SCM_LIB.SCM(SCH_1):PAGE28_I113@PURE_QUANTA.Q_RES(CHIPS)':
 C_PATH='@scm_lib.scm(sch_1):page28_i113@pure_quanta.q_res(chips)',
 P_PATH='@scm_lib.scm(sch_1):page28_i113@pure_quanta.q_res(chips)',
 PATH='I113',
 DRAWING='@SCM_LIB.SCM(SCH_1):PAGE28',
 PHYS_PAGE='28',
 XY='(-1350,3800)',
 ROT='0',
 VER='2',
 PACK_TYPE='0402LF',
 LOCATION='R295',
 CDS_LIB='pure_quanta',
 CDS_PART_NAME='Q_RES_0402LF-10K,1%,1/16W,CHIPA',
 WATTAGE='1/16W',
 TOLERANCE='1%',
 MATERIAL='CHIP',
 VALUE='10K',
 PRIM_FILE='W:/<user>/logical/q_res/chips/chips.prt';

PART_NAME
 R296 'Q_RES_0402LF-100K,1%,1/16W,EMPA':;

SECTION_NUMBER 1
 '@SCM_LIB.SCM(SCH_1):PAGE28_I105@PURE_QUANTA.Q_RES(CHIPS)':
 C_PATH='@scm_lib.scm(sch_1):page28_i105@pure_quanta.q_res(chips)',
 P_PATH='@scm_lib.scm(sch_1):page28_i105@pure_quanta.q_res(chips)',
 PATH='I105',
 DRAWING='@SCM_LIB.SCM(SCH_1):PAGE28',
 PHYS_PAGE='28',
 XY='(-950,3075)',
 ROT='2',
 VER='2',
 PACK_TYPE='0402LF',
 LOCATION='R296',
 CDS_LIB='pure_quanta',
 CDS_PART_NAME='Q_RES_0402LF-100K,1%,1/16W,EMPA',
 WATTAGE='1/16W',
 TOLERANCE='1%',
 MATERIAL='EMPTY',
 VALUE='100K',
 PRIM_FILE='W:/<user>/logical/q_res/chips/chips.prt';

PART_NAME
 R297 'Q_RES_0402LF-10K,1%,1/16W,CHIPA':;

SECTION_NUMBER 1
 '@SCM_LIB.SCM(SCH_1):PAGE34_I137@PURE_QUANTA.Q_RES(CHIPS)':
 C_PATH='@scm_lib.scm(sch_1):page34_i137@pure_quanta.q_res(chips)',
 P_PATH='@scm_lib.scm(sch_1):page34_i137@pure_quanta.q_res(chips)',
 PATH='I137',
 DRAWING='@SCM_LIB.SCM(SCH_1):PAGE34',
 PHYS_PAGE='34',
 XY='(-2550,4450)',
 ROT='0',
 VER='1',
 PACK_TYPE='0402LF',
 LOCATION='R297',
 CDS_LIB='pure_quanta',
 CDS_PART_NAME='Q_RES_0402LF-10K,1%,1/16W,CHIPA',
 WATTAGE='1/16W',
 TOLERANCE='1%',
 MATERIAL='CHIP',
 VALUE='10K',
 PRIM_FILE='W:/<user>/logical/q_res/chips/chips.prt';

PART_NAME
 R298 'Q_RES_0402LF-4.7K,1%,1/16W,CHIA':;

SECTION_NUMBER 1
 '@SCM_LIB.SCM(SCH_1):PAGE28_I96@PURE_QUANTA.Q_RES(CHIPS)':
 C_PATH='@scm_lib.scm(sch_1):page28_i96@pure_quanta.q_res(chips)',
 P_PATH='@scm_lib.scm(sch_1):page28_i96@pure_quanta.q_res(chips)',
 PATH='I96',
 DRAWING='@SCM_LIB.SCM(SCH_1):PAGE28',
 PHYS_PAGE='28',
 XY='(2500,2675)',
 ROT='0',
 VER='2',
 PACK_TYPE='0402LF',
 LOCATION='R298',
 CDS_LIB='pure_quanta',
 CDS_PART_NAME='Q_RES_0402LF-4.7K,1%,1/16W,CHIA',
 WATTAGE='1/16W',
 TOLERANCE='1%',
 MATERIAL='CHIP',
 VALUE='4.7K',
 PRIM_FILE='W:/<user>/logical/q_res/chips/chips.prt';

PART_NAME
 R299 'Q_RES_0402LF-4.7K,1%,1/16W,CHIA':;

SECTION_NUMBER 1
 '@SCM_LIB.SCM(SCH_1):PAGE28_I91@PURE_QUANTA.Q_RES(CHIPS)':
 C_PATH='@scm_lib.scm(sch_1):page28_i91@pure_quanta.q_res(chips)',
 P_PATH='@scm_lib.scm(sch_1):page28_i91@pure_quanta.q_res(chips)',
 PATH='I91',
 DRAWING='@SCM_LIB.SCM(SCH_1):PAGE28',
 PHYS_PAGE='28',
 XY='(3050,2675)',
 ROT='0',
 VER='2',
 PACK_TYPE='0402LF',
 LOCATION='R299',
 CDS_LIB='pure_quanta',
 CDS_PART_NAME='Q_RES_0402LF-4.7K,1%,1/16W,CHIA',
 WATTAGE='1/16W',
 TOLERANCE='1%',
 MATERIAL='CHIP',
 VALUE='4.7K',
 PRIM_FILE='W:/<user>/logical/q_res/chips/chips.prt';

PART_NAME
 R300 'Q_RES_0402LF-33.2,1%,1/16W,CHIA':;

SECTION_NUMBER 1
 '@SCM_LIB.SCM(SCH_1):PAGE28_I183@PURE_QUANTA.Q_RES(CHIPS)':
 C_PATH='@scm_lib.scm(sch_1):page28_i183@pure_quanta.q_res(chips)',
 P_PATH='@scm_lib.scm(sch_1):page28_i183@pure_quanta.q_res(chips)',
 PATH='I183',
 DRAWING='@SCM_LIB.SCM(SCH_1):PAGE28',
 PHYS_PAGE='28',
 XY='(3275,2225)',
 ROT='0',
 VER='1',
 PACK_TYPE='0402LF',
 LOCATION='R300',
 CDS_LIB='pure_quanta',
 CDS_PART_NAME='Q_RES_0402LF-33.2,1%,1/16W,CHIA',
 WATTAGE='1/16W',
 TOLERANCE='1%',
 MATERIAL='CHIP',
 VALUE='33.2',
 PRIM_FILE='W:/<user>/logical/q_res/chips/chips.prt';

PART_NAME
 R301 'Q_RES_0402LF-0,5%,1/16W,CHIP,CA':;

SECTION_NUMBER 1
 '@SCM_LIB.SCM(SCH_1):PAGE41_I75@PURE_QUANTA.Q_RES(CHIPS)':
 C_PATH='@scm_lib.scm(sch_1):page41_i75@pure_quanta.q_res(chips)',
 P_PATH='@scm_lib.scm(sch_1):page41_i75@pure_quanta.q_res(chips)',
 PATH='I75',
 DRAWING='@SCM_LIB.SCM(SCH_1):PAGE41',
 PHYS_PAGE='41',
 XY='(-8200,2500)',
 ROT='0',
 VER='1',
 PACK_TYPE='0402LF',
 CDS_LIB='pure_quanta',
 CDS_PART_NAME='Q_RES_0402LF-0,5%,1/16W,CHIP,CA',
 WATTAGE='1/16W',
 TOLERANCE='5%',
 MATERIAL='CHIP',
 VALUE='0',
 PRIM_FILE='W:/<user>/logical/q_res/chips/chips.prt';

PART_NAME
 R302 'Q_RES_0402LF-33.2,1%,1/16W,CHIA':;

SECTION_NUMBER 1
 '@SCM_LIB.SCM(SCH_1):PAGE28_I184@PURE_QUANTA.Q_RES(CHIPS)':
 C_PATH='@scm_lib.scm(sch_1):page28_i184@pure_quanta.q_res(chips)',
 P_PATH='@scm_lib.scm(sch_1):page28_i184@pure_quanta.q_res(chips)',
 PATH='I184',
 DRAWING='@SCM_LIB.SCM(SCH_1):PAGE28',
 PHYS_PAGE='28',
 XY='(3275,2125)',
 ROT='0',
 VER='1',
 PACK_TYPE='0402LF',
 LOCATION='R302',
 CDS_LIB='pure_quanta',
 CDS_PART_NAME='Q_RES_0402LF-33.2,1%,1/16W,CHIA',
 WATTAGE='1/16W',
 TOLERANCE='1%',
 MATERIAL='CHIP',
 VALUE='33.2',
 PRIM_FILE='W:/<user>/logical/q_res/chips/chips.prt';

PART_NAME
 R303 'Q_RES_0402LF-0,5%,1/16W,CHIP,CA':;

SECTION_NUMBER 1
 '@SCM_LIB.SCM(SCH_1):PAGE34_I166@PURE_QUANTA.Q_RES(CHIPS)':
 C_PATH='@scm_lib.scm(sch_1):page34_i166@pure_quanta.q_res(chips)',
 P_PATH='@scm_lib.scm(sch_1):page34_i166@pure_quanta.q_res(chips)',
 PATH='I166',
 DRAWING='@SCM_LIB.SCM(SCH_1):PAGE34',
 PHYS_PAGE='34',
 XY='(-2725,5050)',
 ROT='0',
 VER='1',
 PACK_TYPE='0402LF',
 LOCATION='R303',
 CDS_LIB='pure_quanta',
 CDS_PART_NAME='Q_RES_0402LF-0,5%,1/16W,CHIP,CA',
 WATTAGE='1/16W',
 TOLERANCE='5%',
 MATERIAL='CHIP',
 VALUE='0',
 PRIM_FILE='W:/<user>/logical/q_res/chips/chips.prt';

PART_NAME
 R304 'Q_RES_0402LF-0,5%,1/16W,CHIP,CA':;

SECTION_NUMBER 1
 '@SCM_LIB.SCM(SCH_1):PAGE41_I73@PURE_QUANTA.Q_RES(CHIPS)':
 C_PATH='@scm_lib.scm(sch_1):page41_i73@pure_quanta.q_res(chips)',
 P_PATH='@scm_lib.scm(sch_1):page41_i73@pure_quanta.q_res(chips)',
 PATH='I73',
 DRAWING='@SCM_LIB.SCM(SCH_1):PAGE41',
 PHYS_PAGE='41',
 XY='(-5125,3825)',
 ROT='0',
 VER='1',
 PACK_TYPE='0402LF',
 CDS_LIB='pure_quanta',
 CDS_PART_NAME='Q_RES_0402LF-0,5%,1/16W,CHIP,CA',
 WATTAGE='1/16W',
 TOLERANCE='5%',
 MATERIAL='CHIP',
 VALUE='0',
 PRIM_FILE='W:/<user>/logical/q_res/chips/chips.prt';

PART_NAME
 R305 'Q_RES_0402LF-0,5%,1/16W,CHIP,CA':;

SECTION_NUMBER 1
 '@SCM_LIB.SCM(SCH_1):PAGE41_I71@PURE_QUANTA.Q_RES(CHIPS)':
 C_PATH='@scm_lib.scm(sch_1):page41_i71@pure_quanta.q_res(chips)',
 P_PATH='@scm_lib.scm(sch_1):page41_i71@pure_quanta.q_res(chips)',
 PATH='I71',
 DRAWING='@SCM_LIB.SCM(SCH_1):PAGE41',
 PHYS_PAGE='41',
 XY='(-5100,6075)',
 ROT='0',
 VER='1',
 PACK_TYPE='0402LF',
 CDS_LIB='pure_quanta',
 CDS_PART_NAME='Q_RES_0402LF-0,5%,1/16W,CHIP,CA',
 WATTAGE='1/16W',
 TOLERANCE='5%',
 MATERIAL='CHIP',
 VALUE='0',
 PRIM_FILE='W:/<user>/logical/q_res/chips/chips.prt';

PART_NAME
 R306 'Q_RES_0402LF-10K,1%,1/16W,CHIPA':;

SECTION_NUMBER 1
 '@SCM_LIB.SCM(SCH_1):PAGE49_I8@PURE_QUANTA.Q_RES(CHIPS)':
 C_PATH='@scm_lib.scm(sch_1):page49_i8@pure_quanta.q_res(chips)',
 P_PATH='@scm_lib.scm(sch_1):page49_i8@pure_quanta.q_res(chips)',
 PATH='I8',
 DRAWING='@SCM_LIB.SCM(SCH_1):PAGE49',
 PHYS_PAGE='49',
 XY='(-7150,4975)',
 ROT='0',
 VER='2',
 PACK_TYPE='0402LF',
 CDS_LIB='pure_quanta',
 CDS_PART_NAME='Q_RES_0402LF-10K,1%,1/16W,CHIPA',
 WATTAGE='1/16W',
 TOLERANCE='1%',
 MATERIAL='CHIP',
 VALUE='10K',
 PRIM_FILE='W:/<user>/logical/q_res/chips/chips.prt';

PART_NAME
 R307 'Q_RES_0402LF-0,5%,1/16W,CHIP,CA':;

SECTION_NUMBER 1
 '@SCM_LIB.SCM(SCH_1):PAGE41_I76@PURE_QUANTA.Q_RES(CHIPS)':
 C_PATH='@scm_lib.scm(sch_1):page41_i76@pure_quanta.q_res(chips)',
 P_PATH='@scm_lib.scm(sch_1):page41_i76@pure_quanta.q_res(chips)',
 PATH='I76',
 DRAWING='@SCM_LIB.SCM(SCH_1):PAGE41',
 PHYS_PAGE='41',
 XY='(-8575,4725)',
 ROT='0',
 VER='1',
 PACK_TYPE='0402LF',
 CDS_LIB='pure_quanta',
 CDS_PART_NAME='Q_RES_0402LF-0,5%,1/16W,CHIP,CA',
 WATTAGE='1/16W',
 TOLERANCE='5%',
 MATERIAL='CHIP',
 VALUE='0',
 PRIM_FILE='W:/<user>/logical/q_res/chips/chips.prt';

PART_NAME
 R308 'Q_RES_0402LF-0,5%,1/16W,CHIP,CA':;

SECTION_NUMBER 1
 '@SCM_LIB.SCM(SCH_1):PAGE41_I74@PURE_QUANTA.Q_RES(CHIPS)':
 C_PATH='@scm_lib.scm(sch_1):page41_i74@pure_quanta.q_res(chips)',
 P_PATH='@scm_lib.scm(sch_1):page41_i74@pure_quanta.q_res(chips)',
 PATH='I74',
 DRAWING='@SCM_LIB.SCM(SCH_1):PAGE41',
 PHYS_PAGE='41',
 XY='(-8250,3475)',
 ROT='0',
 VER='1',
 PACK_TYPE='0402LF',
 CDS_LIB='pure_quanta',
 CDS_PART_NAME='Q_RES_0402LF-0,5%,1/16W,CHIP,CA',
 WATTAGE='1/16W',
 TOLERANCE='5%',
 MATERIAL='CHIP',
 VALUE='0',
 PRIM_FILE='W:/<user>/logical/q_res/chips/chips.prt';

PART_NAME
 R309 'Q_RES_0402LF-33.2,1%,1/16W,CHIA':;

SECTION_NUMBER 1
 '@SCM_LIB.SCM(SCH_1):PAGE13_I360@PURE_QUANTA.Q_RES(CHIPS)':
 C_PATH='@scm_lib.scm(sch_1):page13_i360@pure_quanta.q_res(chips)',
 P_PATH='@scm_lib.scm(sch_1):page13_i360@pure_quanta.q_res(chips)',
 PATH='I360',
 DRAWING='@SCM_LIB.SCM(SCH_1):PAGE13',
 PHYS_PAGE='13',
 XY='(3250,3975)',
 ROT='0',
 VER='1',
 PACK_TYPE='0402LF',
 CDS_LIB='pure_quanta',
 CDS_PART_NAME='Q_RES_0402LF-33.2,1%,1/16W,CHIA',
 WATTAGE='1/16W',
 TOLERANCE='1%',
 MATERIAL='CHIP',
 VALUE='33.2',
 PRIM_FILE='W:/<user>/logical/q_res/chips/chips.prt';

PART_NAME
 R310 'Q_RES_0402LF-33.2,1%,1/16W,CHIA':;

SECTION_NUMBER 1
 '@SCM_LIB.SCM(SCH_1):PAGE12_I441@PURE_QUANTA.Q_RES(CHIPS)':
 C_PATH='@scm_lib.scm(sch_1):page12_i441@pure_quanta.q_res(chips)',
 P_PATH='@scm_lib.scm(sch_1):page12_i441@pure_quanta.q_res(chips)',
 PATH='I441',
 DRAWING='@SCM_LIB.SCM(SCH_1):PAGE12',
 PHYS_PAGE='12',
 XY='(-850,2100)',
 ROT='0',
 VER='1',
 PACK_TYPE='0402LF',
 CDS_LIB='pure_quanta',
 CDS_PART_NAME='Q_RES_0402LF-33.2,1%,1/16W,CHIA',
 WATTAGE='1/16W',
 TOLERANCE='1%',
 MATERIAL='CHIP',
 VALUE='33.2',
 PRIM_FILE='W:/<user>/logical/q_res/chips/chips.prt';

PART_NAME
 R311 'Q_RES_0402LF-33.2,1%,1/16W,CHIA':;

SECTION_NUMBER 1
 '@SCM_LIB.SCM(SCH_1):PAGE12_I447@PURE_QUANTA.Q_RES(CHIPS)':
 C_PATH='@scm_lib.scm(sch_1):page12_i447@pure_quanta.q_res(chips)',
 P_PATH='@scm_lib.scm(sch_1):page12_i447@pure_quanta.q_res(chips)',
 PATH='I447',
 DRAWING='@SCM_LIB.SCM(SCH_1):PAGE12',
 PHYS_PAGE='12',
 XY='(-850,2050)',
 ROT='0',
 VER='1',
 PACK_TYPE='0402LF',
 CDS_LIB='pure_quanta',
 CDS_PART_NAME='Q_RES_0402LF-33.2,1%,1/16W,CHIA',
 WATTAGE='1/16W',
 TOLERANCE='1%',
 MATERIAL='CHIP',
 VALUE='33.2',
 PRIM_FILE='W:/<user>/logical/q_res/chips/chips.prt';

PART_NAME
 R312 'Q_RES_0402LF-47K,1%,1/16W,CHIPA':;

SECTION_NUMBER 1
 '@SCM_LIB.SCM(SCH_1):PAGE12_I456@PURE_QUANTA.Q_RES(CHIPS)':
 C_PATH='@scm_lib.scm(sch_1):page12_i456@pure_quanta.q_res(chips)',
 P_PATH='@scm_lib.scm(sch_1):page12_i456@pure_quanta.q_res(chips)',
 PATH='I456',
 DRAWING='@SCM_LIB.SCM(SCH_1):PAGE12',
 PHYS_PAGE='12',
 XY='(-1275,-625)',
 ROT='0',
 VER='2',
 PACK_TYPE='0402LF',
 CDS_LIB='pure_quanta',
 CDS_PART_NAME='Q_RES_0402LF-47K,1%,1/16W,CHIPA',
 WATTAGE='1/16W',
 TOLERANCE='1%',
 MATERIAL='CHIP',
 VALUE='47K',
 PRIM_FILE='W:/<user>/logical/q_res/chips/chips.prt';

PART_NAME
 R313 'Q_RES_0402LF-470K,1%,1/16W,CHIA':;

SECTION_NUMBER 1
 '@SCM_LIB.SCM(SCH_1):PAGE22_I30@PURE_QUANTA.Q_RES(CHIPS)':
 C_PATH='@scm_lib.scm(sch_1):page22_i30@pure_quanta.q_res(chips)',
 P_PATH='@scm_lib.scm(sch_1):page22_i30@pure_quanta.q_res(chips)',
 PATH='I30',
 DRAWING='@SCM_LIB.SCM(SCH_1):PAGE22',
 PHYS_PAGE='22',
 XY='(-975,2600)',
 ROT='0',
 VER='2',
 PACK_TYPE='0402LF',
 LOCATION='R313',
 CDS_LIB='pure_quanta',
 CDS_PART_NAME='Q_RES_0402LF-470K,1%,1/16W,CHIA',
 WATTAGE='1/16W',
 TOLERANCE='1%',
 MATERIAL='CHIP',
 VALUE='470K',
 PRIM_FILE='W:/<user>/logical/q_res/chips/chips.prt';

PART_NAME
 R314 'Q_RES_0402LF-100K,1%,1/16W,CHIA':;

SECTION_NUMBER 1
 '@SCM_LIB.SCM(SCH_1):PAGE22_I26@PURE_QUANTA.Q_RES(CHIPS)':
 C_PATH='@scm_lib.scm(sch_1):page22_i26@pure_quanta.q_res(chips)',
 P_PATH='@scm_lib.scm(sch_1):page22_i26@pure_quanta.q_res(chips)',
 PATH='I26',
 DRAWING='@SCM_LIB.SCM(SCH_1):PAGE22',
 PHYS_PAGE='22',
 XY='(-175,2550)',
 ROT='0',
 VER='2',
 PACK_TYPE='0402LF',
 LOCATION='R314',
 CDS_LIB='pure_quanta',
 CDS_PART_NAME='Q_RES_0402LF-100K,1%,1/16W,CHIA',
 WATTAGE='1/16W',
 TOLERANCE='1%',
 MATERIAL='CHIP',
 VALUE='100K',
 PRIM_FILE='W:/<user>/logical/q_res/chips/chips.prt';

PART_NAME
 R315 'Q_RES_0402LF-0,5%,1/16W,EMPTY,A':;

SECTION_NUMBER 1
 '@SCM_LIB.SCM(SCH_1):PAGE22_I71@PURE_QUANTA.Q_RES(CHIPS)':
 C_PATH='@scm_lib.scm(sch_1):page22_i71@pure_quanta.q_res(chips)',
 P_PATH='@scm_lib.scm(sch_1):page22_i71@pure_quanta.q_res(chips)',
 PATH='I71',
 DRAWING='@SCM_LIB.SCM(SCH_1):PAGE22',
 PHYS_PAGE='22',
 XY='(1550,2125)',
 ROT='0',
 VER='1',
 PACK_TYPE='0402LF',
 LOCATION='R315',
 CDS_LIB='pure_quanta',
 CDS_PART_NAME='Q_RES_0402LF-0,5%,1/16W,EMPTY,A',
 WATTAGE='1/16W',
 TOLERANCE='5%',
 MATERIAL='EMPTY',
 VALUE='0',
 PRIM_FILE='W:/<user>/logical/q_res/chips/chips.prt';

PART_NAME
 R316 'Q_RES_0402LF-0,5%,1/16W,CHIP,CA':;

SECTION_NUMBER 1
 '@SCM_LIB.SCM(SCH_1):PAGE15_I318@PURE_QUANTA.Q_RES(CHIPS)':
 C_PATH='@scm_lib.scm(sch_1):page15_i318@pure_quanta.q_res(chips)',
 P_PATH='@scm_lib.scm(sch_1):page15_i318@pure_quanta.q_res(chips)',
 PATH='I318',
 DRAWING='@SCM_LIB.SCM(SCH_1):PAGE15',
 PHYS_PAGE='15',
 XY='(4125,3275)',
 ROT='0',
 VER='1',
 PACK_TYPE='0402LF',
 LOCATION='R316',
 CDS_LIB='pure_quanta',
 CDS_PART_NAME='Q_RES_0402LF-0,5%,1/16W,CHIP,CA',
 WATTAGE='1/16W',
 TOLERANCE='5%',
 MATERIAL='CHIP',
 VALUE='0',
 PRIM_FILE='W:/<user>/logical/q_res/chips/chips.prt';

PART_NAME
 R317 'Q_RES_0402LF-0,5%,1/16W,CHIP,CA':;

SECTION_NUMBER 1
 '@SCM_LIB.SCM(SCH_1):PAGE35_I99@PURE_QUANTA.Q_RES(CHIPS)':
 C_PATH='@scm_lib.scm(sch_1):page35_i99@pure_quanta.q_res(chips)',
 P_PATH='@scm_lib.scm(sch_1):page35_i99@pure_quanta.q_res(chips)',
 PATH='I99',
 DRAWING='@SCM_LIB.SCM(SCH_1):PAGE35',
 SEC_TYPE='0402LF',
 PHYS_PAGE='35',
 XY='(-2750,3250)',
 ROT='0',
 VER='1',
 PACK_TYPE='0402LF',
 LOCATION='R317',
 SEC='1',
 CDS_LIB='pure_quanta',
 CDS_PART_NAME='Q_RES_0402LF-0,5%,1/16W,CHIP,CA',
 WATTAGE='1/16W',
 TOLERANCE='5%',
 MATERIAL='CHIP',
 VALUE='0',
 PRIM_FILE='W:/<user>/logical/q_res/chips/chips.prt';

PART_NAME
 R318 'Q_RES_0402LF-0,5%,1/16W,CHIP,CA':;

SECTION_NUMBER 1
 '@SCM_LIB.SCM(SCH_1):PAGE35_I98@PURE_QUANTA.Q_RES(CHIPS)':
 C_PATH='@scm_lib.scm(sch_1):page35_i98@pure_quanta.q_res(chips)',
 P_PATH='@scm_lib.scm(sch_1):page35_i98@pure_quanta.q_res(chips)',
 PATH='I98',
 DRAWING='@SCM_LIB.SCM(SCH_1):PAGE35',
 SEC_TYPE='0402LF',
 PHYS_PAGE='35',
 XY='(-1800,3100)',
 ROT='0',
 VER='1',
 PACK_TYPE='0402LF',
 LOCATION='R318',
 SEC='1',
 CDS_LIB='pure_quanta',
 CDS_PART_NAME='Q_RES_0402LF-0,5%,1/16W,CHIP,CA',
 WATTAGE='1/16W',
 TOLERANCE='5%',
 MATERIAL='CHIP',
 VALUE='0',
 PRIM_FILE='W:/<user>/logical/q_res/chips/chips.prt';

PART_NAME
 R319 'Q_RES_0402LF-4.7K,1%,1/16W,CHIA':;

SECTION_NUMBER 1
 '@SCM_LIB.SCM(SCH_1):PAGE42_I65@PURE_QUANTA.Q_RES(CHIPS)':
 C_PATH='@scm_lib.scm(sch_1):page42_i65@pure_quanta.q_res(chips)',
 P_PATH='@scm_lib.scm(sch_1):page42_i65@pure_quanta.q_res(chips)',
 PATH='I65',
 DRAWING='@SCM_LIB.SCM(SCH_1):PAGE42',
 PHYS_PAGE='42',
 XY='(8500,3550)',
 ROT='0',
 VER='1',
 PACK_TYPE='0402LF',
 CDS_LIB='pure_quanta',
 CDS_PART_NAME='Q_RES_0402LF-4.7K,1%,1/16W,CHIA',
 WATTAGE='1/16W',
 TOLERANCE='1%',
 MATERIAL='CHIP',
 VALUE='4.7K',
 PRIM_FILE='W:/<user>/logical/q_res/chips/chips.prt';

PART_NAME
 R320 'Q_RES_0402LF-0,5%,1/16W,CHIP,CA':;

SECTION_NUMBER 1
 '@SCM_LIB.SCM(SCH_1):PAGE35_I95@PURE_QUANTA.Q_RES(CHIPS)':
 C_PATH='@scm_lib.scm(sch_1):page35_i95@pure_quanta.q_res(chips)',
 P_PATH='@scm_lib.scm(sch_1):page35_i95@pure_quanta.q_res(chips)',
 PATH='I95',
 DRAWING='@SCM_LIB.SCM(SCH_1):PAGE35',
 SEC_TYPE='0402LF',
 PHYS_PAGE='35',
 XY='(-1800,3050)',
 ROT='0',
 VER='1',
 PACK_TYPE='0402LF',
 LOCATION='R320',
 SEC='1',
 CDS_LIB='pure_quanta',
 CDS_PART_NAME='Q_RES_0402LF-0,5%,1/16W,CHIP,CA',
 WATTAGE='1/16W',
 TOLERANCE='5%',
 MATERIAL='CHIP',
 VALUE='0',
 PRIM_FILE='W:/<user>/logical/q_res/chips/chips.prt';

PART_NAME
 R321 'Q_RES_0402LF-0,5%,1/16W,CHIP,CA':;

SECTION_NUMBER 1
 '@SCM_LIB.SCM(SCH_1):PAGE36_I33@PURE_QUANTA.Q_RES(CHIPS)':
 C_PATH='@scm_lib.scm(sch_1):page36_i33@pure_quanta.q_res(chips)',
 P_PATH='@scm_lib.scm(sch_1):page36_i33@pure_quanta.q_res(chips)',
 PATH='I33',
 DRAWING='@SCM_LIB.SCM(SCH_1):PAGE36',
 SEC_TYPE='0402LF',
 PHYS_PAGE='36',
 XY='(-2575,5275)',
 ROT='0',
 VER='1',
 PACK_TYPE='0402LF',
 LOCATION='R321',
 SEC='1',
 CDS_LIB='pure_quanta',
 CDS_PART_NAME='Q_RES_0402LF-0,5%,1/16W,CHIP,CA',
 WATTAGE='1/16W',
 TOLERANCE='5%',
 MATERIAL='CHIP',
 VALUE='0',
 PRIM_FILE='W:/<user>/logical/q_res/chips/chips.prt';

PART_NAME
 R322 'Q_RES_0402LF-0,5%,1/16W,CHIP,CA':;

SECTION_NUMBER 1
 '@SCM_LIB.SCM(SCH_1):PAGE36_I35@PURE_QUANTA.Q_RES(CHIPS)':
 C_PATH='@scm_lib.scm(sch_1):page36_i35@pure_quanta.q_res(chips)',
 P_PATH='@scm_lib.scm(sch_1):page36_i35@pure_quanta.q_res(chips)',
 PATH='I35',
 DRAWING='@SCM_LIB.SCM(SCH_1):PAGE36',
 SEC_TYPE='0402LF',
 PHYS_PAGE='36',
 XY='(-2575,5225)',
 ROT='0',
 VER='1',
 PACK_TYPE='0402LF',
 LOCATION='R322',
 SEC='1',
 CDS_LIB='pure_quanta',
 CDS_PART_NAME='Q_RES_0402LF-0,5%,1/16W,CHIP,CA',
 WATTAGE='1/16W',
 TOLERANCE='5%',
 MATERIAL='CHIP',
 VALUE='0',
 PRIM_FILE='W:/<user>/logical/q_res/chips/chips.prt';

PART_NAME
 R323 'Q_RES_0402LF-0,5%,1/16W,CHIP,CA':;

SECTION_NUMBER 1
 '@SCM_LIB.SCM(SCH_1):PAGE36_I34@PURE_QUANTA.Q_RES(CHIPS)':
 C_PATH='@scm_lib.scm(sch_1):page36_i34@pure_quanta.q_res(chips)',
 P_PATH='@scm_lib.scm(sch_1):page36_i34@pure_quanta.q_res(chips)',
 PATH='I34',
 DRAWING='@SCM_LIB.SCM(SCH_1):PAGE36',
 SEC_TYPE='0402LF',
 PHYS_PAGE='36',
 XY='(-2575,5125)',
 ROT='0',
 VER='1',
 PACK_TYPE='0402LF',
 LOCATION='R323',
 SEC='1',
 CDS_LIB='pure_quanta',
 CDS_PART_NAME='Q_RES_0402LF-0,5%,1/16W,CHIP,CA',
 WATTAGE='1/16W',
 TOLERANCE='5%',
 MATERIAL='CHIP',
 VALUE='0',
 PRIM_FILE='W:/<user>/logical/q_res/chips/chips.prt';

PART_NAME
 R324 'Q_RES_0402LF-1K,1%,1/16W,CHIP,A':;

SECTION_NUMBER 1
 '@SCM_LIB.SCM(SCH_1):PAGE20_I28@PURE_QUANTA.Q_RES(CHIPS)':
 C_PATH='@scm_lib.scm(sch_1):page20_i28@pure_quanta.q_res(chips)',
 P_PATH='@scm_lib.scm(sch_1):page20_i28@pure_quanta.q_res(chips)',
 PATH='I28',
 DRAWING='@SCM_LIB.SCM(SCH_1):PAGE20',
 PHYS_PAGE='20',
 XY='(-250,350)',
 ROT='0',
 VER='2',
 PACK_TYPE='0402LF',
 LOCATION='R324',
 CDS_LIB='pure_quanta',
 CDS_PART_NAME='Q_RES_0402LF-1K,1%,1/16W,CHIP,A',
 WATTAGE='1/16W',
 TOLERANCE='1%',
 MATERIAL='CHIP',
 VALUE='1K',
 PRIM_FILE='W:/<user>/logical/q_res/chips/chips.prt';

PART_NAME
 R325 'Q_RES_0402LF-1K,1%,1/16W,CHIP,A':;

SECTION_NUMBER 1
 '@SCM_LIB.SCM(SCH_1):PAGE20_I27@PURE_QUANTA.Q_RES(CHIPS)':
 C_PATH='@scm_lib.scm(sch_1):page20_i27@pure_quanta.q_res(chips)',
 P_PATH='@scm_lib.scm(sch_1):page20_i27@pure_quanta.q_res(chips)',
 PATH='I27',
 DRAWING='@SCM_LIB.SCM(SCH_1):PAGE20',
 PHYS_PAGE='20',
 XY='(-250,-75)',
 ROT='0',
 VER='2',
 PACK_TYPE='0402LF',
 LOCATION='R325',
 CDS_LIB='pure_quanta',
 CDS_PART_NAME='Q_RES_0402LF-1K,1%,1/16W,CHIP,A',
 WATTAGE='1/16W',
 TOLERANCE='1%',
 MATERIAL='CHIP',
 VALUE='1K',
 PRIM_FILE='W:/<user>/logical/q_res/chips/chips.prt';

PART_NAME
 R326 'Q_RES_0402LF-120,1%,1/16W,CHIPA':;

SECTION_NUMBER 1
 '@SCM_LIB.SCM(SCH_1):PAGE20_I193@PURE_QUANTA.Q_RES(CHIPS)':
 C_PATH='@scm_lib.scm(sch_1):page20_i193@pure_quanta.q_res(chips)',
 P_PATH='@scm_lib.scm(sch_1):page20_i193@pure_quanta.q_res(chips)',
 PATH='I193',
 DRAWING='@SCM_LIB.SCM(SCH_1):PAGE20',
 PHYS_PAGE='20',
 XY='(3600,4650)',
 ROT='0',
 VER='1',
 PACK_TYPE='0402LF',
 LOCATION='R326',
 CDS_LIB='pure_quanta',
 CDS_PART_NAME='Q_RES_0402LF-120,1%,1/16W,CHIPA',
 WATTAGE='1/16W',
 TOLERANCE='1%',
 MATERIAL='CHIP',
 VALUE='120',
 PRIM_FILE='W:/<user>/logical/q_res/chips/chips.prt';

PART_NAME
 R327 'Q_RES_0402LF-120,1%,1/16W,CHIPA':;

SECTION_NUMBER 1
 '@SCM_LIB.SCM(SCH_1):PAGE20_I177@PURE_QUANTA.Q_RES(CHIPS)':
 C_PATH='@scm_lib.scm(sch_1):page20_i177@pure_quanta.q_res(chips)',
 P_PATH='@scm_lib.scm(sch_1):page20_i177@pure_quanta.q_res(chips)',
 PATH='I177',
 DRAWING='@SCM_LIB.SCM(SCH_1):PAGE20',
 PHYS_PAGE='20',
 XY='(3600,4500)',
 ROT='0',
 VER='1',
 PACK_TYPE='0402LF',
 LOCATION='R327',
 CDS_LIB='pure_quanta',
 CDS_PART_NAME='Q_RES_0402LF-120,1%,1/16W,CHIPA',
 WATTAGE='1/16W',
 TOLERANCE='1%',
 MATERIAL='CHIP',
 VALUE='120',
 PRIM_FILE='W:/<user>/logical/q_res/chips/chips.prt';

PART_NAME
 R328 'Q_RES_0402LF-120,1%,1/16W,CHIPA':;

SECTION_NUMBER 1
 '@SCM_LIB.SCM(SCH_1):PAGE20_I176@PURE_QUANTA.Q_RES(CHIPS)':
 C_PATH='@scm_lib.scm(sch_1):page20_i176@pure_quanta.q_res(chips)',
 P_PATH='@scm_lib.scm(sch_1):page20_i176@pure_quanta.q_res(chips)',
 PATH='I176',
 DRAWING='@SCM_LIB.SCM(SCH_1):PAGE20',
 PHYS_PAGE='20',
 XY='(3600,4350)',
 ROT='0',
 VER='1',
 PACK_TYPE='0402LF',
 LOCATION='R328',
 CDS_LIB='pure_quanta',
 CDS_PART_NAME='Q_RES_0402LF-120,1%,1/16W,CHIPA',
 WATTAGE='1/16W',
 TOLERANCE='1%',
 MATERIAL='CHIP',
 VALUE='120',
 PRIM_FILE='W:/<user>/logical/q_res/chips/chips.prt';

PART_NAME
 R329 'Q_RES_0402LF-120,1%,1/16W,CHIPA':;

SECTION_NUMBER 1
 '@SCM_LIB.SCM(SCH_1):PAGE20_I175@PURE_QUANTA.Q_RES(CHIPS)':
 C_PATH='@scm_lib.scm(sch_1):page20_i175@pure_quanta.q_res(chips)',
 P_PATH='@scm_lib.scm(sch_1):page20_i175@pure_quanta.q_res(chips)',
 PATH='I175',
 DRAWING='@SCM_LIB.SCM(SCH_1):PAGE20',
 PHYS_PAGE='20',
 XY='(3600,4200)',
 ROT='0',
 VER='1',
 PACK_TYPE='0402LF',
 LOCATION='R329',
 CDS_LIB='pure_quanta',
 CDS_PART_NAME='Q_RES_0402LF-120,1%,1/16W,CHIPA',
 WATTAGE='1/16W',
 TOLERANCE='1%',
 MATERIAL='CHIP',
 VALUE='120',
 PRIM_FILE='W:/<user>/logical/q_res/chips/chips.prt';

PART_NAME
 R330 'Q_RES_0402LF-120,1%,1/16W,CHIPA':;

SECTION_NUMBER 1
 '@SCM_LIB.SCM(SCH_1):PAGE20_I174@PURE_QUANTA.Q_RES(CHIPS)':
 C_PATH='@scm_lib.scm(sch_1):page20_i174@pure_quanta.q_res(chips)',
 P_PATH='@scm_lib.scm(sch_1):page20_i174@pure_quanta.q_res(chips)',
 PATH='I174',
 DRAWING='@SCM_LIB.SCM(SCH_1):PAGE20',
 PHYS_PAGE='20',
 XY='(3600,4050)',
 ROT='0',
 VER='1',
 PACK_TYPE='0402LF',
 LOCATION='R330',
 CDS_LIB='pure_quanta',
 CDS_PART_NAME='Q_RES_0402LF-120,1%,1/16W,CHIPA',
 WATTAGE='1/16W',
 TOLERANCE='1%',
 MATERIAL='CHIP',
 VALUE='120',
 PRIM_FILE='W:/<user>/logical/q_res/chips/chips.prt';

PART_NAME
 R331 'Q_RES_0402LF-120,1%,1/16W,CHIPA':;

SECTION_NUMBER 1
 '@SCM_LIB.SCM(SCH_1):PAGE20_I173@PURE_QUANTA.Q_RES(CHIPS)':
 C_PATH='@scm_lib.scm(sch_1):page20_i173@pure_quanta.q_res(chips)',
 P_PATH='@scm_lib.scm(sch_1):page20_i173@pure_quanta.q_res(chips)',
 PATH='I173',
 DRAWING='@SCM_LIB.SCM(SCH_1):PAGE20',
 PHYS_PAGE='20',
 XY='(3600,3900)',
 ROT='0',
 VER='1',
 PACK_TYPE='0402LF',
 LOCATION='R331',
 CDS_LIB='pure_quanta',
 CDS_PART_NAME='Q_RES_0402LF-120,1%,1/16W,CHIPA',
 WATTAGE='1/16W',
 TOLERANCE='1%',
 MATERIAL='CHIP',
 VALUE='120',
 PRIM_FILE='W:/<user>/logical/q_res/chips/chips.prt';

PART_NAME
 R332 'Q_RES_0402LF-120,1%,1/16W,CHIPA':;

SECTION_NUMBER 1
 '@SCM_LIB.SCM(SCH_1):PAGE20_I171@PURE_QUANTA.Q_RES(CHIPS)':
 C_PATH='@scm_lib.scm(sch_1):page20_i171@pure_quanta.q_res(chips)',
 P_PATH='@scm_lib.scm(sch_1):page20_i171@pure_quanta.q_res(chips)',
 PATH='I171',
 DRAWING='@SCM_LIB.SCM(SCH_1):PAGE20',
 PHYS_PAGE='20',
 XY='(3600,3750)',
 ROT='0',
 VER='1',
 PACK_TYPE='0402LF',
 LOCATION='R332',
 CDS_LIB='pure_quanta',
 CDS_PART_NAME='Q_RES_0402LF-120,1%,1/16W,CHIPA',
 WATTAGE='1/16W',
 TOLERANCE='1%',
 MATERIAL='CHIP',
 VALUE='120',
 PRIM_FILE='W:/<user>/logical/q_res/chips/chips.prt';

PART_NAME
 R333 'Q_RES_0402LF-120,1%,1/16W,CHIPA':;

SECTION_NUMBER 1
 '@SCM_LIB.SCM(SCH_1):PAGE20_I172@PURE_QUANTA.Q_RES(CHIPS)':
 C_PATH='@scm_lib.scm(sch_1):page20_i172@pure_quanta.q_res(chips)',
 P_PATH='@scm_lib.scm(sch_1):page20_i172@pure_quanta.q_res(chips)',
 PATH='I172',
 DRAWING='@SCM_LIB.SCM(SCH_1):PAGE20',
 PHYS_PAGE='20',
 XY='(3600,3600)',
 ROT='0',
 VER='1',
 PACK_TYPE='0402LF',
 LOCATION='R333',
 CDS_LIB='pure_quanta',
 CDS_PART_NAME='Q_RES_0402LF-120,1%,1/16W,CHIPA',
 WATTAGE='1/16W',
 TOLERANCE='1%',
 MATERIAL='CHIP',
 VALUE='120',
 PRIM_FILE='W:/<user>/logical/q_res/chips/chips.prt';

PART_NAME
 R334 'Q_RES_0402LF-120,1%,1/16W,CHIPA':;

SECTION_NUMBER 1
 '@SCM_LIB.SCM(SCH_1):PAGE20_I164@PURE_QUANTA.Q_RES(CHIPS)':
 C_PATH='@scm_lib.scm(sch_1):page20_i164@pure_quanta.q_res(chips)',
 P_PATH='@scm_lib.scm(sch_1):page20_i164@pure_quanta.q_res(chips)',
 PATH='I164',
 DRAWING='@SCM_LIB.SCM(SCH_1):PAGE20',
 PHYS_PAGE='20',
 XY='(3600,3450)',
 ROT='0',
 VER='1',
 PACK_TYPE='0402LF',
 LOCATION='R334',
 CDS_LIB='pure_quanta',
 CDS_PART_NAME='Q_RES_0402LF-120,1%,1/16W,CHIPA',
 WATTAGE='1/16W',
 TOLERANCE='1%',
 MATERIAL='CHIP',
 VALUE='120',
 PRIM_FILE='W:/<user>/logical/q_res/chips/chips.prt';

PART_NAME
 R335 'Q_RES_0402LF-120,1%,1/16W,CHIPA':;

SECTION_NUMBER 1
 '@SCM_LIB.SCM(SCH_1):PAGE20_I163@PURE_QUANTA.Q_RES(CHIPS)':
 C_PATH='@scm_lib.scm(sch_1):page20_i163@pure_quanta.q_res(chips)',
 P_PATH='@scm_lib.scm(sch_1):page20_i163@pure_quanta.q_res(chips)',
 PATH='I163',
 DRAWING='@SCM_LIB.SCM(SCH_1):PAGE20',
 PHYS_PAGE='20',
 XY='(3600,3300)',
 ROT='0',
 VER='1',
 PACK_TYPE='0402LF',
 LOCATION='R335',
 CDS_LIB='pure_quanta',
 CDS_PART_NAME='Q_RES_0402LF-120,1%,1/16W,CHIPA',
 WATTAGE='1/16W',
 TOLERANCE='1%',
 MATERIAL='CHIP',
 VALUE='120',
 PRIM_FILE='W:/<user>/logical/q_res/chips/chips.prt';

PART_NAME
 R336 'Q_RES_0402LF-120,1%,1/16W,CHIPA':;

SECTION_NUMBER 1
 '@SCM_LIB.SCM(SCH_1):PAGE20_I162@PURE_QUANTA.Q_RES(CHIPS)':
 C_PATH='@scm_lib.scm(sch_1):page20_i162@pure_quanta.q_res(chips)',
 P_PATH='@scm_lib.scm(sch_1):page20_i162@pure_quanta.q_res(chips)',
 PATH='I162',
 DRAWING='@SCM_LIB.SCM(SCH_1):PAGE20',
 PHYS_PAGE='20',
 XY='(3600,3150)',
 ROT='0',
 VER='1',
 PACK_TYPE='0402LF',
 LOCATION='R336',
 CDS_LIB='pure_quanta',
 CDS_PART_NAME='Q_RES_0402LF-120,1%,1/16W,CHIPA',
 WATTAGE='1/16W',
 TOLERANCE='1%',
 MATERIAL='CHIP',
 VALUE='120',
 PRIM_FILE='W:/<user>/logical/q_res/chips/chips.prt';

PART_NAME
 R337 'Q_RES_0402LF-120,1%,1/16W,CHIPA':;

SECTION_NUMBER 1
 '@SCM_LIB.SCM(SCH_1):PAGE20_I161@PURE_QUANTA.Q_RES(CHIPS)':
 C_PATH='@scm_lib.scm(sch_1):page20_i161@pure_quanta.q_res(chips)',
 P_PATH='@scm_lib.scm(sch_1):page20_i161@pure_quanta.q_res(chips)',
 PATH='I161',
 DRAWING='@SCM_LIB.SCM(SCH_1):PAGE20',
 PHYS_PAGE='20',
 XY='(3600,3000)',
 ROT='0',
 VER='1',
 PACK_TYPE='0402LF',
 LOCATION='R337',
 CDS_LIB='pure_quanta',
 CDS_PART_NAME='Q_RES_0402LF-120,1%,1/16W,CHIPA',
 WATTAGE='1/16W',
 TOLERANCE='1%',
 MATERIAL='CHIP',
 VALUE='120',
 PRIM_FILE='W:/<user>/logical/q_res/chips/chips.prt';

PART_NAME
 R338 'Q_RES_0402LF-120,1%,1/16W,CHIPA':;

SECTION_NUMBER 1
 '@SCM_LIB.SCM(SCH_1):PAGE20_I160@PURE_QUANTA.Q_RES(CHIPS)':
 C_PATH='@scm_lib.scm(sch_1):page20_i160@pure_quanta.q_res(chips)',
 P_PATH='@scm_lib.scm(sch_1):page20_i160@pure_quanta.q_res(chips)',
 PATH='I160',
 DRAWING='@SCM_LIB.SCM(SCH_1):PAGE20',
 PHYS_PAGE='20',
 XY='(3600,2850)',
 ROT='0',
 VER='1',
 PACK_TYPE='0402LF',
 LOCATION='R338',
 CDS_LIB='pure_quanta',
 CDS_PART_NAME='Q_RES_0402LF-120,1%,1/16W,CHIPA',
 WATTAGE='1/16W',
 TOLERANCE='1%',
 MATERIAL='CHIP',
 VALUE='120',
 PRIM_FILE='W:/<user>/logical/q_res/chips/chips.prt';

PART_NAME
 R339 'Q_RES_0402LF-120,1%,1/16W,CHIPA':;

SECTION_NUMBER 1
 '@SCM_LIB.SCM(SCH_1):PAGE20_I159@PURE_QUANTA.Q_RES(CHIPS)':
 C_PATH='@scm_lib.scm(sch_1):page20_i159@pure_quanta.q_res(chips)',
 P_PATH='@scm_lib.scm(sch_1):page20_i159@pure_quanta.q_res(chips)',
 PATH='I159',
 DRAWING='@SCM_LIB.SCM(SCH_1):PAGE20',
 PHYS_PAGE='20',
 XY='(3600,2700)',
 ROT='0',
 VER='1',
 PACK_TYPE='0402LF',
 LOCATION='R339',
 CDS_LIB='pure_quanta',
 CDS_PART_NAME='Q_RES_0402LF-120,1%,1/16W,CHIPA',
 WATTAGE='1/16W',
 TOLERANCE='1%',
 MATERIAL='CHIP',
 VALUE='120',
 PRIM_FILE='W:/<user>/logical/q_res/chips/chips.prt';

PART_NAME
 R340 'Q_RES_0402LF-120,1%,1/16W,CHIPA':;

SECTION_NUMBER 1
 '@SCM_LIB.SCM(SCH_1):PAGE20_I124@PURE_QUANTA.Q_RES(CHIPS)':
 C_PATH='@scm_lib.scm(sch_1):page20_i124@pure_quanta.q_res(chips)',
 P_PATH='@scm_lib.scm(sch_1):page20_i124@pure_quanta.q_res(chips)',
 PATH='I124',
 DRAWING='@SCM_LIB.SCM(SCH_1):PAGE20',
 PHYS_PAGE='20',
 XY='(3650,1925)',
 ROT='0',
 VER='1',
 PACK_TYPE='0402LF',
 LOCATION='R340',
 CDS_LIB='pure_quanta',
 CDS_PART_NAME='Q_RES_0402LF-120,1%,1/16W,CHIPA',
 WATTAGE='1/16W',
 TOLERANCE='1%',
 MATERIAL='CHIP',
 VALUE='120',
 PRIM_FILE='W:/<user>/logical/q_res/chips/chips.prt';

PART_NAME
 R341 'Q_RES_0402LF-120,1%,1/16W,CHIPA':;

SECTION_NUMBER 1
 '@SCM_LIB.SCM(SCH_1):PAGE20_I125@PURE_QUANTA.Q_RES(CHIPS)':
 C_PATH='@scm_lib.scm(sch_1):page20_i125@pure_quanta.q_res(chips)',
 P_PATH='@scm_lib.scm(sch_1):page20_i125@pure_quanta.q_res(chips)',
 PATH='I125',
 DRAWING='@SCM_LIB.SCM(SCH_1):PAGE20',
 PHYS_PAGE='20',
 XY='(3650,1775)',
 ROT='0',
 VER='1',
 PACK_TYPE='0402LF',
 LOCATION='R341',
 CDS_LIB='pure_quanta',
 CDS_PART_NAME='Q_RES_0402LF-120,1%,1/16W,CHIPA',
 WATTAGE='1/16W',
 TOLERANCE='1%',
 MATERIAL='CHIP',
 VALUE='120',
 PRIM_FILE='W:/<user>/logical/q_res/chips/chips.prt';

PART_NAME
 R342 'Q_RES_0402LF-120,1%,1/16W,CHIPA':;

SECTION_NUMBER 1
 '@SCM_LIB.SCM(SCH_1):PAGE20_I122@PURE_QUANTA.Q_RES(CHIPS)':
 C_PATH='@scm_lib.scm(sch_1):page20_i122@pure_quanta.q_res(chips)',
 P_PATH='@scm_lib.scm(sch_1):page20_i122@pure_quanta.q_res(chips)',
 PATH='I122',
 DRAWING='@SCM_LIB.SCM(SCH_1):PAGE20',
 PHYS_PAGE='20',
 XY='(3650,1625)',
 ROT='0',
 VER='1',
 PACK_TYPE='0402LF',
 LOCATION='R342',
 CDS_LIB='pure_quanta',
 CDS_PART_NAME='Q_RES_0402LF-120,1%,1/16W,CHIPA',
 WATTAGE='1/16W',
 TOLERANCE='1%',
 MATERIAL='CHIP',
 VALUE='120',
 PRIM_FILE='W:/<user>/logical/q_res/chips/chips.prt';

PART_NAME
 R343 'Q_RES_0402LF-120,1%,1/16W,CHIPA':;

SECTION_NUMBER 1
 '@SCM_LIB.SCM(SCH_1):PAGE20_I123@PURE_QUANTA.Q_RES(CHIPS)':
 C_PATH='@scm_lib.scm(sch_1):page20_i123@pure_quanta.q_res(chips)',
 P_PATH='@scm_lib.scm(sch_1):page20_i123@pure_quanta.q_res(chips)',
 PATH='I123',
 DRAWING='@SCM_LIB.SCM(SCH_1):PAGE20',
 PHYS_PAGE='20',
 XY='(3650,1475)',
 ROT='0',
 VER='1',
 PACK_TYPE='0402LF',
 LOCATION='R343',
 CDS_LIB='pure_quanta',
 CDS_PART_NAME='Q_RES_0402LF-120,1%,1/16W,CHIPA',
 WATTAGE='1/16W',
 TOLERANCE='1%',
 MATERIAL='CHIP',
 VALUE='120',
 PRIM_FILE='W:/<user>/logical/q_res/chips/chips.prt';

PART_NAME
 R344 'Q_RES_0402LF-120,1%,1/16W,CHIPA':;

SECTION_NUMBER 1
 '@SCM_LIB.SCM(SCH_1):PAGE20_I121@PURE_QUANTA.Q_RES(CHIPS)':
 C_PATH='@scm_lib.scm(sch_1):page20_i121@pure_quanta.q_res(chips)',
 P_PATH='@scm_lib.scm(sch_1):page20_i121@pure_quanta.q_res(chips)',
 PATH='I121',
 DRAWING='@SCM_LIB.SCM(SCH_1):PAGE20',
 PHYS_PAGE='20',
 XY='(3650,1325)',
 ROT='0',
 VER='1',
 PACK_TYPE='0402LF',
 LOCATION='R344',
 CDS_LIB='pure_quanta',
 CDS_PART_NAME='Q_RES_0402LF-120,1%,1/16W,CHIPA',
 WATTAGE='1/16W',
 TOLERANCE='1%',
 MATERIAL='CHIP',
 VALUE='120',
 PRIM_FILE='W:/<user>/logical/q_res/chips/chips.prt';

PART_NAME
 R345 'Q_RES_0402LF-120,1%,1/16W,CHIPA':;

SECTION_NUMBER 1
 '@SCM_LIB.SCM(SCH_1):PAGE20_I119@PURE_QUANTA.Q_RES(CHIPS)':
 C_PATH='@scm_lib.scm(sch_1):page20_i119@pure_quanta.q_res(chips)',
 P_PATH='@scm_lib.scm(sch_1):page20_i119@pure_quanta.q_res(chips)',
 PATH='I119',
 DRAWING='@SCM_LIB.SCM(SCH_1):PAGE20',
 PHYS_PAGE='20',
 XY='(3650,1175)',
 ROT='0',
 VER='1',
 PACK_TYPE='0402LF',
 LOCATION='R345',
 CDS_LIB='pure_quanta',
 CDS_PART_NAME='Q_RES_0402LF-120,1%,1/16W,CHIPA',
 WATTAGE='1/16W',
 TOLERANCE='1%',
 MATERIAL='CHIP',
 VALUE='120',
 PRIM_FILE='W:/<user>/logical/q_res/chips/chips.prt';

PART_NAME
 R346 'Q_RES_0402LF-120,1%,1/16W,CHIPA':;

SECTION_NUMBER 1
 '@SCM_LIB.SCM(SCH_1):PAGE20_I120@PURE_QUANTA.Q_RES(CHIPS)':
 C_PATH='@scm_lib.scm(sch_1):page20_i120@pure_quanta.q_res(chips)',
 P_PATH='@scm_lib.scm(sch_1):page20_i120@pure_quanta.q_res(chips)',
 PATH='I120',
 DRAWING='@SCM_LIB.SCM(SCH_1):PAGE20',
 PHYS_PAGE='20',
 XY='(3650,1025)',
 ROT='0',
 VER='1',
 PACK_TYPE='0402LF',
 LOCATION='R346',
 CDS_LIB='pure_quanta',
 CDS_PART_NAME='Q_RES_0402LF-120,1%,1/16W,CHIPA',
 WATTAGE='1/16W',
 TOLERANCE='1%',
 MATERIAL='CHIP',
 VALUE='120',
 PRIM_FILE='W:/<user>/logical/q_res/chips/chips.prt';

PART_NAME
 R347 'Q_RES_0402LF-120,1%,1/16W,CHIPA':;

SECTION_NUMBER 1
 '@SCM_LIB.SCM(SCH_1):PAGE20_I117@PURE_QUANTA.Q_RES(CHIPS)':
 C_PATH='@scm_lib.scm(sch_1):page20_i117@pure_quanta.q_res(chips)',
 P_PATH='@scm_lib.scm(sch_1):page20_i117@pure_quanta.q_res(chips)',
 PATH='I117',
 DRAWING='@SCM_LIB.SCM(SCH_1):PAGE20',
 PHYS_PAGE='20',
 XY='(3650,875)',
 ROT='0',
 VER='1',
 PACK_TYPE='0402LF',
 LOCATION='R347',
 CDS_LIB='pure_quanta',
 CDS_PART_NAME='Q_RES_0402LF-120,1%,1/16W,CHIPA',
 WATTAGE='1/16W',
 TOLERANCE='1%',
 MATERIAL='CHIP',
 VALUE='120',
 PRIM_FILE='W:/<user>/logical/q_res/chips/chips.prt';

PART_NAME
 R348 'Q_RES_0402LF-120,1%,1/16W,CHIPA':;

SECTION_NUMBER 1
 '@SCM_LIB.SCM(SCH_1):PAGE20_I118@PURE_QUANTA.Q_RES(CHIPS)':
 C_PATH='@scm_lib.scm(sch_1):page20_i118@pure_quanta.q_res(chips)',
 P_PATH='@scm_lib.scm(sch_1):page20_i118@pure_quanta.q_res(chips)',
 PATH='I118',
 DRAWING='@SCM_LIB.SCM(SCH_1):PAGE20',
 PHYS_PAGE='20',
 XY='(3650,725)',
 ROT='0',
 VER='1',
 PACK_TYPE='0402LF',
 LOCATION='R348',
 CDS_LIB='pure_quanta',
 CDS_PART_NAME='Q_RES_0402LF-120,1%,1/16W,CHIPA',
 WATTAGE='1/16W',
 TOLERANCE='1%',
 MATERIAL='CHIP',
 VALUE='120',
 PRIM_FILE='W:/<user>/logical/q_res/chips/chips.prt';

PART_NAME
 R349 'Q_RES_0402LF-120,1%,1/16W,CHIPA':;

SECTION_NUMBER 1
 '@SCM_LIB.SCM(SCH_1):PAGE20_I116@PURE_QUANTA.Q_RES(CHIPS)':
 C_PATH='@scm_lib.scm(sch_1):page20_i116@pure_quanta.q_res(chips)',
 P_PATH='@scm_lib.scm(sch_1):page20_i116@pure_quanta.q_res(chips)',
 PATH='I116',
 DRAWING='@SCM_LIB.SCM(SCH_1):PAGE20',
 PHYS_PAGE='20',
 XY='(3650,575)',
 ROT='0',
 VER='1',
 PACK_TYPE='0402LF',
 LOCATION='R349',
 CDS_LIB='pure_quanta',
 CDS_PART_NAME='Q_RES_0402LF-120,1%,1/16W,CHIPA',
 WATTAGE='1/16W',
 TOLERANCE='1%',
 MATERIAL='CHIP',
 VALUE='120',
 PRIM_FILE='W:/<user>/logical/q_res/chips/chips.prt';

PART_NAME
 R350 'Q_RES_0402LF-120,1%,1/16W,EMPTA':;

SECTION_NUMBER 1
 '@SCM_LIB.SCM(SCH_1):PAGE20_I114@PURE_QUANTA.Q_RES(CHIPS)':
 C_PATH='@scm_lib.scm(sch_1):page20_i114@pure_quanta.q_res(chips)',
 P_PATH='@scm_lib.scm(sch_1):page20_i114@pure_quanta.q_res(chips)',
 PATH='I114',
 DRAWING='@SCM_LIB.SCM(SCH_1):PAGE20',
 PHYS_PAGE='20',
 XY='(3650,425)',
 ROT='0',
 VER='1',
 PACK_TYPE='0402LF',
 LOCATION='R350',
 CDS_LIB='pure_quanta',
 CDS_PART_NAME='Q_RES_0402LF-120,1%,1/16W,EMPTA',
 WATTAGE='1/16W',
 TOLERANCE='1%',
 MATERIAL='EMPTY',
 VALUE='120',
 PRIM_FILE='W:/<user>/logical/q_res/chips/chips.prt';

PART_NAME
 R351 'Q_RES_0402LF-120,1%,1/16W,CHIPA':;

SECTION_NUMBER 1
 '@SCM_LIB.SCM(SCH_1):PAGE20_I194@PURE_QUANTA.Q_RES(CHIPS)':
 C_PATH='@scm_lib.scm(sch_1):page20_i194@pure_quanta.q_res(chips)',
 P_PATH='@scm_lib.scm(sch_1):page20_i194@pure_quanta.q_res(chips)',
 PATH='I194',
 DRAWING='@SCM_LIB.SCM(SCH_1):PAGE20',
 PHYS_PAGE='20',
 XY='(4275,4650)',
 ROT='0',
 VER='1',
 PACK_TYPE='0402LF',
 LOCATION='R351',
 CDS_LIB='pure_quanta',
 CDS_PART_NAME='Q_RES_0402LF-120,1%,1/16W,CHIPA',
 WATTAGE='1/16W',
 TOLERANCE='1%',
 MATERIAL='CHIP',
 VALUE='120',
 PRIM_FILE='W:/<user>/logical/q_res/chips/chips.prt';

PART_NAME
 R352 'Q_RES_0402LF-120,1%,1/16W,CHIPA':;

SECTION_NUMBER 1
 '@SCM_LIB.SCM(SCH_1):PAGE20_I184@PURE_QUANTA.Q_RES(CHIPS)':
 C_PATH='@scm_lib.scm(sch_1):page20_i184@pure_quanta.q_res(chips)',
 P_PATH='@scm_lib.scm(sch_1):page20_i184@pure_quanta.q_res(chips)',
 PATH='I184',
 DRAWING='@SCM_LIB.SCM(SCH_1):PAGE20',
 PHYS_PAGE='20',
 XY='(4275,4500)',
 ROT='0',
 VER='1',
 PACK_TYPE='0402LF',
 LOCATION='R352',
 CDS_LIB='pure_quanta',
 CDS_PART_NAME='Q_RES_0402LF-120,1%,1/16W,CHIPA',
 WATTAGE='1/16W',
 TOLERANCE='1%',
 MATERIAL='CHIP',
 VALUE='120',
 PRIM_FILE='W:/<user>/logical/q_res/chips/chips.prt';

PART_NAME
 R353 'Q_RES_0402LF-120,1%,1/16W,CHIPA':;

SECTION_NUMBER 1
 '@SCM_LIB.SCM(SCH_1):PAGE20_I183@PURE_QUANTA.Q_RES(CHIPS)':
 C_PATH='@scm_lib.scm(sch_1):page20_i183@pure_quanta.q_res(chips)',
 P_PATH='@scm_lib.scm(sch_1):page20_i183@pure_quanta.q_res(chips)',
 PATH='I183',
 DRAWING='@SCM_LIB.SCM(SCH_1):PAGE20',
 PHYS_PAGE='20',
 XY='(4275,4350)',
 ROT='0',
 VER='1',
 PACK_TYPE='0402LF',
 LOCATION='R353',
 CDS_LIB='pure_quanta',
 CDS_PART_NAME='Q_RES_0402LF-120,1%,1/16W,CHIPA',
 WATTAGE='1/16W',
 TOLERANCE='1%',
 MATERIAL='CHIP',
 VALUE='120',
 PRIM_FILE='W:/<user>/logical/q_res/chips/chips.prt';

PART_NAME
 R354 'Q_RES_0402LF-120,1%,1/16W,CHIPA':;

SECTION_NUMBER 1
 '@SCM_LIB.SCM(SCH_1):PAGE20_I181@PURE_QUANTA.Q_RES(CHIPS)':
 C_PATH='@scm_lib.scm(sch_1):page20_i181@pure_quanta.q_res(chips)',
 P_PATH='@scm_lib.scm(sch_1):page20_i181@pure_quanta.q_res(chips)',
 PATH='I181',
 DRAWING='@SCM_LIB.SCM(SCH_1):PAGE20',
 PHYS_PAGE='20',
 XY='(4275,4200)',
 ROT='0',
 VER='1',
 PACK_TYPE='0402LF',
 LOCATION='R354',
 CDS_LIB='pure_quanta',
 CDS_PART_NAME='Q_RES_0402LF-120,1%,1/16W,CHIPA',
 WATTAGE='1/16W',
 TOLERANCE='1%',
 MATERIAL='CHIP',
 VALUE='120',
 PRIM_FILE='W:/<user>/logical/q_res/chips/chips.prt';

PART_NAME
 R355 'Q_RES_0402LF-120,1%,1/16W,CHIPA':;

SECTION_NUMBER 1
 '@SCM_LIB.SCM(SCH_1):PAGE20_I182@PURE_QUANTA.Q_RES(CHIPS)':
 C_PATH='@scm_lib.scm(sch_1):page20_i182@pure_quanta.q_res(chips)',
 P_PATH='@scm_lib.scm(sch_1):page20_i182@pure_quanta.q_res(chips)',
 PATH='I182',
 DRAWING='@SCM_LIB.SCM(SCH_1):PAGE20',
 PHYS_PAGE='20',
 XY='(4275,4050)',
 ROT='0',
 VER='1',
 PACK_TYPE='0402LF',
 LOCATION='R355',
 CDS_LIB='pure_quanta',
 CDS_PART_NAME='Q_RES_0402LF-120,1%,1/16W,CHIPA',
 WATTAGE='1/16W',
 TOLERANCE='1%',
 MATERIAL='CHIP',
 VALUE='120',
 PRIM_FILE='W:/<user>/logical/q_res/chips/chips.prt';

PART_NAME
 R356 'Q_RES_0402LF-120,1%,1/16W,CHIPA':;

SECTION_NUMBER 1
 '@SCM_LIB.SCM(SCH_1):PAGE20_I180@PURE_QUANTA.Q_RES(CHIPS)':
 C_PATH='@scm_lib.scm(sch_1):page20_i180@pure_quanta.q_res(chips)',
 P_PATH='@scm_lib.scm(sch_1):page20_i180@pure_quanta.q_res(chips)',
 PATH='I180',
 DRAWING='@SCM_LIB.SCM(SCH_1):PAGE20',
 PHYS_PAGE='20',
 XY='(4275,3900)',
 ROT='0',
 VER='1',
 PACK_TYPE='0402LF',
 LOCATION='R356',
 CDS_LIB='pure_quanta',
 CDS_PART_NAME='Q_RES_0402LF-120,1%,1/16W,CHIPA',
 WATTAGE='1/16W',
 TOLERANCE='1%',
 MATERIAL='CHIP',
 VALUE='120',
 PRIM_FILE='W:/<user>/logical/q_res/chips/chips.prt';

PART_NAME
 R357 'Q_RES_0402LF-120,1%,1/16W,CHIPA':;

SECTION_NUMBER 1
 '@SCM_LIB.SCM(SCH_1):PAGE20_I179@PURE_QUANTA.Q_RES(CHIPS)':
 C_PATH='@scm_lib.scm(sch_1):page20_i179@pure_quanta.q_res(chips)',
 P_PATH='@scm_lib.scm(sch_1):page20_i179@pure_quanta.q_res(chips)',
 PATH='I179',
 DRAWING='@SCM_LIB.SCM(SCH_1):PAGE20',
 PHYS_PAGE='20',
 XY='(4275,3750)',
 ROT='0',
 VER='1',
 PACK_TYPE='0402LF',
 LOCATION='R357',
 CDS_LIB='pure_quanta',
 CDS_PART_NAME='Q_RES_0402LF-120,1%,1/16W,CHIPA',
 WATTAGE='1/16W',
 TOLERANCE='1%',
 MATERIAL='CHIP',
 VALUE='120',
 PRIM_FILE='W:/<user>/logical/q_res/chips/chips.prt';

PART_NAME
 R358 'Q_RES_0402LF-120,1%,1/16W,CHIPA':;

SECTION_NUMBER 1
 '@SCM_LIB.SCM(SCH_1):PAGE20_I178@PURE_QUANTA.Q_RES(CHIPS)':
 C_PATH='@scm_lib.scm(sch_1):page20_i178@pure_quanta.q_res(chips)',
 P_PATH='@scm_lib.scm(sch_1):page20_i178@pure_quanta.q_res(chips)',
 PATH='I178',
 DRAWING='@SCM_LIB.SCM(SCH_1):PAGE20',
 PHYS_PAGE='20',
 XY='(4275,3600)',
 ROT='0',
 VER='1',
 PACK_TYPE='0402LF',
 LOCATION='R358',
 CDS_LIB='pure_quanta',
 CDS_PART_NAME='Q_RES_0402LF-120,1%,1/16W,CHIPA',
 WATTAGE='1/16W',
 TOLERANCE='1%',
 MATERIAL='CHIP',
 VALUE='120',
 PRIM_FILE='W:/<user>/logical/q_res/chips/chips.prt';

PART_NAME
 R359 'Q_RES_0402LF-120,1%,1/16W,CHIPA':;

SECTION_NUMBER 1
 '@SCM_LIB.SCM(SCH_1):PAGE20_I170@PURE_QUANTA.Q_RES(CHIPS)':
 C_PATH='@scm_lib.scm(sch_1):page20_i170@pure_quanta.q_res(chips)',
 P_PATH='@scm_lib.scm(sch_1):page20_i170@pure_quanta.q_res(chips)',
 PATH='I170',
 DRAWING='@SCM_LIB.SCM(SCH_1):PAGE20',
 PHYS_PAGE='20',
 XY='(4275,3450)',
 ROT='0',
 VER='1',
 PACK_TYPE='0402LF',
 LOCATION='R359',
 CDS_LIB='pure_quanta',
 CDS_PART_NAME='Q_RES_0402LF-120,1%,1/16W,CHIPA',
 WATTAGE='1/16W',
 TOLERANCE='1%',
 MATERIAL='CHIP',
 VALUE='120',
 PRIM_FILE='W:/<user>/logical/q_res/chips/chips.prt';

PART_NAME
 R360 'Q_RES_0402LF-120,1%,1/16W,CHIPA':;

SECTION_NUMBER 1
 '@SCM_LIB.SCM(SCH_1):PAGE20_I169@PURE_QUANTA.Q_RES(CHIPS)':
 C_PATH='@scm_lib.scm(sch_1):page20_i169@pure_quanta.q_res(chips)',
 P_PATH='@scm_lib.scm(sch_1):page20_i169@pure_quanta.q_res(chips)',
 PATH='I169',
 DRAWING='@SCM_LIB.SCM(SCH_1):PAGE20',
 PHYS_PAGE='20',
 XY='(4275,3300)',
 ROT='0',
 VER='1',
 PACK_TYPE='0402LF',
 LOCATION='R360',
 CDS_LIB='pure_quanta',
 CDS_PART_NAME='Q_RES_0402LF-120,1%,1/16W,CHIPA',
 WATTAGE='1/16W',
 TOLERANCE='1%',
 MATERIAL='CHIP',
 VALUE='120',
 PRIM_FILE='W:/<user>/logical/q_res/chips/chips.prt';

PART_NAME
 R361 'Q_RES_0402LF-120,1%,1/16W,CHIPA':;

SECTION_NUMBER 1
 '@SCM_LIB.SCM(SCH_1):PAGE20_I167@PURE_QUANTA.Q_RES(CHIPS)':
 C_PATH='@scm_lib.scm(sch_1):page20_i167@pure_quanta.q_res(chips)',
 P_PATH='@scm_lib.scm(sch_1):page20_i167@pure_quanta.q_res(chips)',
 PATH='I167',
 DRAWING='@SCM_LIB.SCM(SCH_1):PAGE20',
 PHYS_PAGE='20',
 XY='(4275,3150)',
 ROT='0',
 VER='1',
 PACK_TYPE='0402LF',
 LOCATION='R361',
 CDS_LIB='pure_quanta',
 CDS_PART_NAME='Q_RES_0402LF-120,1%,1/16W,CHIPA',
 WATTAGE='1/16W',
 TOLERANCE='1%',
 MATERIAL='CHIP',
 VALUE='120',
 PRIM_FILE='W:/<user>/logical/q_res/chips/chips.prt';

PART_NAME
 R362 'Q_RES_0402LF-120,1%,1/16W,CHIPA':;

SECTION_NUMBER 1
 '@SCM_LIB.SCM(SCH_1):PAGE20_I168@PURE_QUANTA.Q_RES(CHIPS)':
 C_PATH='@scm_lib.scm(sch_1):page20_i168@pure_quanta.q_res(chips)',
 P_PATH='@scm_lib.scm(sch_1):page20_i168@pure_quanta.q_res(chips)',
 PATH='I168',
 DRAWING='@SCM_LIB.SCM(SCH_1):PAGE20',
 PHYS_PAGE='20',
 XY='(4275,3000)',
 ROT='0',
 VER='1',
 PACK_TYPE='0402LF',
 LOCATION='R362',
 CDS_LIB='pure_quanta',
 CDS_PART_NAME='Q_RES_0402LF-120,1%,1/16W,CHIPA',
 WATTAGE='1/16W',
 TOLERANCE='1%',
 MATERIAL='CHIP',
 VALUE='120',
 PRIM_FILE='W:/<user>/logical/q_res/chips/chips.prt';

PART_NAME
 R363 'Q_RES_0402LF-120,1%,1/16W,CHIPA':;

SECTION_NUMBER 1
 '@SCM_LIB.SCM(SCH_1):PAGE20_I166@PURE_QUANTA.Q_RES(CHIPS)':
 C_PATH='@scm_lib.scm(sch_1):page20_i166@pure_quanta.q_res(chips)',
 P_PATH='@scm_lib.scm(sch_1):page20_i166@pure_quanta.q_res(chips)',
 PATH='I166',
 DRAWING='@SCM_LIB.SCM(SCH_1):PAGE20',
 PHYS_PAGE='20',
 XY='(4275,2850)',
 ROT='0',
 VER='1',
 PACK_TYPE='0402LF',
 LOCATION='R363',
 CDS_LIB='pure_quanta',
 CDS_PART_NAME='Q_RES_0402LF-120,1%,1/16W,CHIPA',
 WATTAGE='1/16W',
 TOLERANCE='1%',
 MATERIAL='CHIP',
 VALUE='120',
 PRIM_FILE='W:/<user>/logical/q_res/chips/chips.prt';

PART_NAME
 R364 'Q_RES_0402LF-120,1%,1/16W,CHIPA':;

SECTION_NUMBER 1
 '@SCM_LIB.SCM(SCH_1):PAGE20_I165@PURE_QUANTA.Q_RES(CHIPS)':
 C_PATH='@scm_lib.scm(sch_1):page20_i165@pure_quanta.q_res(chips)',
 P_PATH='@scm_lib.scm(sch_1):page20_i165@pure_quanta.q_res(chips)',
 PATH='I165',
 DRAWING='@SCM_LIB.SCM(SCH_1):PAGE20',
 PHYS_PAGE='20',
 XY='(4275,2700)',
 ROT='0',
 VER='1',
 PACK_TYPE='0402LF',
 LOCATION='R364',
 CDS_LIB='pure_quanta',
 CDS_PART_NAME='Q_RES_0402LF-120,1%,1/16W,CHIPA',
 WATTAGE='1/16W',
 TOLERANCE='1%',
 MATERIAL='CHIP',
 VALUE='120',
 PRIM_FILE='W:/<user>/logical/q_res/chips/chips.prt';

PART_NAME
 R365 'Q_RES_0402LF-120,1%,1/16W,CHIPA':;

SECTION_NUMBER 1
 '@SCM_LIB.SCM(SCH_1):PAGE20_I138@PURE_QUANTA.Q_RES(CHIPS)':
 C_PATH='@scm_lib.scm(sch_1):page20_i138@pure_quanta.q_res(chips)',
 P_PATH='@scm_lib.scm(sch_1):page20_i138@pure_quanta.q_res(chips)',
 PATH='I138',
 DRAWING='@SCM_LIB.SCM(SCH_1):PAGE20',
 PHYS_PAGE='20',
 XY='(4325,1925)',
 ROT='0',
 VER='1',
 PACK_TYPE='0402LF',
 LOCATION='R365',
 CDS_LIB='pure_quanta',
 CDS_PART_NAME='Q_RES_0402LF-120,1%,1/16W,CHIPA',
 WATTAGE='1/16W',
 TOLERANCE='1%',
 MATERIAL='CHIP',
 VALUE='120',
 PRIM_FILE='W:/<user>/logical/q_res/chips/chips.prt';

PART_NAME
 R366 'Q_RES_0402LF-120,1%,1/16W,CHIPA':;

SECTION_NUMBER 1
 '@SCM_LIB.SCM(SCH_1):PAGE20_I137@PURE_QUANTA.Q_RES(CHIPS)':
 C_PATH='@scm_lib.scm(sch_1):page20_i137@pure_quanta.q_res(chips)',
 P_PATH='@scm_lib.scm(sch_1):page20_i137@pure_quanta.q_res(chips)',
 PATH='I137',
 DRAWING='@SCM_LIB.SCM(SCH_1):PAGE20',
 PHYS_PAGE='20',
 XY='(4325,1775)',
 ROT='0',
 VER='1',
 PACK_TYPE='0402LF',
 LOCATION='R366',
 CDS_LIB='pure_quanta',
 CDS_PART_NAME='Q_RES_0402LF-120,1%,1/16W,CHIPA',
 WATTAGE='1/16W',
 TOLERANCE='1%',
 MATERIAL='CHIP',
 VALUE='120',
 PRIM_FILE='W:/<user>/logical/q_res/chips/chips.prt';

PART_NAME
 R367 'Q_RES_0402LF-120,1%,1/16W,CHIPA':;

SECTION_NUMBER 1
 '@SCM_LIB.SCM(SCH_1):PAGE20_I136@PURE_QUANTA.Q_RES(CHIPS)':
 C_PATH='@scm_lib.scm(sch_1):page20_i136@pure_quanta.q_res(chips)',
 P_PATH='@scm_lib.scm(sch_1):page20_i136@pure_quanta.q_res(chips)',
 PATH='I136',
 DRAWING='@SCM_LIB.SCM(SCH_1):PAGE20',
 PHYS_PAGE='20',
 XY='(4325,1625)',
 ROT='0',
 VER='1',
 PACK_TYPE='0402LF',
 LOCATION='R367',
 CDS_LIB='pure_quanta',
 CDS_PART_NAME='Q_RES_0402LF-120,1%,1/16W,CHIPA',
 WATTAGE='1/16W',
 TOLERANCE='1%',
 MATERIAL='CHIP',
 VALUE='120',
 PRIM_FILE='W:/<user>/logical/q_res/chips/chips.prt';

PART_NAME
 R368 'Q_RES_0402LF-120,1%,1/16W,CHIPA':;

SECTION_NUMBER 1
 '@SCM_LIB.SCM(SCH_1):PAGE20_I135@PURE_QUANTA.Q_RES(CHIPS)':
 C_PATH='@scm_lib.scm(sch_1):page20_i135@pure_quanta.q_res(chips)',
 P_PATH='@scm_lib.scm(sch_1):page20_i135@pure_quanta.q_res(chips)',
 PATH='I135',
 DRAWING='@SCM_LIB.SCM(SCH_1):PAGE20',
 PHYS_PAGE='20',
 XY='(4325,1475)',
 ROT='0',
 VER='1',
 PACK_TYPE='0402LF',
 LOCATION='R368',
 CDS_LIB='pure_quanta',
 CDS_PART_NAME='Q_RES_0402LF-120,1%,1/16W,CHIPA',
 WATTAGE='1/16W',
 TOLERANCE='1%',
 MATERIAL='CHIP',
 VALUE='120',
 PRIM_FILE='W:/<user>/logical/q_res/chips/chips.prt';

PART_NAME
 R369 'Q_RES_0402LF-120,1%,1/16W,CHIPA':;

SECTION_NUMBER 1
 '@SCM_LIB.SCM(SCH_1):PAGE20_I132@PURE_QUANTA.Q_RES(CHIPS)':
 C_PATH='@scm_lib.scm(sch_1):page20_i132@pure_quanta.q_res(chips)',
 P_PATH='@scm_lib.scm(sch_1):page20_i132@pure_quanta.q_res(chips)',
 PATH='I132',
 DRAWING='@SCM_LIB.SCM(SCH_1):PAGE20',
 PHYS_PAGE='20',
 XY='(4325,1325)',
 ROT='0',
 VER='1',
 PACK_TYPE='0402LF',
 LOCATION='R369',
 CDS_LIB='pure_quanta',
 CDS_PART_NAME='Q_RES_0402LF-120,1%,1/16W,CHIPA',
 WATTAGE='1/16W',
 TOLERANCE='1%',
 MATERIAL='CHIP',
 VALUE='120',
 PRIM_FILE='W:/<user>/logical/q_res/chips/chips.prt';

PART_NAME
 R370 'Q_RES_0402LF-120,1%,1/16W,CHIPA':;

SECTION_NUMBER 1
 '@SCM_LIB.SCM(SCH_1):PAGE20_I131@PURE_QUANTA.Q_RES(CHIPS)':
 C_PATH='@scm_lib.scm(sch_1):page20_i131@pure_quanta.q_res(chips)',
 P_PATH='@scm_lib.scm(sch_1):page20_i131@pure_quanta.q_res(chips)',
 PATH='I131',
 DRAWING='@SCM_LIB.SCM(SCH_1):PAGE20',
 PHYS_PAGE='20',
 XY='(4325,1175)',
 ROT='0',
 VER='1',
 PACK_TYPE='0402LF',
 LOCATION='R370',
 CDS_LIB='pure_quanta',
 CDS_PART_NAME='Q_RES_0402LF-120,1%,1/16W,CHIPA',
 WATTAGE='1/16W',
 TOLERANCE='1%',
 MATERIAL='CHIP',
 VALUE='120',
 PRIM_FILE='W:/<user>/logical/q_res/chips/chips.prt';

PART_NAME
 R371 'Q_RES_0402LF-120,1%,1/16W,CHIPA':;

SECTION_NUMBER 1
 '@SCM_LIB.SCM(SCH_1):PAGE20_I130@PURE_QUANTA.Q_RES(CHIPS)':
 C_PATH='@scm_lib.scm(sch_1):page20_i130@pure_quanta.q_res(chips)',
 P_PATH='@scm_lib.scm(sch_1):page20_i130@pure_quanta.q_res(chips)',
 PATH='I130',
 DRAWING='@SCM_LIB.SCM(SCH_1):PAGE20',
 PHYS_PAGE='20',
 XY='(4325,1025)',
 ROT='0',
 VER='1',
 PACK_TYPE='0402LF',
 LOCATION='R371',
 CDS_LIB='pure_quanta',
 CDS_PART_NAME='Q_RES_0402LF-120,1%,1/16W,CHIPA',
 WATTAGE='1/16W',
 TOLERANCE='1%',
 MATERIAL='CHIP',
 VALUE='120',
 PRIM_FILE='W:/<user>/logical/q_res/chips/chips.prt';

PART_NAME
 R372 'Q_RES_0402LF-120,1%,1/16W,CHIPA':;

SECTION_NUMBER 1
 '@SCM_LIB.SCM(SCH_1):PAGE20_I129@PURE_QUANTA.Q_RES(CHIPS)':
 C_PATH='@scm_lib.scm(sch_1):page20_i129@pure_quanta.q_res(chips)',
 P_PATH='@scm_lib.scm(sch_1):page20_i129@pure_quanta.q_res(chips)',
 PATH='I129',
 DRAWING='@SCM_LIB.SCM(SCH_1):PAGE20',
 PHYS_PAGE='20',
 XY='(4325,875)',
 ROT='0',
 VER='1',
 PACK_TYPE='0402LF',
 LOCATION='R372',
 CDS_LIB='pure_quanta',
 CDS_PART_NAME='Q_RES_0402LF-120,1%,1/16W,CHIPA',
 WATTAGE='1/16W',
 TOLERANCE='1%',
 MATERIAL='CHIP',
 VALUE='120',
 PRIM_FILE='W:/<user>/logical/q_res/chips/chips.prt';

PART_NAME
 R373 'Q_RES_0402LF-120,1%,1/16W,CHIPA':;

SECTION_NUMBER 1
 '@SCM_LIB.SCM(SCH_1):PAGE20_I128@PURE_QUANTA.Q_RES(CHIPS)':
 C_PATH='@scm_lib.scm(sch_1):page20_i128@pure_quanta.q_res(chips)',
 P_PATH='@scm_lib.scm(sch_1):page20_i128@pure_quanta.q_res(chips)',
 PATH='I128',
 DRAWING='@SCM_LIB.SCM(SCH_1):PAGE20',
 PHYS_PAGE='20',
 XY='(4325,725)',
 ROT='0',
 VER='1',
 PACK_TYPE='0402LF',
 LOCATION='R373',
 CDS_LIB='pure_quanta',
 CDS_PART_NAME='Q_RES_0402LF-120,1%,1/16W,CHIPA',
 WATTAGE='1/16W',
 TOLERANCE='1%',
 MATERIAL='CHIP',
 VALUE='120',
 PRIM_FILE='W:/<user>/logical/q_res/chips/chips.prt';

PART_NAME
 R374 'Q_RES_0402LF-120,1%,1/16W,CHIPA':;

SECTION_NUMBER 1
 '@SCM_LIB.SCM(SCH_1):PAGE20_I127@PURE_QUANTA.Q_RES(CHIPS)':
 C_PATH='@scm_lib.scm(sch_1):page20_i127@pure_quanta.q_res(chips)',
 P_PATH='@scm_lib.scm(sch_1):page20_i127@pure_quanta.q_res(chips)',
 PATH='I127',
 DRAWING='@SCM_LIB.SCM(SCH_1):PAGE20',
 PHYS_PAGE='20',
 XY='(4325,575)',
 ROT='0',
 VER='1',
 PACK_TYPE='0402LF',
 LOCATION='R374',
 CDS_LIB='pure_quanta',
 CDS_PART_NAME='Q_RES_0402LF-120,1%,1/16W,CHIPA',
 WATTAGE='1/16W',
 TOLERANCE='1%',
 MATERIAL='CHIP',
 VALUE='120',
 PRIM_FILE='W:/<user>/logical/q_res/chips/chips.prt';

PART_NAME
 R375 'Q_RES_0402LF-120,1%,1/16W,EMPTA':;

SECTION_NUMBER 1
 '@SCM_LIB.SCM(SCH_1):PAGE20_I115@PURE_QUANTA.Q_RES(CHIPS)':
 C_PATH='@scm_lib.scm(sch_1):page20_i115@pure_quanta.q_res(chips)',
 P_PATH='@scm_lib.scm(sch_1):page20_i115@pure_quanta.q_res(chips)',
 PATH='I115',
 DRAWING='@SCM_LIB.SCM(SCH_1):PAGE20',
 PHYS_PAGE='20',
 XY='(4325,425)',
 ROT='0',
 VER='1',
 PACK_TYPE='0402LF',
 LOCATION='R375',
 CDS_LIB='pure_quanta',
 CDS_PART_NAME='Q_RES_0402LF-120,1%,1/16W,EMPTA',
 WATTAGE='1/16W',
 TOLERANCE='1%',
 MATERIAL='EMPTY',
 VALUE='120',
 PRIM_FILE='W:/<user>/logical/q_res/chips/chips.prt';

PART_NAME
 R376 'Q_RES_0402LF-4.7K,1%,1/16W,CHIA':;

SECTION_NUMBER 1
 '@SCM_LIB.SCM(SCH_1):PAGE28_I62@PURE_QUANTA.Q_RES(CHIPS)':
 C_PATH='@scm_lib.scm(sch_1):page28_i62@pure_quanta.q_res(chips)',
 P_PATH='@scm_lib.scm(sch_1):page28_i62@pure_quanta.q_res(chips)',
 PATH='I62',
 DRAWING='@SCM_LIB.SCM(SCH_1):PAGE28',
 PHYS_PAGE='28',
 XY='(-1200,1400)',
 ROT='2',
 VER='2',
 PACK_TYPE='0402LF',
 LOCATION='R376',
 CDS_LIB='pure_quanta',
 CDS_PART_NAME='Q_RES_0402LF-4.7K,1%,1/16W,CHIA',
 WATTAGE='1/16W',
 TOLERANCE='1%',
 MATERIAL='CHIP',
 VALUE='4.7K',
 PRIM_FILE='W:/<user>/logical/q_res/chips/chips.prt';

PART_NAME
 R377 'Q_RES_0402LF-10K,1%,1/16W,EMPTA':;

SECTION_NUMBER 1
 '@SCM_LIB.SCM(SCH_1):PAGE28_I63@PURE_QUANTA.Q_RES(CHIPS)':
 C_PATH='@scm_lib.scm(sch_1):page28_i63@pure_quanta.q_res(chips)',
 P_PATH='@scm_lib.scm(sch_1):page28_i63@pure_quanta.q_res(chips)',
 PATH='I63',
 DRAWING='@SCM_LIB.SCM(SCH_1):PAGE28',
 PHYS_PAGE='28',
 XY='(-1200,925)',
 ROT='2',
 VER='2',
 PACK_TYPE='0402LF',
 LOCATION='R377',
 CDS_LIB='pure_quanta',
 CDS_PART_NAME='Q_RES_0402LF-10K,1%,1/16W,EMPTA',
 WATTAGE='1/16W',
 TOLERANCE='1%',
 MATERIAL='EMPTY',
 VALUE='10K',
 PRIM_FILE='W:/<user>/logical/q_res/chips/chips.prt';

PART_NAME
 R378 'Q_RES_0402LF-20K,1%,1/16W,CHIPA':;

SECTION_NUMBER 1
 '@SCM_LIB.SCM(SCH_1):PAGE28_I54@PURE_QUANTA.Q_RES(CHIPS)':
 C_PATH='@scm_lib.scm(sch_1):page28_i54@pure_quanta.q_res(chips)',
 P_PATH='@scm_lib.scm(sch_1):page28_i54@pure_quanta.q_res(chips)',
 PATH='I54',
 DRAWING='@SCM_LIB.SCM(SCH_1):PAGE28',
 PHYS_PAGE='28',
 XY='(-1000,1000)',
 ROT='0',
 VER='2',
 PACK_TYPE='0402LF',
 LOCATION='R378',
 CDS_LIB='pure_quanta',
 CDS_PART_NAME='Q_RES_0402LF-20K,1%,1/16W,CHIPA',
 WATTAGE='1/16W',
 TOLERANCE='1%',
 MATERIAL='CHIP',
 VALUE='20K',
 PRIM_FILE='W:/<user>/logical/q_res/chips/chips.prt';

PART_NAME
 R379 'Q_RES_0402LF-0,5%,1/16W,CHIP,CA':;

SECTION_NUMBER 1
 '@SCM_LIB.SCM(SCH_1):PAGE36_I36@PURE_QUANTA.Q_RES(CHIPS)':
 C_PATH='@scm_lib.scm(sch_1):page36_i36@pure_quanta.q_res(chips)',
 P_PATH='@scm_lib.scm(sch_1):page36_i36@pure_quanta.q_res(chips)',
 PATH='I36',
 DRAWING='@SCM_LIB.SCM(SCH_1):PAGE36',
 SEC_TYPE='0402LF',
 PHYS_PAGE='36',
 XY='(-2575,5075)',
 ROT='0',
 VER='1',
 PACK_TYPE='0402LF',
 LOCATION='R379',
 SEC='1',
 CDS_LIB='pure_quanta',
 CDS_PART_NAME='Q_RES_0402LF-0,5%,1/16W,CHIP,CA',
 WATTAGE='1/16W',
 TOLERANCE='5%',
 MATERIAL='CHIP',
 VALUE='0',
 PRIM_FILE='W:/<user>/logical/q_res/chips/chips.prt';

PART_NAME
 R380 'Q_RES_0402LF-100,1%,1/16W,CHIPA':;

SECTION_NUMBER 1
 '@SCM_LIB.SCM(SCH_1):PAGE52_I147@PURE_QUANTA.Q_RES(CHIPS)':
 C_PATH='@scm_lib.scm(sch_1):page52_i147@pure_quanta.q_res(chips)',
 P_PATH='@scm_lib.scm(sch_1):page52_i147@pure_quanta.q_res(chips)',
 PATH='I147',
 DRAWING='@SCM_LIB.SCM(SCH_1):PAGE52',
 PHYS_PAGE='52',
 XY='(-2500,-1800)',
 ROT='0',
 VER='1',
 PACK_TYPE='0402LF',
 LOCATION='R380',
 CDS_LIB='pure_quanta',
 CDS_PART_NAME='Q_RES_0402LF-100,1%,1/16W,CHIPA',
 WATTAGE='1/16W',
 TOLERANCE='1%',
 MATERIAL='CHIP',
 VALUE='100',
 PRIM_FILE='W:/<user>/logical/q_res/chips/chips.prt';

PART_NAME
 R381 'Q_RES_0402LF-0,5%,1/16W,CHIP,CA':;

SECTION_NUMBER 1
 '@SCM_LIB.SCM(SCH_1):PAGE52_I97@PURE_QUANTA.Q_RES(CHIPS)':
 C_PATH='@scm_lib.scm(sch_1):page52_i97@pure_quanta.q_res(chips)',
 P_PATH='@scm_lib.scm(sch_1):page52_i97@pure_quanta.q_res(chips)',
 PATH='I97',
 DRAWING='@SCM_LIB.SCM(SCH_1):PAGE52',
 PHYS_PAGE='52',
 XY='(-1625,1325)',
 ROT='0',
 VER='1',
 PACK_TYPE='0402LF',
 LOCATION='R381',
 CDS_LIB='pure_quanta',
 CDS_PART_NAME='Q_RES_0402LF-0,5%,1/16W,CHIP,CA',
 WATTAGE='1/16W',
 TOLERANCE='5%',
 MATERIAL='CHIP',
 VALUE='0',
 PRIM_FILE='W:/<user>/logical/q_res/chips/chips.prt';

PART_NAME
 R382 'Q_RES_0402LF-0,5%,1/16W,CHIP,CA':;

SECTION_NUMBER 1
 '@SCM_LIB.SCM(SCH_1):PAGE53_I65@PURE_QUANTA.Q_RES(CHIPS)':
 C_PATH='@scm_lib.scm(sch_1):page53_i65@pure_quanta.q_res(chips)',
 P_PATH='@scm_lib.scm(sch_1):page53_i65@pure_quanta.q_res(chips)',
 PATH='I65',
 DRAWING='@SCM_LIB.SCM(SCH_1):PAGE53',
 PHYS_PAGE='53',
 XY='(-2000,425)',
 ROT='0',
 VER='1',
 PACK_TYPE='0402LF',
 LOCATION='R382',
 CDS_LIB='pure_quanta',
 CDS_PART_NAME='Q_RES_0402LF-0,5%,1/16W,CHIP,CA',
 WATTAGE='1/16W',
 TOLERANCE='5%',
 MATERIAL='CHIP',
 VALUE='0',
 PRIM_FILE='W:/<user>/logical/q_res/chips/chips.prt';

PART_NAME
 R383 'Q_RES_0402LF-10K,1%,1/16W,CHIPA':;

SECTION_NUMBER 1
 '@SCM_LIB.SCM(SCH_1):PAGE28_I42@PURE_QUANTA.Q_RES(CHIPS)':
 C_PATH='@scm_lib.scm(sch_1):page28_i42@pure_quanta.q_res(chips)',
 P_PATH='@scm_lib.scm(sch_1):page28_i42@pure_quanta.q_res(chips)',
 PATH='I42',
 DRAWING='@SCM_LIB.SCM(SCH_1):PAGE28',
 PHYS_PAGE='28',
 XY='(950,1525)',
 ROT='0',
 VER='2',
 PACK_TYPE='0402LF',
 LOCATION='R383',
 CDS_LIB='pure_quanta',
 CDS_PART_NAME='Q_RES_0402LF-10K,1%,1/16W,CHIPA',
 WATTAGE='1/16W',
 TOLERANCE='1%',
 MATERIAL='CHIP',
 VALUE='10K',
 PRIM_FILE='W:/<user>/logical/q_res/chips/chips.prt';

PART_NAME
 R384 'Q_RES_0402LF-100,1%,1/16W,CHIPA':;

SECTION_NUMBER 1
 '@SCM_LIB.SCM(SCH_1):PAGE28_I185@PURE_QUANTA.Q_RES(CHIPS)':
 C_PATH='@scm_lib.scm(sch_1):page28_i185@pure_quanta.q_res(chips)',
 P_PATH='@scm_lib.scm(sch_1):page28_i185@pure_quanta.q_res(chips)',
 PATH='I185',
 DRAWING='@SCM_LIB.SCM(SCH_1):PAGE28',
 PHYS_PAGE='28',
 XY='(1250,1250)',
 ROT='0',
 VER='1',
 PACK_TYPE='0402LF',
 LOCATION='R384',
 CDS_LIB='pure_quanta',
 CDS_PART_NAME='Q_RES_0402LF-100,1%,1/16W,CHIPA',
 WATTAGE='1/16W',
 TOLERANCE='1%',
 MATERIAL='CHIP',
 VALUE='100',
 PRIM_FILE='W:/<user>/logical/q_res/chips/chips.prt';

PART_NAME
 R385 'Q_RES_0402LF-0,5%,1/16W,CHIP,CA':;

SECTION_NUMBER 1
 '@SCM_LIB.SCM(SCH_1):PAGE29_I96@PURE_QUANTA.Q_RES(CHIPS)':
 C_PATH='@scm_lib.scm(sch_1):page29_i96@pure_quanta.q_res(chips)',
 P_PATH='@scm_lib.scm(sch_1):page29_i96@pure_quanta.q_res(chips)',
 PATH='I96',
 DRAWING='@SCM_LIB.SCM(SCH_1):PAGE29',
 PHYS_PAGE='29',
 XY='(-2450,2050)',
 ROT='0',
 VER='1',
 PACK_TYPE='0402LF',
 LOCATION='R385',
 CDS_LIB='pure_quanta',
 CDS_PART_NAME='Q_RES_0402LF-0,5%,1/16W,CHIP,CA',
 WATTAGE='1/16W',
 TOLERANCE='5%',
 MATERIAL='CHIP',
 VALUE='0',
 PRIM_FILE='W:/<user>/logical/q_res/chips/chips.prt';

PART_NAME
 R386 'Q_RES_0402LF-0,5%,1/16W,CHIP,CA':;

SECTION_NUMBER 1
 '@SCM_LIB.SCM(SCH_1):PAGE29_I101@PURE_QUANTA.Q_RES(CHIPS)':
 C_PATH='@scm_lib.scm(sch_1):page29_i101@pure_quanta.q_res(chips)',
 P_PATH='@scm_lib.scm(sch_1):page29_i101@pure_quanta.q_res(chips)',
 PATH='I101',
 DRAWING='@SCM_LIB.SCM(SCH_1):PAGE29',
 PHYS_PAGE='29',
 XY='(-2250,1115)',
 ROT='0',
 VER='1',
 PACK_TYPE='0402LF',
 LOCATION='R386',
 CDS_LIB='pure_quanta',
 CDS_PART_NAME='Q_RES_0402LF-0,5%,1/16W,CHIP,CA',
 WATTAGE='1/16W',
 TOLERANCE='5%',
 MATERIAL='CHIP',
 VALUE='0',
 PRIM_FILE='W:/<user>/logical/q_res/chips/chips.prt';

PART_NAME
 R387 'Q_RES_0402LF-100K,1%,1/16W,CHIA':;

SECTION_NUMBER 1
 '@SCM_LIB.SCM(SCH_1):PAGE12_I508@PURE_QUANTA.Q_RES(CHIPS)':
 C_PATH='@scm_lib.scm(sch_1):page12_i508@pure_quanta.q_res(chips)',
 P_PATH='@scm_lib.scm(sch_1):page12_i508@pure_quanta.q_res(chips)',
 PATH='I508',
 DRAWING='@SCM_LIB.SCM(SCH_1):PAGE12',
 PHYS_PAGE='12',
 XY='(-575,3800)',
 ROT='0',
 VER='1',
 PACK_TYPE='0402LF',
 CDS_LIB='pure_quanta',
 CDS_PART_NAME='Q_RES_0402LF-100K,1%,1/16W,CHIA',
 WATTAGE='1/16W',
 TOLERANCE='1%',
 MATERIAL='CHIP',
 VALUE='100K',
 PRIM_FILE='W:/<user>/logical/q_res/chips/chips.prt';

PART_NAME
 R388 'Q_RES_0402LF-33.2,1%,1/16W,CHIA':;

SECTION_NUMBER 1
 '@SCM_LIB.SCM(SCH_1):PAGE22_I92@PURE_QUANTA.Q_RES(CHIPS)':
 C_PATH='@scm_lib.scm(sch_1):page22_i92@pure_quanta.q_res(chips)',
 P_PATH='@scm_lib.scm(sch_1):page22_i92@pure_quanta.q_res(chips)',
 PATH='I92',
 DRAWING='@SCM_LIB.SCM(SCH_1):PAGE22',
 PHYS_PAGE='22',
 XY='(-3075,1000)',
 ROT='0',
 VER='1',
 PACK_TYPE='0402LF',
 CDS_LIB='pure_quanta',
 CDS_PART_NAME='Q_RES_0402LF-33.2,1%,1/16W,CHIA',
 WATTAGE='1/16W',
 TOLERANCE='1%',
 MATERIAL='CHIP',
 VALUE='33.2',
 PRIM_FILE='W:/<user>/logical/q_res/chips/chips.prt';

PART_NAME
 R389 'Q_RES_0402LF-316,1%,1/16W,CHIPA':;

SECTION_NUMBER 1
 '@SCM_LIB.SCM(SCH_1):PAGE50_I225@PURE_QUANTA.Q_RES(CHIPS)':
 C_PATH='@scm_lib.scm(sch_1):page50_i225@pure_quanta.q_res(chips)',
 P_PATH='@scm_lib.scm(sch_1):page50_i225@pure_quanta.q_res(chips)',
 PATH='I225',
 DRAWING='@SCM_LIB.SCM(SCH_1):PAGE50',
 PHYS_PAGE='50',
 XY='(625,1625)',
 ROT='0',
 VER='1',
 PACK_TYPE='0402LF',
 CDS_LIB='pure_quanta',
 CDS_PART_NAME='Q_RES_0402LF-316,1%,1/16W,CHIPA',
 WATTAGE='1/16W',
 TOLERANCE='1%',
 MATERIAL='CHIP',
 VALUE='316',
 PRIM_FILE='W:/<user>/logical/q_res/chips/chips.prt';

PART_NAME
 R390 'Q_RES_0402LF-33.2,1%,1/16W,CHIA':;

SECTION_NUMBER 1
 '@SCM_LIB.SCM(SCH_1):PAGE49_I92@PURE_QUANTA.Q_RES(CHIPS)':
 C_PATH='@scm_lib.scm(sch_1):page49_i92@pure_quanta.q_res(chips)',
 P_PATH='@scm_lib.scm(sch_1):page49_i92@pure_quanta.q_res(chips)',
 PATH='I92',
 DRAWING='@SCM_LIB.SCM(SCH_1):PAGE49',
 PHYS_PAGE='49',
 XY='(-7775,4575)',
 ROT='0',
 VER='1',
 PACK_TYPE='0402LF',
 CDS_LIB='pure_quanta',
 CDS_PART_NAME='Q_RES_0402LF-33.2,1%,1/16W,CHIA',
 WATTAGE='1/16W',
 TOLERANCE='1%',
 MATERIAL='CHIP',
 VALUE='33.2',
 PRIM_FILE='W:/<user>/logical/q_res/chips/chips.prt';

PART_NAME
 R391 'Q_RES_0402LF-8.2K,5%,1/16W,EMPA':;

SECTION_NUMBER 1
 '@SCM_LIB.SCM(SCH_1):PAGE50_I235@PURE_QUANTA.Q_RES(CHIPS)':
 C_PATH='@scm_lib.scm(sch_1):page50_i235@pure_quanta.q_res(chips)',
 P_PATH='@scm_lib.scm(sch_1):page50_i235@pure_quanta.q_res(chips)',
 PATH='I235',
 DRAWING='@SCM_LIB.SCM(SCH_1):PAGE50',
 PHYS_PAGE='50',
 XY='(3000,3675)',
 ROT='0',
 VER='2',
 PACK_TYPE='0402LF',
 CDS_LIB='pure_quanta',
 CDS_PART_NAME='Q_RES_0402LF-8.2K,5%,1/16W,EMPA',
 WATTAGE='1/16W',
 TOLERANCE='5%',
 MATERIAL='EMPTY',
 VALUE='8.2K',
 PRIM_FILE='W:/<user>/logical/q_res/chips/chips.prt';

PART_NAME
 R392 'Q_RES_0402LF-0,5%,1/16W,CHIP,CA':;

SECTION_NUMBER 1
 '@SCM_LIB.SCM(SCH_1):PAGE13_I447@PURE_QUANTA.Q_RES(CHIPS)':
 C_PATH='@scm_lib.scm(sch_1):page13_i447@pure_quanta.q_res(chips)',
 P_PATH='@scm_lib.scm(sch_1):page13_i447@pure_quanta.q_res(chips)',
 PATH='I447',
 DRAWING='@SCM_LIB.SCM(SCH_1):PAGE13',
 PHYS_PAGE='13',
 XY='(-3350,4625)',
 ROT='0',
 VER='2',
 PACK_TYPE='0402LF',
 LOCATION='R392',
 CDS_LIB='pure_quanta',
 CDS_PART_NAME='Q_RES_0402LF-0,5%,1/16W,CHIP,CA',
 WATTAGE='1/16W',
 TOLERANCE='5%',
 MATERIAL='CHIP',
 VALUE='0',
 PRIM_FILE='W:/<user>/logical/q_res/chips/chips.prt';

PART_NAME
 R393 'Q_RES_0402LF-0,5%,1/16W,CHIP,CA':;

SECTION_NUMBER 1
 '@SCM_LIB.SCM(SCH_1):PAGE54_I102@PURE_QUANTA.Q_RES(CHIPS)':
 C_PATH='@scm_lib.scm(sch_1):page54_i102@pure_quanta.q_res(chips)',
 P_PATH='@scm_lib.scm(sch_1):page54_i102@pure_quanta.q_res(chips)',
 PATH='I102',
 DRAWING='@SCM_LIB.SCM(SCH_1):PAGE54',
 PHYS_PAGE='54',
 XY='(-1625,2175)',
 ROT='0',
 VER='1',
 PACK_TYPE='0402LF',
 LOCATION='R393',
 CDS_LIB='pure_quanta',
 CDS_PART_NAME='Q_RES_0402LF-0,5%,1/16W,CHIP,CA',
 WATTAGE='1/16W',
 TOLERANCE='5%',
 MATERIAL='CHIP',
 VALUE='0',
 PRIM_FILE='W:/<user>/logical/q_res/chips/chips.prt';

PART_NAME
 R394 'Q_RES_0402LF-33.2,1%,1/16W,CHIA':;

SECTION_NUMBER 1
 '@SCM_LIB.SCM(SCH_1):PAGE12_I314@PURE_QUANTA.Q_RES(CHIPS)':
 C_PATH='@scm_lib.scm(sch_1):page12_i314@pure_quanta.q_res(chips)',
 P_PATH='@scm_lib.scm(sch_1):page12_i314@pure_quanta.q_res(chips)',
 PATH='I314',
 DRAWING='@SCM_LIB.SCM(SCH_1):PAGE12',
 PHYS_PAGE='12',
 XY='(4125,1700)',
 ROT='0',
 VER='1',
 PACK_TYPE='0402LF',
 LOCATION='R394',
 CDS_LIB='pure_quanta',
 CDS_PART_NAME='Q_RES_0402LF-33.2,1%,1/16W,CHIA',
 WATTAGE='1/16W',
 TOLERANCE='1%',
 MATERIAL='CHIP',
 VALUE='33.2',
 PRIM_FILE='W:/<user>/logical/q_res/chips/chips.prt';

PART_NAME
 R395 'Q_RES_0402LF-0,5%,1/16W,CHIP,CA':;

SECTION_NUMBER 1
 '@SCM_LIB.SCM(SCH_1):PAGE13_I448@PURE_QUANTA.Q_RES(CHIPS)':
 C_PATH='@scm_lib.scm(sch_1):page13_i448@pure_quanta.q_res(chips)',
 P_PATH='@scm_lib.scm(sch_1):page13_i448@pure_quanta.q_res(chips)',
 PATH='I448',
 DRAWING='@SCM_LIB.SCM(SCH_1):PAGE13',
 PHYS_PAGE='13',
 XY='(-775,4625)',
 ROT='0',
 VER='2',
 PACK_TYPE='0402LF',
 CDS_LIB='pure_quanta',
 CDS_PART_NAME='Q_RES_0402LF-0,5%,1/16W,CHIP,CA',
 WATTAGE='1/16W',
 TOLERANCE='5%',
 MATERIAL='CHIP',
 VALUE='0',
 PRIM_FILE='W:/<user>/logical/q_res/chips/chips.prt';

PART_NAME
 R396 'Q_RES_0402LF-100K,1%,1/16W,CHIA':;

SECTION_NUMBER 1
 '@SCM_LIB.SCM(SCH_1):PAGE31_I80@PURE_QUANTA.Q_RES(CHIPS)':
 C_PATH='@scm_lib.scm(sch_1):page31_i80@pure_quanta.q_res(chips)',
 P_PATH='@scm_lib.scm(sch_1):page31_i80@pure_quanta.q_res(chips)',
 PATH='I80',
 DRAWING='@SCM_LIB.SCM(SCH_1):PAGE31',
 PHYS_PAGE='31',
 XY='(-2000,5825)',
 ROT='0',
 VER='2',
 PACK_TYPE='0402LF',
 CDS_LIB='pure_quanta',
 CDS_PART_NAME='Q_RES_0402LF-100K,1%,1/16W,CHIA',
 WATTAGE='1/16W',
 TOLERANCE='1%',
 MATERIAL='CHIP',
 VALUE='100K',
 PRIM_FILE='W:/<user>/logical/q_res/chips/chips.prt';

PART_NAME
 R397 'Q_RES_0402LF-0,5%,1/16W,CHIP,CA':;

SECTION_NUMBER 1
 '@SCM_LIB.SCM(SCH_1):PAGE34_I167@PURE_QUANTA.Q_RES(CHIPS)':
 C_PATH='@scm_lib.scm(sch_1):page34_i167@pure_quanta.q_res(chips)',
 P_PATH='@scm_lib.scm(sch_1):page34_i167@pure_quanta.q_res(chips)',
 PATH='I167',
 DRAWING='@SCM_LIB.SCM(SCH_1):PAGE34',
 PHYS_PAGE='34',
 XY='(-2550,4500)',
 ROT='0',
 VER='1',
 PACK_TYPE='0402LF',
 LOCATION='R397',
 CDS_LIB='pure_quanta',
 CDS_PART_NAME='Q_RES_0402LF-0,5%,1/16W,CHIP,CA',
 WATTAGE='1/16W',
 TOLERANCE='5%',
 MATERIAL='CHIP',
 VALUE='0',
 PRIM_FILE='W:/<user>/logical/q_res/chips/chips.prt';

PART_NAME
 R398 'Q_RES_0402LF-0,5%,1/16W,CHIP,CA':;

SECTION_NUMBER 1
 '@SCM_LIB.SCM(SCH_1):PAGE15_I351@PURE_QUANTA.Q_RES(CHIPS)':
 C_PATH='@scm_lib.scm(sch_1):page15_i351@pure_quanta.q_res(chips)',
 P_PATH='@scm_lib.scm(sch_1):page15_i351@pure_quanta.q_res(chips)',
 PATH='I351',
 DRAWING='@SCM_LIB.SCM(SCH_1):PAGE15',
 PHYS_PAGE='15',
 XY='(-300,1975)',
 ROT='2',
 VER='1',
 PACK_TYPE='0402LF',
 CDS_LIB='pure_quanta',
 CDS_PART_NAME='Q_RES_0402LF-0,5%,1/16W,CHIP,CA',
 WATTAGE='1/16W',
 TOLERANCE='5%',
 MATERIAL='CHIP',
 VALUE='0',
 PRIM_FILE='W:/<user>/logical/q_res/chips/chips.prt';

PART_NAME
 R399 'Q_RES_0402LF-0,5%,1/16W,CHIP,CA':;

SECTION_NUMBER 1
 '@SCM_LIB.SCM(SCH_1):PAGE56_I55@PURE_QUANTA.Q_RES(CHIPS)':
 C_PATH='@scm_lib.scm(sch_1):page56_i55@pure_quanta.q_res(chips)',
 P_PATH='@scm_lib.scm(sch_1):page56_i55@pure_quanta.q_res(chips)',
 PATH='I55',
 DRAWING='@SCM_LIB.SCM(SCH_1):PAGE56',
 PHYS_PAGE='56',
 XY='(-3650,325)',
 ROT='0',
 VER='1',
 PACK_TYPE='0402LF',
 LOCATION='R399',
 CDS_LIB='pure_quanta',
 CDS_PART_NAME='Q_RES_0402LF-0,5%,1/16W,CHIP,CA',
 WATTAGE='1/16W',
 TOLERANCE='5%',
 MATERIAL='CHIP',
 VALUE='0',
 PRIM_FILE='W:/<user>/logical/q_res/chips/chips.prt';

PART_NAME
 R400 'Q_RES_0402LF-4.7K,1%,1/16W,EMPA':;

SECTION_NUMBER 1
 '@SCM_LIB.SCM(SCH_1):PAGE12_I454@PURE_QUANTA.Q_RES(CHIPS)':
 C_PATH='@scm_lib.scm(sch_1):page12_i454@pure_quanta.q_res(chips)',
 P_PATH='@scm_lib.scm(sch_1):page12_i454@pure_quanta.q_res(chips)',
 PATH='I454',
 DRAWING='@SCM_LIB.SCM(SCH_1):PAGE12',
 PHYS_PAGE='12',
 XY='(4600,-950)',
 ROT='0',
 VER='1',
 PACK_TYPE='0402LF',
 CDS_LIB='pure_quanta',
 CDS_PART_NAME='Q_RES_0402LF-4.7K,1%,1/16W,EMPA',
 WATTAGE='1/16W',
 TOLERANCE='1%',
 MATERIAL='EMPTY',
 VALUE='4.7K',
 PRIM_FILE='W:/<user>/logical/q_res/chips/chips.prt';

PART_NAME
 R401 'Q_RES_0402LF-33.2,1%,1/16W,CHIA':;

SECTION_NUMBER 1
 '@SCM_LIB.SCM(SCH_1):PAGE13_I374@PURE_QUANTA.Q_RES(CHIPS)':
 C_PATH='@scm_lib.scm(sch_1):page13_i374@pure_quanta.q_res(chips)',
 P_PATH='@scm_lib.scm(sch_1):page13_i374@pure_quanta.q_res(chips)',
 PATH='I374',
 DRAWING='@SCM_LIB.SCM(SCH_1):PAGE13',
 PHYS_PAGE='13',
 XY='(-1775,4175)',
 ROT='0',
 VER='1',
 PACK_TYPE='0402LF',
 CDS_LIB='pure_quanta',
 CDS_PART_NAME='Q_RES_0402LF-33.2,1%,1/16W,CHIA',
 WATTAGE='1/16W',
 TOLERANCE='1%',
 MATERIAL='CHIP',
 VALUE='33.2',
 PRIM_FILE='W:/<user>/logical/q_res/chips/chips.prt';

PART_NAME
 R402 'Q_RES_0402LF-33.2,1%,1/16W,CHIA':;

SECTION_NUMBER 1
 '@SCM_LIB.SCM(SCH_1):PAGE13_I373@PURE_QUANTA.Q_RES(CHIPS)':
 C_PATH='@scm_lib.scm(sch_1):page13_i373@pure_quanta.q_res(chips)',
 P_PATH='@scm_lib.scm(sch_1):page13_i373@pure_quanta.q_res(chips)',
 PATH='I373',
 DRAWING='@SCM_LIB.SCM(SCH_1):PAGE13',
 PHYS_PAGE='13',
 XY='(-1775,4125)',
 ROT='0',
 VER='1',
 PACK_TYPE='0402LF',
 CDS_LIB='pure_quanta',
 CDS_PART_NAME='Q_RES_0402LF-33.2,1%,1/16W,CHIA',
 WATTAGE='1/16W',
 TOLERANCE='1%',
 MATERIAL='CHIP',
 VALUE='33.2',
 PRIM_FILE='W:/<user>/logical/q_res/chips/chips.prt';

PART_NAME
 R403 'Q_RES_0402LF-10K,1%,1/16W,CHIPA':;

SECTION_NUMBER 1
 '@SCM_LIB.SCM(SCH_1):PAGE53_I68@PURE_QUANTA.Q_RES(CHIPS)':
 C_PATH='@scm_lib.scm(sch_1):page53_i68@pure_quanta.q_res(chips)',
 P_PATH='@scm_lib.scm(sch_1):page53_i68@pure_quanta.q_res(chips)',
 PATH='I68',
 DRAWING='@SCM_LIB.SCM(SCH_1):PAGE53',
 PHYS_PAGE='53',
 XY='(-1375,100)',
 ROT='0',
 VER='2',
 PACK_TYPE='0402LF',
 CDS_LIB='pure_quanta',
 CDS_PART_NAME='Q_RES_0402LF-10K,1%,1/16W,CHIPA',
 WATTAGE='1/16W',
 TOLERANCE='1%',
 MATERIAL='CHIP',
 VALUE='10K',
 PRIM_FILE='W:/<user>/logical/q_res/chips/chips.prt';

PART_NAME
 R404 'Q_RES_0402LF-10K,1%,1/16W,CHIPA':;

SECTION_NUMBER 1
 '@SCM_LIB.SCM(SCH_1):PAGE21_I166@PURE_QUANTA.Q_RES(CHIPS)':
 C_PATH='@scm_lib.scm(sch_1):page21_i166@pure_quanta.q_res(chips)',
 P_PATH='@scm_lib.scm(sch_1):page21_i166@pure_quanta.q_res(chips)',
 PATH='I166',
 DRAWING='@SCM_LIB.SCM(SCH_1):PAGE21',
 PHYS_PAGE='21',
 XY='(500,3725)',
 ROT='0',
 VER='2',
 PACK_TYPE='0402LF',
 CDS_LIB='pure_quanta',
 CDS_PART_NAME='Q_RES_0402LF-10K,1%,1/16W,CHIPA',
 WATTAGE='1/16W',
 TOLERANCE='1%',
 MATERIAL='CHIP',
 VALUE='10K',
 PRIM_FILE='W:/<user>/logical/q_res/chips/chips.prt';

PART_NAME
 R405 'Q_RES_0402LF-33.2,1%,1/16W,CHIA':;

SECTION_NUMBER 1
 '@SCM_LIB.SCM(SCH_1):PAGE13_I430@PURE_QUANTA.Q_RES(CHIPS)':
 C_PATH='@scm_lib.scm(sch_1):page13_i430@pure_quanta.q_res(chips)',
 P_PATH='@scm_lib.scm(sch_1):page13_i430@pure_quanta.q_res(chips)',
 PATH='I430',
 DRAWING='@SCM_LIB.SCM(SCH_1):PAGE13',
 PHYS_PAGE='13',
 XY='(3150,1625)',
 ROT='0',
 VER='1',
 PACK_TYPE='0402LF',
 LOCATION='R405',
 CDS_LIB='pure_quanta',
 CDS_PART_NAME='Q_RES_0402LF-33.2,1%,1/16W,CHIA',
 WATTAGE='1/16W',
 TOLERANCE='1%',
 MATERIAL='CHIP',
 VALUE='33.2',
 PRIM_FILE='W:/<user>/logical/q_res/chips/chips.prt';

PART_NAME
 R406 'Q_RES_0402LF-10K,1%,1/16W,CHIPA':;

SECTION_NUMBER 1
 '@SCM_LIB.SCM(SCH_1):PAGE54_I108@PURE_QUANTA.Q_RES(CHIPS)':
 C_PATH='@scm_lib.scm(sch_1):page54_i108@pure_quanta.q_res(chips)',
 P_PATH='@scm_lib.scm(sch_1):page54_i108@pure_quanta.q_res(chips)',
 PATH='I108',
 DRAWING='@SCM_LIB.SCM(SCH_1):PAGE54',
 PHYS_PAGE='54',
 XY='(-725,1850)',
 ROT='0',
 VER='2',
 PACK_TYPE='0402LF',
 CDS_LIB='pure_quanta',
 CDS_PART_NAME='Q_RES_0402LF-10K,1%,1/16W,CHIPA',
 WATTAGE='1/16W',
 TOLERANCE='1%',
 MATERIAL='CHIP',
 VALUE='10K',
 PRIM_FILE='W:/<user>/logical/q_res/chips/chips.prt';

PART_NAME
 R407 'Q_RES_0402LF-33.2,1%,1/16W,CHIA':;

SECTION_NUMBER 1
 '@SCM_LIB.SCM(SCH_1):PAGE13_I349@PURE_QUANTA.Q_RES(CHIPS)':
 C_PATH='@scm_lib.scm(sch_1):page13_i349@pure_quanta.q_res(chips)',
 P_PATH='@scm_lib.scm(sch_1):page13_i349@pure_quanta.q_res(chips)',
 PATH='I349',
 DRAWING='@SCM_LIB.SCM(SCH_1):PAGE13',
 SEC_TYPE='0402LF',
 PHYS_PAGE='13',
 XY='(3800,2775)',
 ROT='0',
 VER='1',
 PACK_TYPE='0402LF',
 LOCATION='R407',
 SEC='1',
 CDS_LIB='pure_quanta',
 CDS_PART_NAME='Q_RES_0402LF-33.2,1%,1/16W,CHIA',
 WATTAGE='1/16W',
 TOLERANCE='1%',
 MATERIAL='CHIP',
 VALUE='33.2',
 PRIM_FILE='W:/<user>/logical/q_res/chips/chips.prt';

PART_NAME
 R408 'Q_RES_0402LF-4.7K,1%,1/16W,EMPB':;

SECTION_NUMBER 1
 '@SCM_LIB.SCM(SCH_1):PAGE46_I139@PURE_QUANTA.Q_RES(CHIPS)':
 C_PATH='@scm_lib.scm(sch_1):page46_i139@pure_quanta.q_res(chips)',
 P_PATH='@scm_lib.scm(sch_1):page46_i139@pure_quanta.q_res(chips)',
 PATH='I139',
 DRAWING='@SCM_LIB.SCM(SCH_1):PAGE46',
 PHYS_PAGE='46',
 XY='(-10225,-5100)',
 ROT='0',
 VER='2',
 PACK_TYPE='0402LF',
 CDS_LIB='pure_quanta',
 CDS_PART_NAME='Q_RES_0402LF-4.7K,1%,1/16W,EMPB',
 WATTAGE='1/16W',
 TOLERANCE='1%',
 MATERIAL='EMPTY',
 VALUE='4.7K',
 PRIM_FILE='W:/<user>/logical/q_res/chips/chips.prt';

PART_NAME
 R409 'Q_RES_0402LF-49.9,1%,1/16W,CHIA':;

SECTION_NUMBER 1
 '@SCM_LIB.SCM(SCH_1):PAGE26_I57@PURE_QUANTA.Q_RES(CHIPS)':
 C_PATH='@scm_lib.scm(sch_1):page26_i57@pure_quanta.q_res(chips)',
 P_PATH='@scm_lib.scm(sch_1):page26_i57@pure_quanta.q_res(chips)',
 PATH='I57',
 DRAWING='@SCM_LIB.SCM(SCH_1):PAGE26',
 PHYS_PAGE='26',
 XY='(1625,3125)',
 ROT='0',
 VER='1',
 PACK_TYPE='0402LF',
 LOCATION='R409',
 CDS_LIB='pure_quanta',
 CDS_PART_NAME='Q_RES_0402LF-49.9,1%,1/16W,CHIA',
 WATTAGE='1/16W',
 TOLERANCE='1%',
 MATERIAL='CHIP',
 VALUE='49.9',
 PRIM_FILE='W:/<user>/logical/q_res/chips/chips.prt';

PART_NAME
 R410 'Q_RES_0402LF-49.9,1%,1/16W,CHIA':;

SECTION_NUMBER 1
 '@SCM_LIB.SCM(SCH_1):PAGE26_I56@PURE_QUANTA.Q_RES(CHIPS)':
 C_PATH='@scm_lib.scm(sch_1):page26_i56@pure_quanta.q_res(chips)',
 P_PATH='@scm_lib.scm(sch_1):page26_i56@pure_quanta.q_res(chips)',
 PATH='I56',
 DRAWING='@SCM_LIB.SCM(SCH_1):PAGE26',
 PHYS_PAGE='26',
 XY='(1625,3025)',
 ROT='0',
 VER='1',
 PACK_TYPE='0402LF',
 LOCATION='R410',
 CDS_LIB='pure_quanta',
 CDS_PART_NAME='Q_RES_0402LF-49.9,1%,1/16W,CHIA',
 WATTAGE='1/16W',
 TOLERANCE='1%',
 MATERIAL='CHIP',
 VALUE='49.9',
 PRIM_FILE='W:/<user>/logical/q_res/chips/chips.prt';

PART_NAME
 R411 'Q_RES_0402LF-100,1%,1/16W,CHIPA':;

SECTION_NUMBER 1
 '@SCM_LIB.SCM(SCH_1):PAGE26_I6@PURE_QUANTA.Q_RES(CHIPS)':
 C_PATH='@scm_lib.scm(sch_1):page26_i6@pure_quanta.q_res(chips)',
 P_PATH='@scm_lib.scm(sch_1):page26_i6@pure_quanta.q_res(chips)',
 PATH='I6',
 DRAWING='@SCM_LIB.SCM(SCH_1):PAGE26',
 PHYS_PAGE='26',
 XY='(-1800,500)',
 ROT='0',
 VER='2',
 PACK_TYPE='0402LF',
 LOCATION='R411',
 CDS_LIB='pure_quanta',
 CDS_PART_NAME='Q_RES_0402LF-100,1%,1/16W,CHIPA',
 WATTAGE='1/16W',
 TOLERANCE='1%',
 MATERIAL='CHIP',
 VALUE='100',
 PRIM_FILE='W:/<user>/logical/q_res/chips/chips.prt';

PART_NAME
 R412 'Q_RES_0402LF-100,1%,1/16W,CHIPA':;

SECTION_NUMBER 1
 '@SCM_LIB.SCM(SCH_1):PAGE26_I8@PURE_QUANTA.Q_RES(CHIPS)':
 C_PATH='@scm_lib.scm(sch_1):page26_i8@pure_quanta.q_res(chips)',
 P_PATH='@scm_lib.scm(sch_1):page26_i8@pure_quanta.q_res(chips)',
 PATH='I8',
 DRAWING='@SCM_LIB.SCM(SCH_1):PAGE26',
 PHYS_PAGE='26',
 XY='(-1450,500)',
 ROT='0',
 VER='2',
 PACK_TYPE='0402LF',
 LOCATION='R412',
 CDS_LIB='pure_quanta',
 CDS_PART_NAME='Q_RES_0402LF-100,1%,1/16W,CHIPA',
 WATTAGE='1/16W',
 TOLERANCE='1%',
 MATERIAL='CHIP',
 VALUE='100',
 PRIM_FILE='W:/<user>/logical/q_res/chips/chips.prt';

PART_NAME
 R413 'Q_RES_0402LF-100,1%,1/16W,CHIPA':;

SECTION_NUMBER 1
 '@SCM_LIB.SCM(SCH_1):PAGE26_I12@PURE_QUANTA.Q_RES(CHIPS)':
 C_PATH='@scm_lib.scm(sch_1):page26_i12@pure_quanta.q_res(chips)',
 P_PATH='@scm_lib.scm(sch_1):page26_i12@pure_quanta.q_res(chips)',
 PATH='I12',
 DRAWING='@SCM_LIB.SCM(SCH_1):PAGE26',
 PHYS_PAGE='26',
 XY='(-1100,500)',
 ROT='0',
 VER='2',
 PACK_TYPE='0402LF',
 LOCATION='R413',
 CDS_LIB='pure_quanta',
 CDS_PART_NAME='Q_RES_0402LF-100,1%,1/16W,CHIPA',
 WATTAGE='1/16W',
 TOLERANCE='1%',
 MATERIAL='CHIP',
 VALUE='100',
 PRIM_FILE='W:/<user>/logical/q_res/chips/chips.prt';

PART_NAME
 R414 'Q_RES_0402LF-4.7K,1%,1/16W,EMPB':;

SECTION_NUMBER 1
 '@SCM_LIB.SCM(SCH_1):PAGE46_I140@PURE_QUANTA.Q_RES(CHIPS)':
 C_PATH='@scm_lib.scm(sch_1):page46_i140@pure_quanta.q_res(chips)',
 P_PATH='@scm_lib.scm(sch_1):page46_i140@pure_quanta.q_res(chips)',
 PATH='I140',
 DRAWING='@SCM_LIB.SCM(SCH_1):PAGE46',
 PHYS_PAGE='46',
 XY='(-10125,-5100)',
 ROT='0',
 VER='2',
 PACK_TYPE='0402LF',
 CDS_LIB='pure_quanta',
 CDS_PART_NAME='Q_RES_0402LF-4.7K,1%,1/16W,EMPB',
 WATTAGE='1/16W',
 TOLERANCE='1%',
 MATERIAL='EMPTY',
 VALUE='4.7K',
 PRIM_FILE='W:/<user>/logical/q_res/chips/chips.prt';

PART_NAME
 R415 'Q_RES_0402LF-2.2,1%,1/16W,CHIPA':;

SECTION_NUMBER 1
 '@SCM_LIB.SCM(SCH_1):PAGE52_I146@PURE_QUANTA.Q_RES(CHIPS)':
 C_PATH='@scm_lib.scm(sch_1):page52_i146@pure_quanta.q_res(chips)',
 P_PATH='@scm_lib.scm(sch_1):page52_i146@pure_quanta.q_res(chips)',
 PATH='I146',
 DRAWING='@SCM_LIB.SCM(SCH_1):PAGE52',
 PHYS_PAGE='52',
 XY='(850,1625)',
 ROT='0',
 VER='1',
 PACK_TYPE='0402LF',
 LOCATION='R415',
 CDS_LIB='pure_quanta',
 CDS_PART_NAME='Q_RES_0402LF-2.2,1%,1/16W,CHIPA',
 WATTAGE='1/16W',
 TOLERANCE='1%',
 MATERIAL='CHIP',
 VALUE='2.2',
 PRIM_FILE='W:/<user>/logical/q_res/chips/chips.prt';

PART_NAME
 R416 'Q_RES_0402LF-4.7K,1%,1/16W,CHIA':;

SECTION_NUMBER 1
 '@SCM_LIB.SCM(SCH_1):PAGE26_I41@PURE_QUANTA.Q_RES(CHIPS)':
 C_PATH='@scm_lib.scm(sch_1):page26_i41@pure_quanta.q_res(chips)',
 P_PATH='@scm_lib.scm(sch_1):page26_i41@pure_quanta.q_res(chips)',
 PATH='I41',
 DRAWING='@SCM_LIB.SCM(SCH_1):PAGE26',
 PHYS_PAGE='26',
 XY='(-1175,3350)',
 ROT='0',
 VER='2',
 PACK_TYPE='0402LF',
 LOCATION='R416',
 CDS_LIB='pure_quanta',
 CDS_PART_NAME='Q_RES_0402LF-4.7K,1%,1/16W,CHIA',
 WATTAGE='1/16W',
 TOLERANCE='1%',
 MATERIAL='CHIP',
 VALUE='4.7K',
 PRIM_FILE='W:/<user>/logical/q_res/chips/chips.prt';

PART_NAME
 R417 'Q_RES_0402LF-1K,1%,1/16W,EMPTYA':;

SECTION_NUMBER 1
 '@SCM_LIB.SCM(SCH_1):PAGE26_I39@PURE_QUANTA.Q_RES(CHIPS)':
 C_PATH='@scm_lib.scm(sch_1):page26_i39@pure_quanta.q_res(chips)',
 P_PATH='@scm_lib.scm(sch_1):page26_i39@pure_quanta.q_res(chips)',
 PATH='I39',
 DRAWING='@SCM_LIB.SCM(SCH_1):PAGE26',
 SEC_TYPE='0402LF',
 PHYS_PAGE='26',
 XY='(-1175,2650)',
 ROT='0',
 VER='2',
 PACK_TYPE='0402LF',
 LOCATION='R417',
 SEC='1',
 CDS_LIB='pure_quanta',
 CDS_PART_NAME='Q_RES_0402LF-1K,1%,1/16W,EMPTYA',
 WATTAGE='1/16W',
 TOLERANCE='1%',
 MATERIAL='EMPTY',
 VALUE='1K',
 PRIM_FILE='W:/<user>/logical/q_res/chips/chips.prt';

PART_NAME
 R418 'Q_RES_0402LF-4.7K,1%,1/16W,EMPA':;

SECTION_NUMBER 1
 '@SCM_LIB.SCM(SCH_1):PAGE26_I40@PURE_QUANTA.Q_RES(CHIPS)':
 C_PATH='@scm_lib.scm(sch_1):page26_i40@pure_quanta.q_res(chips)',
 P_PATH='@scm_lib.scm(sch_1):page26_i40@pure_quanta.q_res(chips)',
 PATH='I40',
 DRAWING='@SCM_LIB.SCM(SCH_1):PAGE26',
 PHYS_PAGE='26',
 XY='(-1725,3350)',
 ROT='0',
 VER='2',
 PACK_TYPE='0402LF',
 LOCATION='R418',
 CDS_LIB='pure_quanta',
 CDS_PART_NAME='Q_RES_0402LF-4.7K,1%,1/16W,EMPA',
 WATTAGE='1/16W',
 TOLERANCE='1%',
 MATERIAL='EMPTY',
 VALUE='4.7K',
 PRIM_FILE='W:/<user>/logical/q_res/chips/chips.prt';

PART_NAME
 R419 'Q_RES_0402LF-1K,1%,1/16W,CHIP,A':;

SECTION_NUMBER 1
 '@SCM_LIB.SCM(SCH_1):PAGE26_I37@PURE_QUANTA.Q_RES(CHIPS)':
 C_PATH='@scm_lib.scm(sch_1):page26_i37@pure_quanta.q_res(chips)',
 P_PATH='@scm_lib.scm(sch_1):page26_i37@pure_quanta.q_res(chips)',
 PATH='I37',
 DRAWING='@SCM_LIB.SCM(SCH_1):PAGE26',
 SEC_TYPE='0402LF',
 PHYS_PAGE='26',
 XY='(-1725,2650)',
 ROT='0',
 VER='2',
 PACK_TYPE='0402LF',
 LOCATION='R419',
 SEC='1',
 CDS_LIB='pure_quanta',
 CDS_PART_NAME='Q_RES_0402LF-1K,1%,1/16W,CHIP,A',
 WATTAGE='1/16W',
 TOLERANCE='1%',
 MATERIAL='CHIP',
 VALUE='1K',
 PRIM_FILE='W:/<user>/logical/q_res/chips/chips.prt';

PART_NAME
 R420 'Q_RES_0402LF-150,1%,1/16W,CHIPA':;

SECTION_NUMBER 1
 '@SCM_LIB.SCM(SCH_1):PAGE26_I69@PURE_QUANTA.Q_RES(CHIPS)':
 C_PATH='@scm_lib.scm(sch_1):page26_i69@pure_quanta.q_res(chips)',
 P_PATH='@scm_lib.scm(sch_1):page26_i69@pure_quanta.q_res(chips)',
 PATH='I69',
 DRAWING='@SCM_LIB.SCM(SCH_1):PAGE26',
 PHYS_PAGE='26',
 XY='(2275,750)',
 ROT='0',
 VER='1',
 PACK_TYPE='0402LF',
 LOCATION='R420',
 CDS_LIB='pure_quanta',
 CDS_PART_NAME='Q_RES_0402LF-150,1%,1/16W,CHIPA',
 WATTAGE='1/16W',
 TOLERANCE='1%',
 MATERIAL='CHIP',
 VALUE='150',
 PRIM_FILE='W:/<user>/logical/q_res/chips/chips.prt';

PART_NAME
 R421 'Q_RES_0402LF-33.2,1%,1/16W,CHIA':;

SECTION_NUMBER 1
 '@SCM_LIB.SCM(SCH_1):PAGE26_I33@PURE_QUANTA.Q_RES(CHIPS)':
 C_PATH='@scm_lib.scm(sch_1):page26_i33@pure_quanta.q_res(chips)',
 P_PATH='@scm_lib.scm(sch_1):page26_i33@pure_quanta.q_res(chips)',
 PATH='I33',
 DRAWING='@SCM_LIB.SCM(SCH_1):PAGE26',
 PHYS_PAGE='26',
 XY='(2275,700)',
 ROT='0',
 VER='1',
 PACK_TYPE='0402LF',
 LOCATION='R421',
 CDS_LIB='pure_quanta',
 CDS_PART_NAME='Q_RES_0402LF-33.2,1%,1/16W,CHIA',
 WATTAGE='1/16W',
 TOLERANCE='1%',
 MATERIAL='CHIP',
 VALUE='33.2',
 PRIM_FILE='W:/<user>/logical/q_res/chips/chips.prt';

PART_NAME
 R422 'Q_RES_0402LF-2.2K,5%,1/16W,CHIA':;

SECTION_NUMBER 1
 '@SCM_LIB.SCM(SCH_1):PAGE27_I239@PURE_QUANTA.Q_RES(CHIPS)':
 C_PATH='@scm_lib.scm(sch_1):page27_i239@pure_quanta.q_res(chips)',
 P_PATH='@scm_lib.scm(sch_1):page27_i239@pure_quanta.q_res(chips)',
 PATH='I239',
 DRAWING='@SCM_LIB.SCM(SCH_1):PAGE27',
 PHYS_PAGE='27',
 XY='(-625,4200)',
 ROT='0',
 VER='1',
 PACK_TYPE='0402LF',
 LOCATION='R422',
 CDS_LIB='pure_quanta',
 CDS_PART_NAME='Q_RES_0402LF-2.2K,5%,1/16W,CHIA',
 WATTAGE='1/16W',
 TOLERANCE='5%',
 MATERIAL='CHIP',
 VALUE='2.2K',
 PRIM_FILE='W:/<user>/logical/q_res/chips/chips.prt';

PART_NAME
 R423 'Q_RES_0402LF-33.2,1%,1/16W,CHIA':;

SECTION_NUMBER 1
 '@SCM_LIB.SCM(SCH_1):PAGE12_I252@PURE_QUANTA.Q_RES(CHIPS)':
 C_PATH='@scm_lib.scm(sch_1):page12_i252@pure_quanta.q_res(chips)',
 P_PATH='@scm_lib.scm(sch_1):page12_i252@pure_quanta.q_res(chips)',
 PATH='I252',
 DRAWING='@SCM_LIB.SCM(SCH_1):PAGE12',
 PHYS_PAGE='12',
 XY='(4375,250)',
 ROT='0',
 VER='1',
 PACK_TYPE='0402LF',
 LOCATION='R423',
 CDS_LIB='pure_quanta',
 CDS_PART_NAME='Q_RES_0402LF-33.2,1%,1/16W,CHIA',
 WATTAGE='1/16W',
 TOLERANCE='1%',
 MATERIAL='CHIP',
 VALUE='33.2',
 PRIM_FILE='W:/<user>/logical/q_res/chips/chips.prt';

PART_NAME
 R424 'Q_RES_0402LF-33.2,1%,1/16W,CHIA':;

SECTION_NUMBER 1
 '@SCM_LIB.SCM(SCH_1):PAGE12_I253@PURE_QUANTA.Q_RES(CHIPS)':
 C_PATH='@scm_lib.scm(sch_1):page12_i253@pure_quanta.q_res(chips)',
 P_PATH='@scm_lib.scm(sch_1):page12_i253@pure_quanta.q_res(chips)',
 PATH='I253',
 DRAWING='@SCM_LIB.SCM(SCH_1):PAGE12',
 PHYS_PAGE='12',
 XY='(4375,200)',
 ROT='0',
 VER='1',
 PACK_TYPE='0402LF',
 LOCATION='R424',
 CDS_LIB='pure_quanta',
 CDS_PART_NAME='Q_RES_0402LF-33.2,1%,1/16W,CHIA',
 WATTAGE='1/16W',
 TOLERANCE='1%',
 MATERIAL='CHIP',
 VALUE='33.2',
 PRIM_FILE='W:/<user>/logical/q_res/chips/chips.prt';

PART_NAME
 R425 'Q_RES_0402LF-33.2,1%,1/16W,CHIA':;

SECTION_NUMBER 1
 '@SCM_LIB.SCM(SCH_1):PAGE12_I254@PURE_QUANTA.Q_RES(CHIPS)':
 C_PATH='@scm_lib.scm(sch_1):page12_i254@pure_quanta.q_res(chips)',
 P_PATH='@scm_lib.scm(sch_1):page12_i254@pure_quanta.q_res(chips)',
 PATH='I254',
 DRAWING='@SCM_LIB.SCM(SCH_1):PAGE12',
 PHYS_PAGE='12',
 XY='(4375,150)',
 ROT='0',
 VER='1',
 PACK_TYPE='0402LF',
 LOCATION='R425',
 CDS_LIB='pure_quanta',
 CDS_PART_NAME='Q_RES_0402LF-33.2,1%,1/16W,CHIA',
 WATTAGE='1/16W',
 TOLERANCE='1%',
 MATERIAL='CHIP',
 VALUE='33.2',
 PRIM_FILE='W:/<user>/logical/q_res/chips/chips.prt';

PART_NAME
 R426 'Q_RES_0402LF-33.2,1%,1/16W,CHIA':;

SECTION_NUMBER 1
 '@SCM_LIB.SCM(SCH_1):PAGE12_I255@PURE_QUANTA.Q_RES(CHIPS)':
 C_PATH='@scm_lib.scm(sch_1):page12_i255@pure_quanta.q_res(chips)',
 P_PATH='@scm_lib.scm(sch_1):page12_i255@pure_quanta.q_res(chips)',
 PATH='I255',
 DRAWING='@SCM_LIB.SCM(SCH_1):PAGE12',
 PHYS_PAGE='12',
 XY='(4375,100)',
 ROT='0',
 VER='1',
 PACK_TYPE='0402LF',
 LOCATION='R426',
 CDS_LIB='pure_quanta',
 CDS_PART_NAME='Q_RES_0402LF-33.2,1%,1/16W,CHIA',
 WATTAGE='1/16W',
 TOLERANCE='1%',
 MATERIAL='CHIP',
 VALUE='33.2',
 PRIM_FILE='W:/<user>/logical/q_res/chips/chips.prt';

PART_NAME
 R427 'Q_RES_0402LF-33.2,1%,1/16W,CHIA':;

SECTION_NUMBER 1
 '@SCM_LIB.SCM(SCH_1):PAGE13_I198@PURE_QUANTA.Q_RES(CHIPS)':
 C_PATH='@scm_lib.scm(sch_1):page13_i198@pure_quanta.q_res(chips)',
 P_PATH='@scm_lib.scm(sch_1):page13_i198@pure_quanta.q_res(chips)',
 PATH='I198',
 DRAWING='@SCM_LIB.SCM(SCH_1):PAGE13',
 PHYS_PAGE='13',
 XY='(-2125,2125)',
 ROT='0',
 VER='1',
 PACK_TYPE='0402LF',
 LOCATION='R427',
 CDS_LIB='pure_quanta',
 CDS_PART_NAME='Q_RES_0402LF-33.2,1%,1/16W,CHIA',
 WATTAGE='1/16W',
 TOLERANCE='1%',
 MATERIAL='CHIP',
 VALUE='33.2',
 PRIM_FILE='W:/<user>/logical/q_res/chips/chips.prt';

PART_NAME
 R428 'Q_RES_0402LF-2.2K,5%,1/16W,CHIA':;

SECTION_NUMBER 1
 '@SCM_LIB.SCM(SCH_1):PAGE27_I240@PURE_QUANTA.Q_RES(CHIPS)':
 C_PATH='@scm_lib.scm(sch_1):page27_i240@pure_quanta.q_res(chips)',
 P_PATH='@scm_lib.scm(sch_1):page27_i240@pure_quanta.q_res(chips)',
 PATH='I240',
 DRAWING='@SCM_LIB.SCM(SCH_1):PAGE27',
 PHYS_PAGE='27',
 XY='(-625,4100)',
 ROT='0',
 VER='1',
 PACK_TYPE='0402LF',
 LOCATION='R428',
 CDS_LIB='pure_quanta',
 CDS_PART_NAME='Q_RES_0402LF-2.2K,5%,1/16W,CHIA',
 WATTAGE='1/16W',
 TOLERANCE='5%',
 MATERIAL='CHIP',
 VALUE='2.2K',
 PRIM_FILE='W:/<user>/logical/q_res/chips/chips.prt';

PART_NAME
 R429 'Q_RES_0402LF-2.2K,5%,1/16W,CHIA':;

SECTION_NUMBER 1
 '@SCM_LIB.SCM(SCH_1):PAGE27_I241@PURE_QUANTA.Q_RES(CHIPS)':
 C_PATH='@scm_lib.scm(sch_1):page27_i241@pure_quanta.q_res(chips)',
 P_PATH='@scm_lib.scm(sch_1):page27_i241@pure_quanta.q_res(chips)',
 PATH='I241',
 DRAWING='@SCM_LIB.SCM(SCH_1):PAGE27',
 PHYS_PAGE='27',
 XY='(-625,4000)',
 ROT='0',
 VER='1',
 PACK_TYPE='0402LF',
 LOCATION='R429',
 CDS_LIB='pure_quanta',
 CDS_PART_NAME='Q_RES_0402LF-2.2K,5%,1/16W,CHIA',
 WATTAGE='1/16W',
 TOLERANCE='5%',
 MATERIAL='CHIP',
 VALUE='2.2K',
 PRIM_FILE='W:/<user>/logical/q_res/chips/chips.prt';

PART_NAME
 R430 'Q_RES_0402LF-4.7K,1%,1/16W,CHIA':;

SECTION_NUMBER 1
 '@SCM_LIB.SCM(SCH_1):PAGE27_I188@PURE_QUANTA.Q_RES(CHIPS)':
 C_PATH='@scm_lib.scm(sch_1):page27_i188@pure_quanta.q_res(chips)',
 P_PATH='@scm_lib.scm(sch_1):page27_i188@pure_quanta.q_res(chips)',
 PATH='I188',
 DRAWING='@SCM_LIB.SCM(SCH_1):PAGE27',
 PHYS_PAGE='27',
 XY='(2750,2625)',
 ROT='0',
 VER='2',
 PACK_TYPE='0402LF',
 LOCATION='R430',
 CDS_LIB='pure_quanta',
 CDS_PART_NAME='Q_RES_0402LF-4.7K,1%,1/16W,CHIA',
 WATTAGE='1/16W',
 TOLERANCE='1%',
 MATERIAL='CHIP',
 VALUE='4.7K',
 PRIM_FILE='W:/<user>/logical/q_res/chips/chips.prt';

PART_NAME
 R431 'Q_RES_0402LF-100,1%,1/16W,EMPTA':;

SECTION_NUMBER 1
 '@SCM_LIB.SCM(SCH_1):PAGE48_I56@PURE_QUANTA.Q_RES(CHIPS)':
 C_PATH='@scm_lib.scm(sch_1):page48_i56@pure_quanta.q_res(chips)',
 P_PATH='@scm_lib.scm(sch_1):page48_i56@pure_quanta.q_res(chips)',
 PATH='I56',
 DRAWING='@SCM_LIB.SCM(SCH_1):PAGE48',
 PHYS_PAGE='48',
 XY='(-2225,3300)',
 ROT='0',
 VER='2',
 PACK_TYPE='0402LF',
 LOCATION='R431',
 CDS_LIB='pure_quanta',
 CDS_PART_NAME='Q_RES_0402LF-100,1%,1/16W,EMPTA',
 WATTAGE='1/16W',
 TOLERANCE='1%',
 MATERIAL='EMPTY',
 VALUE='100',
 PRIM_FILE='W:/<user>/logical/q_res/chips/chips.prt';

PART_NAME
 R432 'Q_RES_0402LF-0,5%,1/16W,CHIP,CA':;

SECTION_NUMBER 1
 '@SCM_LIB.SCM(SCH_1):PAGE35_I100@PURE_QUANTA.Q_RES(CHIPS)':
 C_PATH='@scm_lib.scm(sch_1):page35_i100@pure_quanta.q_res(chips)',
 P_PATH='@scm_lib.scm(sch_1):page35_i100@pure_quanta.q_res(chips)',
 PATH='I100',
 DRAWING='@SCM_LIB.SCM(SCH_1):PAGE35',
 SEC_TYPE='0402LF',
 PHYS_PAGE='35',
 XY='(-1800,3850)',
 ROT='0',
 VER='1',
 PACK_TYPE='0402LF',
 LOCATION='R432',
 SEC='1',
 CDS_LIB='pure_quanta',
 CDS_PART_NAME='Q_RES_0402LF-0,5%,1/16W,CHIP,CA',
 WATTAGE='1/16W',
 TOLERANCE='5%',
 MATERIAL='CHIP',
 VALUE='0',
 PRIM_FILE='W:/<user>/logical/q_res/chips/chips.prt';

PART_NAME
 R433 'Q_RES_0402LF-33.2,1%,1/16W,CHIA':;

SECTION_NUMBER 1
 '@SCM_LIB.SCM(SCH_1):PAGE12_I382@PURE_QUANTA.Q_RES(CHIPS)':
 C_PATH='@scm_lib.scm(sch_1):page12_i382@pure_quanta.q_res(chips)',
 P_PATH='@scm_lib.scm(sch_1):page12_i382@pure_quanta.q_res(chips)',
 PATH='I382',
 DRAWING='@SCM_LIB.SCM(SCH_1):PAGE12',
 PHYS_PAGE='12',
 XY='(-650,350)',
 ROT='0',
 VER='1',
 PACK_TYPE='0402LF',
 LOCATION='R433',
 CDS_LIB='pure_quanta',
 CDS_PART_NAME='Q_RES_0402LF-33.2,1%,1/16W,CHIA',
 WATTAGE='1/16W',
 TOLERANCE='1%',
 MATERIAL='CHIP',
 VALUE='33.2',
 PRIM_FILE='W:/<user>/logical/q_res/chips/chips.prt';

PART_NAME
 R434 'Q_RES_0402LF-33.2,1%,1/16W,CHIA':;

SECTION_NUMBER 1
 '@SCM_LIB.SCM(SCH_1):PAGE34_I160@PURE_QUANTA.Q_RES(CHIPS)':
 C_PATH='@scm_lib.scm(sch_1):page34_i160@pure_quanta.q_res(chips)',
 P_PATH='@scm_lib.scm(sch_1):page34_i160@pure_quanta.q_res(chips)',
 PATH='I160',
 DRAWING='@SCM_LIB.SCM(SCH_1):PAGE34',
 PHYS_PAGE='34',
 XY='(-2550,3850)',
 ROT='0',
 VER='1',
 PACK_TYPE='0402LF',
 LOCATION='R434',
 CDS_LIB='pure_quanta',
 CDS_PART_NAME='Q_RES_0402LF-33.2,1%,1/16W,CHIA',
 WATTAGE='1/16W',
 TOLERANCE='1%',
 MATERIAL='CHIP',
 VALUE='33.2',
 PRIM_FILE='W:/<user>/logical/q_res/chips/chips.prt';

PART_NAME
 R435 'Q_RES_0402LF-33.2,1%,1/16W,CHIA':;

SECTION_NUMBER 1
 '@SCM_LIB.SCM(SCH_1):PAGE34_I161@PURE_QUANTA.Q_RES(CHIPS)':
 C_PATH='@scm_lib.scm(sch_1):page34_i161@pure_quanta.q_res(chips)',
 P_PATH='@scm_lib.scm(sch_1):page34_i161@pure_quanta.q_res(chips)',
 PATH='I161',
 DRAWING='@SCM_LIB.SCM(SCH_1):PAGE34',
 PHYS_PAGE='34',
 XY='(-2550,3750)',
 ROT='0',
 VER='1',
 PACK_TYPE='0402LF',
 LOCATION='R435',
 CDS_LIB='pure_quanta',
 CDS_PART_NAME='Q_RES_0402LF-33.2,1%,1/16W,CHIA',
 WATTAGE='1/16W',
 TOLERANCE='1%',
 MATERIAL='CHIP',
 VALUE='33.2',
 PRIM_FILE='W:/<user>/logical/q_res/chips/chips.prt';

PART_NAME
 R436 'Q_RES_0402LF-33.2,1%,1/16W,CHIA':;

SECTION_NUMBER 1
 '@SCM_LIB.SCM(SCH_1):PAGE34_I162@PURE_QUANTA.Q_RES(CHIPS)':
 C_PATH='@scm_lib.scm(sch_1):page34_i162@pure_quanta.q_res(chips)',
 P_PATH='@scm_lib.scm(sch_1):page34_i162@pure_quanta.q_res(chips)',
 PATH='I162',
 DRAWING='@SCM_LIB.SCM(SCH_1):PAGE34',
 PHYS_PAGE='34',
 XY='(-2550,3700)',
 ROT='0',
 VER='1',
 PACK_TYPE='0402LF',
 LOCATION='R436',
 CDS_LIB='pure_quanta',
 CDS_PART_NAME='Q_RES_0402LF-33.2,1%,1/16W,CHIA',
 WATTAGE='1/16W',
 TOLERANCE='1%',
 MATERIAL='CHIP',
 VALUE='33.2',
 PRIM_FILE='W:/<user>/logical/q_res/chips/chips.prt';

PART_NAME
 R437 'Q_RES_0402LF-33.2,1%,1/16W,CHIA':;

SECTION_NUMBER 1
 '@SCM_LIB.SCM(SCH_1):PAGE34_I163@PURE_QUANTA.Q_RES(CHIPS)':
 C_PATH='@scm_lib.scm(sch_1):page34_i163@pure_quanta.q_res(chips)',
 P_PATH='@scm_lib.scm(sch_1):page34_i163@pure_quanta.q_res(chips)',
 PATH='I163',
 DRAWING='@SCM_LIB.SCM(SCH_1):PAGE34',
 PHYS_PAGE='34',
 XY='(-2550,3600)',
 ROT='0',
 VER='1',
 PACK_TYPE='0402LF',
 LOCATION='R437',
 CDS_LIB='pure_quanta',
 CDS_PART_NAME='Q_RES_0402LF-33.2,1%,1/16W,CHIA',
 WATTAGE='1/16W',
 TOLERANCE='1%',
 MATERIAL='CHIP',
 VALUE='33.2',
 PRIM_FILE='W:/<user>/logical/q_res/chips/chips.prt';

PART_NAME
 R438 'Q_RES_0402LF-2.2K,5%,1/16W,CHIA':;

SECTION_NUMBER 1
 '@SCM_LIB.SCM(SCH_1):PAGE27_I242@PURE_QUANTA.Q_RES(CHIPS)':
 C_PATH='@scm_lib.scm(sch_1):page27_i242@pure_quanta.q_res(chips)',
 P_PATH='@scm_lib.scm(sch_1):page27_i242@pure_quanta.q_res(chips)',
 PATH='I242',
 DRAWING='@SCM_LIB.SCM(SCH_1):PAGE27',
 PHYS_PAGE='27',
 XY='(-625,3900)',
 ROT='0',
 VER='1',
 PACK_TYPE='0402LF',
 LOCATION='R438',
 CDS_LIB='pure_quanta',
 CDS_PART_NAME='Q_RES_0402LF-2.2K,5%,1/16W,CHIA',
 WATTAGE='1/16W',
 TOLERANCE='5%',
 MATERIAL='CHIP',
 VALUE='2.2K',
 PRIM_FILE='W:/<user>/logical/q_res/chips/chips.prt';

PART_NAME
 R439 'Q_RES_0402LF-33.2,1%,1/16W,CHIA':;

SECTION_NUMBER 1
 '@SCM_LIB.SCM(SCH_1):PAGE13_I227@PURE_QUANTA.Q_RES(CHIPS)':
 C_PATH='@scm_lib.scm(sch_1):page13_i227@pure_quanta.q_res(chips)',
 P_PATH='@scm_lib.scm(sch_1):page13_i227@pure_quanta.q_res(chips)',
 PATH='I227',
 DRAWING='@SCM_LIB.SCM(SCH_1):PAGE13',
 PHYS_PAGE='13',
 XY='(-2300,2325)',
 ROT='0',
 VER='1',
 PACK_TYPE='0402LF',
 LOCATION='R439',
 CDS_LIB='pure_quanta',
 CDS_PART_NAME='Q_RES_0402LF-33.2,1%,1/16W,CHIA',
 WATTAGE='1/16W',
 TOLERANCE='1%',
 MATERIAL='CHIP',
 VALUE='33.2',
 PRIM_FILE='W:/<user>/logical/q_res/chips/chips.prt';

PART_NAME
 R440 'Q_RES_0402LF-49.9,1%,1/16W,EMPA':;

SECTION_NUMBER 1
 '@SCM_LIB.SCM(SCH_1):PAGE15_I354@PURE_QUANTA.Q_RES(CHIPS)':
 C_PATH='@scm_lib.scm(sch_1):page15_i354@pure_quanta.q_res(chips)',
 P_PATH='@scm_lib.scm(sch_1):page15_i354@pure_quanta.q_res(chips)',
 PATH='I354',
 DRAWING='@SCM_LIB.SCM(SCH_1):PAGE15',
 PHYS_PAGE='15',
 XY='(3900,3050)',
 ROT='0',
 VER='1',
 PACK_TYPE='0402LF',
 CDS_LIB='pure_quanta',
 CDS_PART_NAME='Q_RES_0402LF-49.9,1%,1/16W,EMPA',
 WATTAGE='1/16W',
 TOLERANCE='1%',
 MATERIAL='EMPTY',
 VALUE='49.9',
 PRIM_FILE='W:/<user>/logical/q_res/chips/chips.prt';

PART_NAME
 R441 'Q_RES_0402LF-49.9,1%,1/16W,EMPA':;

SECTION_NUMBER 1
 '@SCM_LIB.SCM(SCH_1):PAGE15_I353@PURE_QUANTA.Q_RES(CHIPS)':
 C_PATH='@scm_lib.scm(sch_1):page15_i353@pure_quanta.q_res(chips)',
 P_PATH='@scm_lib.scm(sch_1):page15_i353@pure_quanta.q_res(chips)',
 PATH='I353',
 DRAWING='@SCM_LIB.SCM(SCH_1):PAGE15',
 PHYS_PAGE='15',
 XY='(3900,2975)',
 ROT='0',
 VER='1',
 PACK_TYPE='0402LF',
 CDS_LIB='pure_quanta',
 CDS_PART_NAME='Q_RES_0402LF-49.9,1%,1/16W,EMPA',
 WATTAGE='1/16W',
 TOLERANCE='1%',
 MATERIAL='EMPTY',
 VALUE='49.9',
 PRIM_FILE='W:/<user>/logical/q_res/chips/chips.prt';

PART_NAME
 R442 'Q_RES_0402LF-33.2,1%,1/16W,CHIA':;

SECTION_NUMBER 1
 '@SCM_LIB.SCM(SCH_1):PAGE13_I301@PURE_QUANTA.Q_RES(CHIPS)':
 C_PATH='@scm_lib.scm(sch_1):page13_i301@pure_quanta.q_res(chips)',
 P_PATH='@scm_lib.scm(sch_1):page13_i301@pure_quanta.q_res(chips)',
 PATH='I301',
 DRAWING='@SCM_LIB.SCM(SCH_1):PAGE13',
 PHYS_PAGE='13',
 XY='(-1750,3275)',
 ROT='0',
 VER='1',
 PACK_TYPE='0402LF',
 LOCATION='R442',
 CDS_LIB='pure_quanta',
 CDS_PART_NAME='Q_RES_0402LF-33.2,1%,1/16W,CHIA',
 WATTAGE='1/16W',
 TOLERANCE='1%',
 MATERIAL='CHIP',
 VALUE='33.2',
 PRIM_FILE='W:/<user>/logical/q_res/chips/chips.prt';

PART_NAME
 R443 'Q_RES_0402LF-33.2,1%,1/16W,CHIA':;

SECTION_NUMBER 1
 '@SCM_LIB.SCM(SCH_1):PAGE13_I300@PURE_QUANTA.Q_RES(CHIPS)':
 C_PATH='@scm_lib.scm(sch_1):page13_i300@pure_quanta.q_res(chips)',
 P_PATH='@scm_lib.scm(sch_1):page13_i300@pure_quanta.q_res(chips)',
 PATH='I300',
 DRAWING='@SCM_LIB.SCM(SCH_1):PAGE13',
 PHYS_PAGE='13',
 XY='(-1750,3225)',
 ROT='0',
 VER='1',
 PACK_TYPE='0402LF',
 LOCATION='R443',
 CDS_LIB='pure_quanta',
 CDS_PART_NAME='Q_RES_0402LF-33.2,1%,1/16W,CHIA',
 WATTAGE='1/16W',
 TOLERANCE='1%',
 MATERIAL='CHIP',
 VALUE='33.2',
 PRIM_FILE='W:/<user>/logical/q_res/chips/chips.prt';

PART_NAME
 R444 'Q_RES_0402LF-33.2,1%,1/16W,CHIA':;

SECTION_NUMBER 1
 '@SCM_LIB.SCM(SCH_1):PAGE13_I306@PURE_QUANTA.Q_RES(CHIPS)':
 C_PATH='@scm_lib.scm(sch_1):page13_i306@pure_quanta.q_res(chips)',
 P_PATH='@scm_lib.scm(sch_1):page13_i306@pure_quanta.q_res(chips)',
 PATH='I306',
 DRAWING='@SCM_LIB.SCM(SCH_1):PAGE13',
 PHYS_PAGE='13',
 XY='(-1750,3075)',
 ROT='0',
 VER='1',
 PACK_TYPE='0402LF',
 LOCATION='R444',
 CDS_LIB='pure_quanta',
 CDS_PART_NAME='Q_RES_0402LF-33.2,1%,1/16W,CHIA',
 WATTAGE='1/16W',
 TOLERANCE='1%',
 MATERIAL='CHIP',
 VALUE='33.2',
 PRIM_FILE='W:/<user>/logical/q_res/chips/chips.prt';

PART_NAME
 R445 'Q_RES_0402LF-33.2,1%,1/16W,CHIA':;

SECTION_NUMBER 1
 '@SCM_LIB.SCM(SCH_1):PAGE36_I81@PURE_QUANTA.Q_RES(CHIPS)':
 C_PATH='@scm_lib.scm(sch_1):page36_i81@pure_quanta.q_res(chips)',
 P_PATH='@scm_lib.scm(sch_1):page36_i81@pure_quanta.q_res(chips)',
 PATH='I81',
 DRAWING='@SCM_LIB.SCM(SCH_1):PAGE36',
 PHYS_PAGE='36',
 XY='(-7250,4775)',
 ROT='0',
 VER='1',
 PACK_TYPE='0402LF',
 LOCATION='R445',
 CDS_LIB='pure_quanta',
 CDS_PART_NAME='Q_RES_0402LF-33.2,1%,1/16W,CHIA',
 WATTAGE='1/16W',
 TOLERANCE='1%',
 MATERIAL='CHIP',
 VALUE='33.2',
 PRIM_FILE='W:/<user>/logical/q_res/chips/chips.prt';

PART_NAME
 R446 'Q_RES_0402LF-4.7K,1%,1/16W,CHIA':;

SECTION_NUMBER 1
 '@SCM_LIB.SCM(SCH_1):PAGE13_I299@PURE_QUANTA.Q_RES(CHIPS)':
 C_PATH='@scm_lib.scm(sch_1):page13_i299@pure_quanta.q_res(chips)',
 P_PATH='@scm_lib.scm(sch_1):page13_i299@pure_quanta.q_res(chips)',
 PATH='I299',
 DRAWING='@SCM_LIB.SCM(SCH_1):PAGE13',
 SEC_TYPE='0402LF',
 PHYS_PAGE='13',
 XY='(2800,-850)',
 ROT='0',
 VER='1',
 PACK_TYPE='0402LF',
 LOCATION='R446',
 SEC='1',
 CDS_LIB='pure_quanta',
 CDS_PART_NAME='Q_RES_0402LF-4.7K,1%,1/16W,CHIA',
 WATTAGE='1/16W',
 TOLERANCE='1%',
 MATERIAL='CHIP',
 VALUE='4.7K',
 PRIM_FILE='W:/<user>/logical/q_res/chips/chips.prt';

PART_NAME
 R447 'Q_RES_0402LF-0,5%,1/16W,CHIP,CA':;

SECTION_NUMBER 1
 '@SCM_LIB.SCM(SCH_1):PAGE34_I168@PURE_QUANTA.Q_RES(CHIPS)':
 C_PATH='@scm_lib.scm(sch_1):page34_i168@pure_quanta.q_res(chips)',
 P_PATH='@scm_lib.scm(sch_1):page34_i168@pure_quanta.q_res(chips)',
 PATH='I168',
 DRAWING='@SCM_LIB.SCM(SCH_1):PAGE34',
 PHYS_PAGE='34',
 XY='(-2550,4350)',
 ROT='0',
 VER='1',
 PACK_TYPE='0402LF',
 LOCATION='R447',
 CDS_LIB='pure_quanta',
 CDS_PART_NAME='Q_RES_0402LF-0,5%,1/16W,CHIP,CA',
 WATTAGE='1/16W',
 TOLERANCE='5%',
 MATERIAL='CHIP',
 VALUE='0',
 PRIM_FILE='W:/<user>/logical/q_res/chips/chips.prt';

PART_NAME
 R448 'Q_RES_0402LF-33.2,1%,1/16W,CHIA':;

SECTION_NUMBER 1
 '@SCM_LIB.SCM(SCH_1):PAGE15_I320@PURE_QUANTA.Q_RES(CHIPS)':
 C_PATH='@scm_lib.scm(sch_1):page15_i320@pure_quanta.q_res(chips)',
 P_PATH='@scm_lib.scm(sch_1):page15_i320@pure_quanta.q_res(chips)',
 PATH='I320',
 DRAWING='@SCM_LIB.SCM(SCH_1):PAGE15',
 PHYS_PAGE='15',
 XY='(-1300,2625)',
 ROT='0',
 VER='1',
 PACK_TYPE='0402LF',
 LOCATION='R448',
 CDS_LIB='pure_quanta',
 CDS_PART_NAME='Q_RES_0402LF-33.2,1%,1/16W,CHIA',
 WATTAGE='1/16W',
 TOLERANCE='1%',
 MATERIAL='CHIP',
 VALUE='33.2',
 PRIM_FILE='W:/<user>/logical/q_res/chips/chips.prt';

PART_NAME
 R449 'Q_RES_0402LF-33.2,1%,1/16W,CHIA':;

SECTION_NUMBER 1
 '@SCM_LIB.SCM(SCH_1):PAGE15_I321@PURE_QUANTA.Q_RES(CHIPS)':
 C_PATH='@scm_lib.scm(sch_1):page15_i321@pure_quanta.q_res(chips)',
 P_PATH='@scm_lib.scm(sch_1):page15_i321@pure_quanta.q_res(chips)',
 PATH='I321',
 DRAWING='@SCM_LIB.SCM(SCH_1):PAGE15',
 PHYS_PAGE='15',
 XY='(-1300,2575)',
 ROT='0',
 VER='1',
 PACK_TYPE='0402LF',
 LOCATION='R449',
 CDS_LIB='pure_quanta',
 CDS_PART_NAME='Q_RES_0402LF-33.2,1%,1/16W,CHIA',
 WATTAGE='1/16W',
 TOLERANCE='1%',
 MATERIAL='CHIP',
 VALUE='33.2',
 PRIM_FILE='W:/<user>/logical/q_res/chips/chips.prt';

PART_NAME
 R450 'Q_RES_0402LF-0,5%,1/16W,CHIP,CA':;

SECTION_NUMBER 1
 '@SCM_LIB.SCM(SCH_1):PAGE22_I101@PURE_QUANTA.Q_RES(CHIPS)':
 C_PATH='@scm_lib.scm(sch_1):page22_i101@pure_quanta.q_res(chips)',
 P_PATH='@scm_lib.scm(sch_1):page22_i101@pure_quanta.q_res(chips)',
 PATH='I101',
 DRAWING='@SCM_LIB.SCM(SCH_1):PAGE22',
 PHYS_PAGE='22',
 XY='(-3700,2750)',
 ROT='0',
 VER='2',
 PACK_TYPE='0402LF',
 LOCATION='R450',
 CDS_LIB='pure_quanta',
 CDS_PART_NAME='Q_RES_0402LF-0,5%,1/16W,CHIP,CA',
 WATTAGE='1/16W',
 TOLERANCE='5%',
 MATERIAL='CHIP',
 VALUE='0',
 PRIM_FILE='W:/<user>/logical/q_res/chips/chips.prt';

PART_NAME
 R451 'Q_RES_0402LF-0,5%,1/16W,CHIP,CA':;

SECTION_NUMBER 1
 '@SCM_LIB.SCM(SCH_1):PAGE22_I74@PURE_QUANTA.Q_RES(CHIPS)':
 C_PATH='@scm_lib.scm(sch_1):page22_i74@pure_quanta.q_res(chips)',
 P_PATH='@scm_lib.scm(sch_1):page22_i74@pure_quanta.q_res(chips)',
 PATH='I74',
 DRAWING='@SCM_LIB.SCM(SCH_1):PAGE22',
 PHYS_PAGE='22',
 XY='(-2975,-175)',
 ROT='0',
 VER='1',
 PACK_TYPE='0402LF',
 LOCATION='R451',
 CDS_LIB='pure_quanta',
 CDS_PART_NAME='Q_RES_0402LF-0,5%,1/16W,CHIP,CA',
 WATTAGE='1/16W',
 TOLERANCE='5%',
 MATERIAL='CHIP',
 VALUE='0',
 PRIM_FILE='W:/<user>/logical/q_res/chips/chips.prt';

PART_NAME
 R452 'Q_RES_0402LF-4.7K,1%,1/16W,CHIA':;

SECTION_NUMBER 1
 '@SCM_LIB.SCM(SCH_1):PAGE13_I339@PURE_QUANTA.Q_RES(CHIPS)':
 C_PATH='@scm_lib.scm(sch_1):page13_i339@pure_quanta.q_res(chips)',
 P_PATH='@scm_lib.scm(sch_1):page13_i339@pure_quanta.q_res(chips)',
 PATH='I339',
 DRAWING='@SCM_LIB.SCM(SCH_1):PAGE13',
 SEC_TYPE='0402LF',
 PHYS_PAGE='13',
 XY='(2800,-900)',
 ROT='0',
 VER='1',
 PACK_TYPE='0402LF',
 LOCATION='R452',
 SEC='1',
 CDS_LIB='pure_quanta',
 CDS_PART_NAME='Q_RES_0402LF-4.7K,1%,1/16W,CHIA',
 WATTAGE='1/16W',
 TOLERANCE='1%',
 MATERIAL='CHIP',
 VALUE='4.7K',
 PRIM_FILE='W:/<user>/logical/q_res/chips/chips.prt';

PART_NAME
 R453 'Q_RES_0402LF-0,5%,1/16W,CHIP,CA':;

SECTION_NUMBER 1
 '@SCM_LIB.SCM(SCH_1):PAGE35_I2@PURE_QUANTA.Q_RES(CHIPS)':
 C_PATH='@scm_lib.scm(sch_1):page35_i2@pure_quanta.q_res(chips)',
 P_PATH='@scm_lib.scm(sch_1):page35_i2@pure_quanta.q_res(chips)',
 PATH='I2',
 DRAWING='@SCM_LIB.SCM(SCH_1):PAGE35',
 PHYS_PAGE='35',
 XY='(-7300,4950)',
 ROT='0',
 VER='1',
 PACK_TYPE='0402LF',
 LOCATION='R453',
 CDS_LIB='pure_quanta',
 CDS_PART_NAME='Q_RES_0402LF-0,5%,1/16W,CHIP,CA',
 WATTAGE='1/16W',
 TOLERANCE='5%',
 MATERIAL='CHIP',
 VALUE='0',
 PRIM_FILE='W:/<user>/logical/q_res/chips/chips.prt';

PART_NAME
 R454 'Q_RES_0402LF-0,5%,1/16W,CHIP,CA':;

SECTION_NUMBER 1
 '@SCM_LIB.SCM(SCH_1):PAGE35_I3@PURE_QUANTA.Q_RES(CHIPS)':
 C_PATH='@scm_lib.scm(sch_1):page35_i3@pure_quanta.q_res(chips)',
 P_PATH='@scm_lib.scm(sch_1):page35_i3@pure_quanta.q_res(chips)',
 PATH='I3',
 DRAWING='@SCM_LIB.SCM(SCH_1):PAGE35',
 PHYS_PAGE='35',
 XY='(-7300,4900)',
 ROT='0',
 VER='1',
 PACK_TYPE='0402LF',
 LOCATION='R454',
 CDS_LIB='pure_quanta',
 CDS_PART_NAME='Q_RES_0402LF-0,5%,1/16W,CHIP,CA',
 WATTAGE='1/16W',
 TOLERANCE='5%',
 MATERIAL='CHIP',
 VALUE='0',
 PRIM_FILE='W:/<user>/logical/q_res/chips/chips.prt';

PART_NAME
 R455 'Q_RES_0402LF-33.2,1%,1/16W,CHIA':;

SECTION_NUMBER 1
 '@SCM_LIB.SCM(SCH_1):PAGE10_I557@PURE_QUANTA.Q_RES(CHIPS)':
 C_PATH='@scm_lib.scm(sch_1):page10_i557@pure_quanta.q_res(chips)',
 P_PATH='@scm_lib.scm(sch_1):page10_i557@pure_quanta.q_res(chips)',
 PATH='I557',
 DRAWING='@SCM_LIB.SCM(SCH_1):PAGE10',
 PHYS_PAGE='10',
 XY='(-10350,2000)',
 ROT='0',
 VER='1',
 PACK_TYPE='0402LF',
 CDS_LIB='pure_quanta',
 CDS_PART_NAME='Q_RES_0402LF-33.2,1%,1/16W,CHIA',
 WATTAGE='1/16W',
 TOLERANCE='1%',
 MATERIAL='CHIP',
 VALUE='33.2',
 PRIM_FILE='W:/<user>/logical/q_res/chips/chips.prt';

PART_NAME
 R456 'Q_RES_0402LF-0,5%,1/16W,CHIP,CA':;

SECTION_NUMBER 1
 '@SCM_LIB.SCM(SCH_1):PAGE35_I4@PURE_QUANTA.Q_RES(CHIPS)':
 C_PATH='@scm_lib.scm(sch_1):page35_i4@pure_quanta.q_res(chips)',
 P_PATH='@scm_lib.scm(sch_1):page35_i4@pure_quanta.q_res(chips)',
 PATH='I4',
 DRAWING='@SCM_LIB.SCM(SCH_1):PAGE35',
 PHYS_PAGE='35',
 XY='(-7300,4800)',
 ROT='0',
 VER='1',
 PACK_TYPE='0402LF',
 LOCATION='R456',
 CDS_LIB='pure_quanta',
 CDS_PART_NAME='Q_RES_0402LF-0,5%,1/16W,CHIP,CA',
 WATTAGE='1/16W',
 TOLERANCE='5%',
 MATERIAL='CHIP',
 VALUE='0',
 PRIM_FILE='W:/<user>/logical/q_res/chips/chips.prt';

PART_NAME
 R457 'Q_RES_0402LF-0,5%,1/16W,CHIP,CA':;

SECTION_NUMBER 1
 '@SCM_LIB.SCM(SCH_1):PAGE35_I5@PURE_QUANTA.Q_RES(CHIPS)':
 C_PATH='@scm_lib.scm(sch_1):page35_i5@pure_quanta.q_res(chips)',
 P_PATH='@scm_lib.scm(sch_1):page35_i5@pure_quanta.q_res(chips)',
 PATH='I5',
 DRAWING='@SCM_LIB.SCM(SCH_1):PAGE35',
 PHYS_PAGE='35',
 XY='(-7300,4750)',
 ROT='0',
 VER='1',
 PACK_TYPE='0402LF',
 LOCATION='R457',
 CDS_LIB='pure_quanta',
 CDS_PART_NAME='Q_RES_0402LF-0,5%,1/16W,CHIP,CA',
 WATTAGE='1/16W',
 TOLERANCE='5%',
 MATERIAL='CHIP',
 VALUE='0',
 PRIM_FILE='W:/<user>/logical/q_res/chips/chips.prt';

PART_NAME
 R458 'Q_RES_0402LF-33.2,1%,1/16W,CHIA':;

SECTION_NUMBER 1
 '@SCM_LIB.SCM(SCH_1):PAGE13_I407@PURE_QUANTA.Q_RES(CHIPS)':
 C_PATH='@scm_lib.scm(sch_1):page13_i407@pure_quanta.q_res(chips)',
 P_PATH='@scm_lib.scm(sch_1):page13_i407@pure_quanta.q_res(chips)',
 PATH='I407',
 DRAWING='@SCM_LIB.SCM(SCH_1):PAGE13',
 PHYS_PAGE='13',
 XY='(3250,3875)',
 ROT='0',
 VER='1',
 PACK_TYPE='0402LF',
 LOCATION='R458',
 CDS_LIB='pure_quanta',
 CDS_PART_NAME='Q_RES_0402LF-33.2,1%,1/16W,CHIA',
 WATTAGE='1/16W',
 TOLERANCE='1%',
 MATERIAL='CHIP',
 VALUE='33.2',
 PRIM_FILE='W:/<user>/logical/q_res/chips/chips.prt';

PART_NAME
 R459 'Q_RES_0402LF-33.2,1%,1/16W,CHIA':;

SECTION_NUMBER 1
 '@SCM_LIB.SCM(SCH_1):PAGE34_I159@PURE_QUANTA.Q_RES(CHIPS)':
 C_PATH='@scm_lib.scm(sch_1):page34_i159@pure_quanta.q_res(chips)',
 P_PATH='@scm_lib.scm(sch_1):page34_i159@pure_quanta.q_res(chips)',
 PATH='I159',
 DRAWING='@SCM_LIB.SCM(SCH_1):PAGE34',
 PHYS_PAGE='34',
 XY='(-7000,4650)',
 ROT='0',
 VER='1',
 PACK_TYPE='0402LF',
 LOCATION='R459',
 CDS_LIB='pure_quanta',
 CDS_PART_NAME='Q_RES_0402LF-33.2,1%,1/16W,CHIA',
 WATTAGE='1/16W',
 TOLERANCE='1%',
 MATERIAL='CHIP',
 VALUE='33.2',
 PRIM_FILE='W:/<user>/logical/q_res/chips/chips.prt';

PART_NAME
 R460 'Q_RES_0402LF-33.2,1%,1/16W,CHIA':;

SECTION_NUMBER 1
 '@SCM_LIB.SCM(SCH_1):PAGE13_I312@PURE_QUANTA.Q_RES(CHIPS)':
 C_PATH='@scm_lib.scm(sch_1):page13_i312@pure_quanta.q_res(chips)',
 P_PATH='@scm_lib.scm(sch_1):page13_i312@pure_quanta.q_res(chips)',
 PATH='I312',
 DRAWING='@SCM_LIB.SCM(SCH_1):PAGE13',
 PHYS_PAGE='13',
 XY='(-1775,3975)',
 ROT='0',
 VER='1',
 PACK_TYPE='0402LF',
 LOCATION='R460',
 CDS_LIB='pure_quanta',
 CDS_PART_NAME='Q_RES_0402LF-33.2,1%,1/16W,CHIA',
 WATTAGE='1/16W',
 TOLERANCE='1%',
 MATERIAL='CHIP',
 VALUE='33.2',
 PRIM_FILE='W:/<user>/logical/q_res/chips/chips.prt';

PART_NAME
 R461 'Q_RES_0402LF-33.2,1%,1/16W,CHIA':;

SECTION_NUMBER 1
 '@SCM_LIB.SCM(SCH_1):PAGE13_I365@PURE_QUANTA.Q_RES(CHIPS)':
 C_PATH='@scm_lib.scm(sch_1):page13_i365@pure_quanta.q_res(chips)',
 P_PATH='@scm_lib.scm(sch_1):page13_i365@pure_quanta.q_res(chips)',
 PATH='I365',
 DRAWING='@SCM_LIB.SCM(SCH_1):PAGE13',
 PHYS_PAGE='13',
 XY='(-1775,2775)',
 ROT='0',
 VER='1',
 PACK_TYPE='0402LF',
 LOCATION='R461',
 CDS_LIB='pure_quanta',
 CDS_PART_NAME='Q_RES_0402LF-33.2,1%,1/16W,CHIA',
 WATTAGE='1/16W',
 TOLERANCE='1%',
 MATERIAL='CHIP',
 VALUE='33.2',
 PRIM_FILE='W:/<user>/logical/q_res/chips/chips.prt';

PART_NAME
 R462 'Q_RES_0402LF-4.7K,1%,1/16W,CHIA':;

SECTION_NUMBER 1
 '@SCM_LIB.SCM(SCH_1):PAGE15_I391@PURE_QUANTA.Q_RES(CHIPS)':
 C_PATH='@scm_lib.scm(sch_1):page15_i391@pure_quanta.q_res(chips)',
 P_PATH='@scm_lib.scm(sch_1):page15_i391@pure_quanta.q_res(chips)',
 PATH='I391',
 DRAWING='@SCM_LIB.SCM(SCH_1):PAGE15',
 PHYS_PAGE='15',
 XY='(4425,3900)',
 ROT='0',
 VER='1',
 PACK_TYPE='0402LF',
 CDS_LIB='pure_quanta',
 CDS_PART_NAME='Q_RES_0402LF-4.7K,1%,1/16W,CHIA',
 WATTAGE='1/16W',
 TOLERANCE='1%',
 MATERIAL='CHIP',
 VALUE='4.7K',
 PRIM_FILE='W:/<user>/logical/q_res/chips/chips.prt';

PART_NAME
 R463 'Q_RES_0402LF-0,5%,1/16W,EMPTY,A':;

SECTION_NUMBER 1
 '@SCM_LIB.SCM(SCH_1):PAGE35_I131@PURE_QUANTA.Q_RES(CHIPS)':
 C_PATH='@scm_lib.scm(sch_1):page35_i131@pure_quanta.q_res(chips)',
 P_PATH='@scm_lib.scm(sch_1):page35_i131@pure_quanta.q_res(chips)',
 PATH='I131',
 DRAWING='@SCM_LIB.SCM(SCH_1):PAGE35',
 SEC_TYPE='0402LF',
 PHYS_PAGE='35',
 XY='(-6800,3600)',
 ROT='0',
 VER='1',
 PACK_TYPE='0402LF',
 SEC='1',
 CDS_LIB='pure_quanta',
 CDS_PART_NAME='Q_RES_0402LF-0,5%,1/16W,EMPTY,A',
 WATTAGE='1/16W',
 TOLERANCE='5%',
 MATERIAL='EMPTY',
 VALUE='0',
 PRIM_FILE='W:/<user>/logical/q_res/chips/chips.prt';

PART_NAME
 R464 'Q_RES_0402LF-10K,1%,1/16W,CHIPA':;

SECTION_NUMBER 1
 '@SCM_LIB.SCM(SCH_1):PAGE46_I75@PURE_QUANTA.Q_RES(CHIPS)':
 C_PATH='@scm_lib.scm(sch_1):page46_i75@pure_quanta.q_res(chips)',
 P_PATH='@scm_lib.scm(sch_1):page46_i75@pure_quanta.q_res(chips)',
 PATH='I75',
 DRAWING='@SCM_LIB.SCM(SCH_1):PAGE46',
 PHYS_PAGE='46',
 XY='(-5250,-2450)',
 ROT='2',
 VER='2',
 PACK_TYPE='0402LF',
 LOCATION='R464',
 CDS_LIB='pure_quanta',
 CDS_PART_NAME='Q_RES_0402LF-10K,1%,1/16W,CHIPA',
 WATTAGE='1/16W',
 TOLERANCE='1%',
 MATERIAL='CHIP',
 VALUE='10K',
 PRIM_FILE='W:/<user>/logical/q_res/chips/chips.prt';

PART_NAME
 R465 'Q_RES_0402LF-33.2,1%,1/16W,CHIA':;

SECTION_NUMBER 1
 '@SCM_LIB.SCM(SCH_1):PAGE13_I432@PURE_QUANTA.Q_RES(CHIPS)':
 C_PATH='@scm_lib.scm(sch_1):page13_i432@pure_quanta.q_res(chips)',
 P_PATH='@scm_lib.scm(sch_1):page13_i432@pure_quanta.q_res(chips)',
 PATH='I432',
 DRAWING='@SCM_LIB.SCM(SCH_1):PAGE13',
 PHYS_PAGE='13',
 XY='(3650,3075)',
 ROT='0',
 VER='1',
 PACK_TYPE='0402LF',
 LOCATION='R465',
 CDS_LIB='pure_quanta',
 CDS_PART_NAME='Q_RES_0402LF-33.2,1%,1/16W,CHIA',
 WATTAGE='1/16W',
 TOLERANCE='1%',
 MATERIAL='CHIP',
 VALUE='33.2',
 PRIM_FILE='W:/<user>/logical/q_res/chips/chips.prt';

PART_NAME
 R466 'Q_RES_0402LF-33.2,1%,1/16W,CHIA':;

SECTION_NUMBER 1
 '@SCM_LIB.SCM(SCH_1):PAGE13_I431@PURE_QUANTA.Q_RES(CHIPS)':
 C_PATH='@scm_lib.scm(sch_1):page13_i431@pure_quanta.q_res(chips)',
 P_PATH='@scm_lib.scm(sch_1):page13_i431@pure_quanta.q_res(chips)',
 PATH='I431',
 DRAWING='@SCM_LIB.SCM(SCH_1):PAGE13',
 PHYS_PAGE='13',
 XY='(3800,2625)',
 ROT='0',
 VER='1',
 PACK_TYPE='0402LF',
 LOCATION='R466',
 CDS_LIB='pure_quanta',
 CDS_PART_NAME='Q_RES_0402LF-33.2,1%,1/16W,CHIA',
 WATTAGE='1/16W',
 TOLERANCE='1%',
 MATERIAL='CHIP',
 VALUE='33.2',
 PRIM_FILE='W:/<user>/logical/q_res/chips/chips.prt';

PART_NAME
 R467 'Q_RES_0402LF-2K,1%,1/16W,CHIP,A':;

SECTION_NUMBER 1
 '@SCM_LIB.SCM(SCH_1):PAGE44_I313@PURE_QUANTA.Q_RES(CHIPS)':
 C_PATH='@scm_lib.scm(sch_1):page44_i313@pure_quanta.q_res(chips)',
 P_PATH='@scm_lib.scm(sch_1):page44_i313@pure_quanta.q_res(chips)',
 PATH='I313',
 DRAWING='@SCM_LIB.SCM(SCH_1):PAGE44',
 PHYS_PAGE='44',
 XY='(1250,-1375)',
 ROT='0',
 VER='2',
 PACK_TYPE='0402LF',
 LOCATION='R467',
 CDS_LIB='pure_quanta',
 CDS_PART_NAME='Q_RES_0402LF-2K,1%,1/16W,CHIP,A',
 WATTAGE='1/16W',
 TOLERANCE='1%',
 MATERIAL='CHIP',
 VALUE='2K',
 PRIM_FILE='W:/<user>/logical/q_res/chips/chips.prt';

PART_NAME
 R468 'Q_RES_0402LF-90.9,1%,1/16W,CHIA':;

SECTION_NUMBER 1
 '@SCM_LIB.SCM(SCH_1):PAGE13_I449@PURE_QUANTA.Q_RES(CHIPS)':
 C_PATH='@scm_lib.scm(sch_1):page13_i449@pure_quanta.q_res(chips)',
 P_PATH='@scm_lib.scm(sch_1):page13_i449@pure_quanta.q_res(chips)',
 PATH='I449',
 DRAWING='@SCM_LIB.SCM(SCH_1):PAGE13',
 PHYS_PAGE='13',
 XY='(3250,4025)',
 ROT='0',
 VER='1',
 PACK_TYPE='0402LF',
 LOCATION='R468',
 CDS_LIB='pure_quanta',
 CDS_PART_NAME='Q_RES_0402LF-90.9,1%,1/16W,CHIA',
 WATTAGE='1/16W',
 TOLERANCE='1%',
 MATERIAL='CHIP',
 VALUE='90.9',
 PRIM_FILE='W:/<user>/logical/q_res/chips/chips.prt';

PART_NAME
 R469 'Q_RES_0402LF-33.2,1%,1/16W,CHIA':;

SECTION_NUMBER 1
 '@SCM_LIB.SCM(SCH_1):PAGE13_I319@PURE_QUANTA.Q_RES(CHIPS)':
 C_PATH='@scm_lib.scm(sch_1):page13_i319@pure_quanta.q_res(chips)',
 P_PATH='@scm_lib.scm(sch_1):page13_i319@pure_quanta.q_res(chips)',
 PATH='I319',
 DRAWING='@SCM_LIB.SCM(SCH_1):PAGE13',
 PHYS_PAGE='13',
 XY='(3250,3925)',
 ROT='0',
 VER='1',
 PACK_TYPE='0402LF',
 LOCATION='R469',
 CDS_LIB='pure_quanta',
 CDS_PART_NAME='Q_RES_0402LF-33.2,1%,1/16W,CHIA',
 WATTAGE='1/16W',
 TOLERANCE='1%',
 MATERIAL='CHIP',
 VALUE='33.2',
 PRIM_FILE='W:/<user>/logical/q_res/chips/chips.prt';

PART_NAME
 R470 'Q_RES_0402LF-0,5%,1/16W,EMPTY,A':;

SECTION_NUMBER 1
 '@SCM_LIB.SCM(SCH_1):PAGE50_I241@PURE_QUANTA.Q_RES(CHIPS)':
 C_PATH='@scm_lib.scm(sch_1):page50_i241@pure_quanta.q_res(chips)',
 P_PATH='@scm_lib.scm(sch_1):page50_i241@pure_quanta.q_res(chips)',
 PATH='I241',
 DRAWING='@SCM_LIB.SCM(SCH_1):PAGE50',
 PHYS_PAGE='50',
 XY='(2675,3275)',
 ROT='0',
 VER='1',
 PACK_TYPE='0402LF',
 CDS_LIB='pure_quanta',
 CDS_PART_NAME='Q_RES_0402LF-0,5%,1/16W,EMPTY,A',
 WATTAGE='1/16W',
 TOLERANCE='5%',
 MATERIAL='EMPTY',
 VALUE='0',
 PRIM_FILE='W:/<user>/logical/q_res/chips/chips.prt';

PART_NAME
 R471 'Q_RES_0402LF-0,5%,1/16W,CHIP,CA':;

SECTION_NUMBER 1
 '@SCM_LIB.SCM(SCH_1):PAGE50_I242@PURE_QUANTA.Q_RES(CHIPS)':
 C_PATH='@scm_lib.scm(sch_1):page50_i242@pure_quanta.q_res(chips)',
 P_PATH='@scm_lib.scm(sch_1):page50_i242@pure_quanta.q_res(chips)',
 PATH='I242',
 DRAWING='@SCM_LIB.SCM(SCH_1):PAGE50',
 PHYS_PAGE='50',
 XY='(4100,2550)',
 ROT='0',
 VER='1',
 PACK_TYPE='0402LF',
 CDS_LIB='pure_quanta',
 CDS_PART_NAME='Q_RES_0402LF-0,5%,1/16W,CHIP,CA',
 WATTAGE='1/16W',
 TOLERANCE='5%',
 MATERIAL='CHIP',
 VALUE='0',
 PRIM_FILE='W:/<user>/logical/q_res/chips/chips.prt';

PART_NAME
 R472 'Q_RES_0402LF-4.7K,1%,1/16W,EMPA':;

SECTION_NUMBER 1
 '@SCM_LIB.SCM(SCH_1):PAGE35_I136@PURE_QUANTA.Q_RES(CHIPS)':
 C_PATH='@scm_lib.scm(sch_1):page35_i136@pure_quanta.q_res(chips)',
 P_PATH='@scm_lib.scm(sch_1):page35_i136@pure_quanta.q_res(chips)',
 PATH='I136',
 DRAWING='@SCM_LIB.SCM(SCH_1):PAGE35',
 PHYS_PAGE='35',
 XY='(-7950,2075)',
 ROT='0',
 VER='1',
 PACK_TYPE='0402LF',
 CDS_LIB='pure_quanta',
 CDS_PART_NAME='Q_RES_0402LF-4.7K,1%,1/16W,EMPA',
 WATTAGE='1/16W',
 TOLERANCE='1%',
 MATERIAL='EMPTY',
 VALUE='4.7K',
 PRIM_FILE='W:/<user>/logical/q_res/chips/chips.prt';

PART_NAME
 R479 'Q_RES_0402LF-33.2,1%,1/16W,CHIA':;

SECTION_NUMBER 1
 '@SCM_LIB.SCM(SCH_1):PAGE15_I330@PURE_QUANTA.Q_RES(CHIPS)':
 C_PATH='@scm_lib.scm(sch_1):page15_i330@pure_quanta.q_res(chips)',
 P_PATH='@scm_lib.scm(sch_1):page15_i330@pure_quanta.q_res(chips)',
 PATH='I330',
 DRAWING='@SCM_LIB.SCM(SCH_1):PAGE15',
 PHYS_PAGE='15',
 XY='(-825,3625)',
 ROT='0',
 VER='1',
 PACK_TYPE='0402LF',
 LOCATION='R479',
 CDS_LIB='pure_quanta',
 CDS_PART_NAME='Q_RES_0402LF-33.2,1%,1/16W,CHIA',
 WATTAGE='1/16W',
 TOLERANCE='1%',
 MATERIAL='CHIP',
 VALUE='33.2',
 PRIM_FILE='W:/<user>/logical/q_res/chips/chips.prt';

PART_NAME
 R481 'Q_RES_0402LF-33.2,1%,1/16W,CHIA':;

SECTION_NUMBER 1
 '@SCM_LIB.SCM(SCH_1):PAGE45_I24@PURE_QUANTA.Q_RES(CHIPS)':
 C_PATH='@scm_lib.scm(sch_1):page45_i24@pure_quanta.q_res(chips)',
 P_PATH='@scm_lib.scm(sch_1):page45_i24@pure_quanta.q_res(chips)',
 PATH='I24',
 DRAWING='@SCM_LIB.SCM(SCH_1):PAGE45',
 PHYS_PAGE='45',
 XY='(-1575,2100)',
 ROT='0',
 VER='1',
 PACK_TYPE='0402LF',
 LOCATION='R481',
 CDS_LIB='pure_quanta',
 CDS_PART_NAME='Q_RES_0402LF-33.2,1%,1/16W,CHIA',
 WATTAGE='1/16W',
 TOLERANCE='1%',
 MATERIAL='CHIP',
 VALUE='33.2',
 PRIM_FILE='W:/<user>/logical/q_res/chips/chips.prt';

PART_NAME
 R482 'Q_RES_0402LF-33.2,1%,1/16W,CHIA':;

SECTION_NUMBER 1
 '@SCM_LIB.SCM(SCH_1):PAGE45_I22@PURE_QUANTA.Q_RES(CHIPS)':
 C_PATH='@scm_lib.scm(sch_1):page45_i22@pure_quanta.q_res(chips)',
 P_PATH='@scm_lib.scm(sch_1):page45_i22@pure_quanta.q_res(chips)',
 PATH='I22',
 DRAWING='@SCM_LIB.SCM(SCH_1):PAGE45',
 PHYS_PAGE='45',
 XY='(-1575,2050)',
 ROT='0',
 VER='1',
 PACK_TYPE='0402LF',
 LOCATION='R482',
 CDS_LIB='pure_quanta',
 CDS_PART_NAME='Q_RES_0402LF-33.2,1%,1/16W,CHIA',
 WATTAGE='1/16W',
 TOLERANCE='1%',
 MATERIAL='CHIP',
 VALUE='33.2',
 PRIM_FILE='W:/<user>/logical/q_res/chips/chips.prt';

PART_NAME
 R483 'Q_RES_0402LF-33.2,1%,1/16W,CHIA':;

SECTION_NUMBER 1
 '@SCM_LIB.SCM(SCH_1):PAGE45_I23@PURE_QUANTA.Q_RES(CHIPS)':
 C_PATH='@scm_lib.scm(sch_1):page45_i23@pure_quanta.q_res(chips)',
 P_PATH='@scm_lib.scm(sch_1):page45_i23@pure_quanta.q_res(chips)',
 PATH='I23',
 DRAWING='@SCM_LIB.SCM(SCH_1):PAGE45',
 PHYS_PAGE='45',
 XY='(-1575,2000)',
 ROT='0',
 VER='1',
 PACK_TYPE='0402LF',
 LOCATION='R483',
 CDS_LIB='pure_quanta',
 CDS_PART_NAME='Q_RES_0402LF-33.2,1%,1/16W,CHIA',
 WATTAGE='1/16W',
 TOLERANCE='1%',
 MATERIAL='CHIP',
 VALUE='33.2',
 PRIM_FILE='W:/<user>/logical/q_res/chips/chips.prt';

PART_NAME
 R484 'Q_RES_0402LF-33.2,1%,1/16W,CHIA':;

SECTION_NUMBER 1
 '@SCM_LIB.SCM(SCH_1):PAGE45_I21@PURE_QUANTA.Q_RES(CHIPS)':
 C_PATH='@scm_lib.scm(sch_1):page45_i21@pure_quanta.q_res(chips)',
 P_PATH='@scm_lib.scm(sch_1):page45_i21@pure_quanta.q_res(chips)',
 PATH='I21',
 DRAWING='@SCM_LIB.SCM(SCH_1):PAGE45',
 PHYS_PAGE='45',
 XY='(-1575,1950)',
 ROT='0',
 VER='1',
 PACK_TYPE='0402LF',
 LOCATION='R484',
 CDS_LIB='pure_quanta',
 CDS_PART_NAME='Q_RES_0402LF-33.2,1%,1/16W,CHIA',
 WATTAGE='1/16W',
 TOLERANCE='1%',
 MATERIAL='CHIP',
 VALUE='33.2',
 PRIM_FILE='W:/<user>/logical/q_res/chips/chips.prt';

PART_NAME
 R485 'Q_RES_0402LF-33.2,1%,1/16W,CHIA':;

SECTION_NUMBER 1
 '@SCM_LIB.SCM(SCH_1):PAGE45_I20@PURE_QUANTA.Q_RES(CHIPS)':
 C_PATH='@scm_lib.scm(sch_1):page45_i20@pure_quanta.q_res(chips)',
 P_PATH='@scm_lib.scm(sch_1):page45_i20@pure_quanta.q_res(chips)',
 PATH='I20',
 DRAWING='@SCM_LIB.SCM(SCH_1):PAGE45',
 PHYS_PAGE='45',
 XY='(-1575,1900)',
 ROT='0',
 VER='1',
 PACK_TYPE='0402LF',
 LOCATION='R485',
 CDS_LIB='pure_quanta',
 CDS_PART_NAME='Q_RES_0402LF-33.2,1%,1/16W,CHIA',
 WATTAGE='1/16W',
 TOLERANCE='1%',
 MATERIAL='CHIP',
 VALUE='33.2',
 PRIM_FILE='W:/<user>/logical/q_res/chips/chips.prt';

PART_NAME
 R486 'Q_RES_0402LF-33.2,1%,1/16W,CHIA':;

SECTION_NUMBER 1
 '@SCM_LIB.SCM(SCH_1):PAGE45_I19@PURE_QUANTA.Q_RES(CHIPS)':
 C_PATH='@scm_lib.scm(sch_1):page45_i19@pure_quanta.q_res(chips)',
 P_PATH='@scm_lib.scm(sch_1):page45_i19@pure_quanta.q_res(chips)',
 PATH='I19',
 DRAWING='@SCM_LIB.SCM(SCH_1):PAGE45',
 PHYS_PAGE='45',
 XY='(-1575,1850)',
 ROT='0',
 VER='1',
 PACK_TYPE='0402LF',
 LOCATION='R486',
 CDS_LIB='pure_quanta',
 CDS_PART_NAME='Q_RES_0402LF-33.2,1%,1/16W,CHIA',
 WATTAGE='1/16W',
 TOLERANCE='1%',
 MATERIAL='CHIP',
 VALUE='33.2',
 PRIM_FILE='W:/<user>/logical/q_res/chips/chips.prt';

PART_NAME
 R487 'Q_RES_0402LF-4.7K,1%,1/16W,EMPA':;

SECTION_NUMBER 1
 '@SCM_LIB.SCM(SCH_1):PAGE45_I51@PURE_QUANTA.Q_RES(CHIPS)':
 C_PATH='@scm_lib.scm(sch_1):page45_i51@pure_quanta.q_res(chips)',
 P_PATH='@scm_lib.scm(sch_1):page45_i51@pure_quanta.q_res(chips)',
 PATH='I51',
 DRAWING='@SCM_LIB.SCM(SCH_1):PAGE45',
 PHYS_PAGE='45',
 XY='(-725,1550)',
 ROT='2',
 VER='2',
 PACK_TYPE='0402LF',
 LOCATION='R487',
 CDS_LIB='pure_quanta',
 CDS_PART_NAME='Q_RES_0402LF-4.7K,1%,1/16W,EMPA',
 WATTAGE='1/16W',
 TOLERANCE='1%',
 MATERIAL='EMPTY',
 VALUE='4.7K',
 PRIM_FILE='W:/<user>/logical/q_res/chips/chips.prt';

PART_NAME
 R488 'Q_RES_0402LF-4.7K,1%,1/16W,CHIA':;

SECTION_NUMBER 1
 '@SCM_LIB.SCM(SCH_1):PAGE45_I33@PURE_QUANTA.Q_RES(CHIPS)':
 C_PATH='@scm_lib.scm(sch_1):page45_i33@pure_quanta.q_res(chips)',
 P_PATH='@scm_lib.scm(sch_1):page45_i33@pure_quanta.q_res(chips)',
 PATH='I33',
 DRAWING='@SCM_LIB.SCM(SCH_1):PAGE45',
 PHYS_PAGE='45',
 XY='(-1075,2350)',
 ROT='0',
 VER='2',
 PACK_TYPE='0402LF',
 LOCATION='R488',
 CDS_LIB='pure_quanta',
 CDS_PART_NAME='Q_RES_0402LF-4.7K,1%,1/16W,CHIA',
 WATTAGE='1/16W',
 TOLERANCE='1%',
 MATERIAL='CHIP',
 VALUE='4.7K',
 PRIM_FILE='W:/<user>/logical/q_res/chips/chips.prt';

PART_NAME
 R489 'Q_RES_0402LF-33.2,1%,1/16W,CHIA':;

SECTION_NUMBER 1
 '@SCM_LIB.SCM(SCH_1):PAGE15_I326@PURE_QUANTA.Q_RES(CHIPS)':
 C_PATH='@scm_lib.scm(sch_1):page15_i326@pure_quanta.q_res(chips)',
 P_PATH='@scm_lib.scm(sch_1):page15_i326@pure_quanta.q_res(chips)',
 PATH='I326',
 DRAWING='@SCM_LIB.SCM(SCH_1):PAGE15',
 PHYS_PAGE='15',
 XY='(-825,3525)',
 ROT='0',
 VER='1',
 PACK_TYPE='0402LF',
 LOCATION='R489',
 CDS_LIB='pure_quanta',
 CDS_PART_NAME='Q_RES_0402LF-33.2,1%,1/16W,CHIA',
 WATTAGE='1/16W',
 TOLERANCE='1%',
 MATERIAL='CHIP',
 VALUE='33.2',
 PRIM_FILE='W:/<user>/logical/q_res/chips/chips.prt';

PART_NAME
 R490 'Q_RES_0402LF-4.7K,1%,1/16W,CHIA':;

SECTION_NUMBER 1
 '@SCM_LIB.SCM(SCH_1):PAGE45_I34@PURE_QUANTA.Q_RES(CHIPS)':
 C_PATH='@scm_lib.scm(sch_1):page45_i34@pure_quanta.q_res(chips)',
 P_PATH='@scm_lib.scm(sch_1):page45_i34@pure_quanta.q_res(chips)',
 PATH='I34',
 DRAWING='@SCM_LIB.SCM(SCH_1):PAGE45',
 PHYS_PAGE='45',
 XY='(-850,2350)',
 ROT='0',
 VER='2',
 PACK_TYPE='0402LF',
 LOCATION='R490',
 CDS_LIB='pure_quanta',
 CDS_PART_NAME='Q_RES_0402LF-4.7K,1%,1/16W,CHIA',
 WATTAGE='1/16W',
 TOLERANCE='1%',
 MATERIAL='CHIP',
 VALUE='4.7K',
 PRIM_FILE='W:/<user>/logical/q_res/chips/chips.prt';

PART_NAME
 R491 'Q_RES_0402LF-4.7K,1%,1/16W,EMPA':;

SECTION_NUMBER 1
 '@SCM_LIB.SCM(SCH_1):PAGE15_I346@PURE_QUANTA.Q_RES(CHIPS)':
 C_PATH='@scm_lib.scm(sch_1):page15_i346@pure_quanta.q_res(chips)',
 P_PATH='@scm_lib.scm(sch_1):page15_i346@pure_quanta.q_res(chips)',
 PATH='I346',
 DRAWING='@SCM_LIB.SCM(SCH_1):PAGE15',
 PHYS_PAGE='15',
 XY='(-2650,4275)',
 ROT='0',
 VER='2',
 PACK_TYPE='0402LF',
 LOCATION='R491',
 CDS_LIB='pure_quanta',
 CDS_PART_NAME='Q_RES_0402LF-4.7K,1%,1/16W,EMPA',
 WATTAGE='1/16W',
 TOLERANCE='1%',
 MATERIAL='EMPTY',
 VALUE='4.7K',
 PRIM_FILE='W:/<user>/logical/q_res/chips/chips.prt';

PART_NAME
 R492 'Q_RES_0402LF-4.7K,1%,1/16W,CHIA':;

SECTION_NUMBER 1
 '@SCM_LIB.SCM(SCH_1):PAGE45_I35@PURE_QUANTA.Q_RES(CHIPS)':
 C_PATH='@scm_lib.scm(sch_1):page45_i35@pure_quanta.q_res(chips)',
 P_PATH='@scm_lib.scm(sch_1):page45_i35@pure_quanta.q_res(chips)',
 PATH='I35',
 DRAWING='@SCM_LIB.SCM(SCH_1):PAGE45',
 PHYS_PAGE='45',
 XY='(-625,2350)',
 ROT='0',
 VER='2',
 PACK_TYPE='0402LF',
 LOCATION='R492',
 CDS_LIB='pure_quanta',
 CDS_PART_NAME='Q_RES_0402LF-4.7K,1%,1/16W,CHIA',
 WATTAGE='1/16W',
 TOLERANCE='1%',
 MATERIAL='CHIP',
 VALUE='4.7K',
 PRIM_FILE='W:/<user>/logical/q_res/chips/chips.prt';

PART_NAME
 R493 'Q_RES_0402LF-150K,1%,1/16W,EMPA':;

SECTION_NUMBER 1
 '@SCM_LIB.SCM(SCH_1):PAGE17_I284@PURE_QUANTA.Q_RES(CHIPS)':
 C_PATH='@scm_lib.scm(sch_1):page17_i284@pure_quanta.q_res(chips)',
 P_PATH='@scm_lib.scm(sch_1):page17_i284@pure_quanta.q_res(chips)',
 PATH='I284',
 DRAWING='@SCM_LIB.SCM(SCH_1):PAGE17',
 PHYS_PAGE='17',
 XY='(1725,-400)',
 ROT='0',
 VER='2',
 PACK_TYPE='0402LF',
 LOCATION='R493',
 CDS_LIB='pure_quanta',
 CDS_PART_NAME='Q_RES_0402LF-150K,1%,1/16W,EMPA',
 WATTAGE='1/16W',
 TOLERANCE='1%',
 MATERIAL='EMPTY',
 VALUE='150K',
 PRIM_FILE='W:/<user>/logical/q_res/chips/chips.prt';

PART_NAME
 R494 'Q_RES_0402LF-33.2,1%,1/16W,CHIA':;

SECTION_NUMBER 1
 '@SCM_LIB.SCM(SCH_1):PAGE13_I335@PURE_QUANTA.Q_RES(CHIPS)':
 C_PATH='@scm_lib.scm(sch_1):page13_i335@pure_quanta.q_res(chips)',
 P_PATH='@scm_lib.scm(sch_1):page13_i335@pure_quanta.q_res(chips)',
 PATH='I335',
 DRAWING='@SCM_LIB.SCM(SCH_1):PAGE13',
 SEC_TYPE='0402LF',
 PHYS_PAGE='13',
 XY='(3650,3175)',
 ROT='0',
 VER='1',
 PACK_TYPE='0402LF',
 LOCATION='R494',
 SEC='1',
 CDS_LIB='pure_quanta',
 CDS_PART_NAME='Q_RES_0402LF-33.2,1%,1/16W,CHIA',
 WATTAGE='1/16W',
 TOLERANCE='1%',
 MATERIAL='CHIP',
 VALUE='33.2',
 PRIM_FILE='W:/<user>/logical/q_res/chips/chips.prt';

PART_NAME
 R496 'Q_RES_0402LF-4.7K,1%,1/16W,EMPA':;

SECTION_NUMBER 1
 '@SCM_LIB.SCM(SCH_1):PAGE45_I48@PURE_QUANTA.Q_RES(CHIPS)':
 C_PATH='@scm_lib.scm(sch_1):page45_i48@pure_quanta.q_res(chips)',
 P_PATH='@scm_lib.scm(sch_1):page45_i48@pure_quanta.q_res(chips)',
 PATH='I48',
 DRAWING='@SCM_LIB.SCM(SCH_1):PAGE45',
 PHYS_PAGE='45',
 XY='(3275,2250)',
 ROT='2',
 VER='2',
 PACK_TYPE='0402LF',
 LOCATION='R496',
 CDS_LIB='pure_quanta',
 CDS_PART_NAME='Q_RES_0402LF-4.7K,1%,1/16W,EMPA',
 WATTAGE='1/16W',
 TOLERANCE='1%',
 MATERIAL='EMPTY',
 VALUE='4.7K',
 PRIM_FILE='W:/<user>/logical/q_res/chips/chips.prt';

PART_NAME
 R497 'Q_RES_0402LF-10K,1%,1/16W,CHIPA':;

SECTION_NUMBER 1
 '@SCM_LIB.SCM(SCH_1):PAGE46_I78@PURE_QUANTA.Q_RES(CHIPS)':
 C_PATH='@scm_lib.scm(sch_1):page46_i78@pure_quanta.q_res(chips)',
 P_PATH='@scm_lib.scm(sch_1):page46_i78@pure_quanta.q_res(chips)',
 PATH='I78',
 DRAWING='@SCM_LIB.SCM(SCH_1):PAGE46',
 PHYS_PAGE='46',
 XY='(-4875,-2475)',
 ROT='2',
 VER='2',
 PACK_TYPE='0402LF',
 LOCATION='R497',
 CDS_LIB='pure_quanta',
 CDS_PART_NAME='Q_RES_0402LF-10K,1%,1/16W,CHIPA',
 WATTAGE='1/16W',
 TOLERANCE='1%',
 MATERIAL='CHIP',
 VALUE='10K',
 PRIM_FILE='W:/<user>/logical/q_res/chips/chips.prt';

PART_NAME
 R498 'Q_RES_0402LF-22,1%,1/16W,CHIP,A':;

SECTION_NUMBER 1
 '@SCM_LIB.SCM(SCH_1):PAGE46_I137@PURE_QUANTA.Q_RES(CHIPS)':
 C_PATH='@scm_lib.scm(sch_1):page46_i137@pure_quanta.q_res(chips)',
 P_PATH='@scm_lib.scm(sch_1):page46_i137@pure_quanta.q_res(chips)',
 PATH='I137',
 DRAWING='@SCM_LIB.SCM(SCH_1):PAGE46',
 PHYS_PAGE='46',
 XY='(-9825,-2775)',
 ROT='0',
 VER='1',
 PACK_TYPE='0402LF',
 LOCATION='R498',
 CDS_LIB='pure_quanta',
 CDS_PART_NAME='Q_RES_0402LF-22,1%,1/16W,CHIP,A',
 WATTAGE='1/16W',
 TOLERANCE='1%',
 MATERIAL='CHIP',
 VALUE='22',
 PRIM_FILE='W:/<user>/logical/q_res/chips/chips.prt';

PART_NAME
 R499 'Q_RES_0402LF-22,1%,1/16W,CHIP,A':;

SECTION_NUMBER 1
 '@SCM_LIB.SCM(SCH_1):PAGE46_I136@PURE_QUANTA.Q_RES(CHIPS)':
 C_PATH='@scm_lib.scm(sch_1):page46_i136@pure_quanta.q_res(chips)',
 P_PATH='@scm_lib.scm(sch_1):page46_i136@pure_quanta.q_res(chips)',
 PATH='I136',
 DRAWING='@SCM_LIB.SCM(SCH_1):PAGE46',
 PHYS_PAGE='46',
 XY='(-9825,-2825)',
 ROT='0',
 VER='1',
 PACK_TYPE='0402LF',
 LOCATION='R499',
 CDS_LIB='pure_quanta',
 CDS_PART_NAME='Q_RES_0402LF-22,1%,1/16W,CHIP,A',
 WATTAGE='1/16W',
 TOLERANCE='1%',
 MATERIAL='CHIP',
 VALUE='22',
 PRIM_FILE='W:/<user>/logical/q_res/chips/chips.prt';

PART_NAME
 R500 'Q_RES_0402LF-0,5%,1/16W,CHIP,CA':;

SECTION_NUMBER 1
 '@SCM_LIB.SCM(SCH_1):PAGE46_I65@PURE_QUANTA.Q_RES(CHIPS)':
 C_PATH='@scm_lib.scm(sch_1):page46_i65@pure_quanta.q_res(chips)',
 P_PATH='@scm_lib.scm(sch_1):page46_i65@pure_quanta.q_res(chips)',
 PATH='I65',
 DRAWING='@SCM_LIB.SCM(SCH_1):PAGE46',
 SEC_TYPE='0402LF',
 PHYS_PAGE='46',
 XY='(-9825,-2875)',
 ROT='2',
 VER='1',
 PACK_TYPE='0402LF',
 LOCATION='R500',
 SEC='1',
 CDS_LIB='pure_quanta',
 CDS_PART_NAME='Q_RES_0402LF-0,5%,1/16W,CHIP,CA',
 WATTAGE='1/16W',
 TOLERANCE='5%',
 MATERIAL='CHIP',
 VALUE='0',
 PRIM_FILE='W:/<user>/logical/q_res/chips/chips.prt';

PART_NAME
 R501 'Q_RES_0402LF-33.2,1%,1/16W,CHIA':;

SECTION_NUMBER 1
 '@SCM_LIB.SCM(SCH_1):PAGE46_I58@PURE_QUANTA.Q_RES(CHIPS)':
 C_PATH='@scm_lib.scm(sch_1):page46_i58@pure_quanta.q_res(chips)',
 P_PATH='@scm_lib.scm(sch_1):page46_i58@pure_quanta.q_res(chips)',
 PATH='I58',
 DRAWING='@SCM_LIB.SCM(SCH_1):PAGE46',
 SEC_TYPE='0402LF',
 PHYS_PAGE='46',
 XY='(-9825,-2675)',
 ROT='2',
 VER='1',
 PACK_TYPE='0402LF',
 LOCATION='R501',
 SEC='1',
 CDS_LIB='pure_quanta',
 CDS_PART_NAME='Q_RES_0402LF-33.2,1%,1/16W,CHIA',
 WATTAGE='1/16W',
 TOLERANCE='1%',
 MATERIAL='CHIP',
 VALUE='33.2',
 PRIM_FILE='W:/<user>/logical/q_res/chips/chips.prt';

PART_NAME
 R503 'Q_RES_0402LF-0,5%,1/16W,CHIP,CA':;

SECTION_NUMBER 1
 '@SCM_LIB.SCM(SCH_1):PAGE46_I60@PURE_QUANTA.Q_RES(CHIPS)':
 C_PATH='@scm_lib.scm(sch_1):page46_i60@pure_quanta.q_res(chips)',
 P_PATH='@scm_lib.scm(sch_1):page46_i60@pure_quanta.q_res(chips)',
 PATH='I60',
 DRAWING='@SCM_LIB.SCM(SCH_1):PAGE46',
 SEC_TYPE='0402LF',
 PHYS_PAGE='46',
 XY='(-9825,-2725)',
 ROT='2',
 VER='1',
 PACK_TYPE='0402LF',
 LOCATION='R503',
 SEC='1',
 CDS_LIB='pure_quanta',
 CDS_PART_NAME='Q_RES_0402LF-0,5%,1/16W,CHIP,CA',
 WATTAGE='1/16W',
 TOLERANCE='5%',
 MATERIAL='CHIP',
 VALUE='0',
 PRIM_FILE='W:/<user>/logical/q_res/chips/chips.prt';

PART_NAME
 R504 'Q_RES_0402LF-8.2K,5%,1/16W,CHIA':;

SECTION_NUMBER 1
 '@SCM_LIB.SCM(SCH_1):PAGE50_I82@PURE_QUANTA.Q_RES(CHIPS)':
 C_PATH='@scm_lib.scm(sch_1):page50_i82@pure_quanta.q_res(chips)',
 P_PATH='@scm_lib.scm(sch_1):page50_i82@pure_quanta.q_res(chips)',
 PATH='I82',
 DRAWING='@SCM_LIB.SCM(SCH_1):PAGE50',
 PHYS_PAGE='50',
 XY='(-1150,3625)',
 ROT='0',
 VER='2',
 PACK_TYPE='0402LF',
 LOCATION='R504',
 CDS_LIB='pure_quanta',
 CDS_PART_NAME='Q_RES_0402LF-8.2K,5%,1/16W,CHIA',
 WATTAGE='1/16W',
 TOLERANCE='5%',
 MATERIAL='CHIP',
 VALUE='8.2K',
 PRIM_FILE='W:/<user>/logical/q_res/chips/chips.prt';

PART_NAME
 R505 'Q_RES_0402LF-0,5%,1/16W,CHIP,CA':;

SECTION_NUMBER 1
 '@SCM_LIB.SCM(SCH_1):PAGE46_I74@PURE_QUANTA.Q_RES(CHIPS)':
 C_PATH='@scm_lib.scm(sch_1):page46_i74@pure_quanta.q_res(chips)',
 P_PATH='@scm_lib.scm(sch_1):page46_i74@pure_quanta.q_res(chips)',
 PATH='I74',
 DRAWING='@SCM_LIB.SCM(SCH_1):PAGE46',
 PHYS_PAGE='46',
 XY='(-6275,-2775)',
 ROT='2',
 VER='1',
 PACK_TYPE='0402LF',
 LOCATION='R505',
 CDS_LIB='pure_quanta',
 CDS_PART_NAME='Q_RES_0402LF-0,5%,1/16W,CHIP,CA',
 WATTAGE='1/16W',
 TOLERANCE='5%',
 MATERIAL='CHIP',
 VALUE='0',
 PRIM_FILE='W:/<user>/logical/q_res/chips/chips.prt';

PART_NAME
 R506 'Q_RES_0402LF-100,1%,1/16W,EMPTA':;

SECTION_NUMBER 1
 '@SCM_LIB.SCM(SCH_1):PAGE48_I53@PURE_QUANTA.Q_RES(CHIPS)':
 C_PATH='@scm_lib.scm(sch_1):page48_i53@pure_quanta.q_res(chips)',
 P_PATH='@scm_lib.scm(sch_1):page48_i53@pure_quanta.q_res(chips)',
 PATH='I53',
 DRAWING='@SCM_LIB.SCM(SCH_1):PAGE48',
 PHYS_PAGE='48',
 XY='(-2675,-50)',
 ROT='0',
 VER='2',
 PACK_TYPE='0402LF',
 LOCATION='R506',
 CDS_LIB='pure_quanta',
 CDS_PART_NAME='Q_RES_0402LF-100,1%,1/16W,EMPTA',
 WATTAGE='1/16W',
 TOLERANCE='1%',
 MATERIAL='EMPTY',
 VALUE='100',
 PRIM_FILE='W:/<user>/logical/q_res/chips/chips.prt';

PART_NAME
 R507 'Q_RES_0402LF-100,1%,1/16W,EMPTA':;

SECTION_NUMBER 1
 '@SCM_LIB.SCM(SCH_1):PAGE48_I52@PURE_QUANTA.Q_RES(CHIPS)':
 C_PATH='@scm_lib.scm(sch_1):page48_i52@pure_quanta.q_res(chips)',
 P_PATH='@scm_lib.scm(sch_1):page48_i52@pure_quanta.q_res(chips)',
 PATH='I52',
 DRAWING='@SCM_LIB.SCM(SCH_1):PAGE48',
 PHYS_PAGE='48',
 XY='(-2050,-75)',
 ROT='0',
 VER='2',
 PACK_TYPE='0402LF',
 LOCATION='R507',
 CDS_LIB='pure_quanta',
 CDS_PART_NAME='Q_RES_0402LF-100,1%,1/16W,EMPTA',
 WATTAGE='1/16W',
 TOLERANCE='1%',
 MATERIAL='EMPTY',
 VALUE='100',
 PRIM_FILE='W:/<user>/logical/q_res/chips/chips.prt';

PART_NAME
 R508 'Q_RES_0402LF-10K,1%,1/16W,CHIPA':;

SECTION_NUMBER 1
 '@SCM_LIB.SCM(SCH_1):PAGE48_I51@PURE_QUANTA.Q_RES(CHIPS)':
 C_PATH='@scm_lib.scm(sch_1):page48_i51@pure_quanta.q_res(chips)',
 P_PATH='@scm_lib.scm(sch_1):page48_i51@pure_quanta.q_res(chips)',
 PATH='I51',
 DRAWING='@SCM_LIB.SCM(SCH_1):PAGE48',
 PHYS_PAGE='48',
 XY='(-1075,675)',
 ROT='0',
 VER='2',
 PACK_TYPE='0402LF',
 LOCATION='R508',
 CDS_LIB='pure_quanta',
 CDS_PART_NAME='Q_RES_0402LF-10K,1%,1/16W,CHIPA',
 WATTAGE='1/16W',
 TOLERANCE='1%',
 MATERIAL='CHIP',
 VALUE='10K',
 PRIM_FILE='W:/<user>/logical/q_res/chips/chips.prt';

PART_NAME
 R509 'Q_RES_0402LF-33.2,1%,1/16W,CHIA':;

SECTION_NUMBER 1
 '@SCM_LIB.SCM(SCH_1):PAGE48_I50@PURE_QUANTA.Q_RES(CHIPS)':
 C_PATH='@scm_lib.scm(sch_1):page48_i50@pure_quanta.q_res(chips)',
 P_PATH='@scm_lib.scm(sch_1):page48_i50@pure_quanta.q_res(chips)',
 PATH='I50',
 DRAWING='@SCM_LIB.SCM(SCH_1):PAGE48',
 PHYS_PAGE='48',
 XY='(-950,250)',
 ROT='0',
 VER='1',
 PACK_TYPE='0402LF',
 LOCATION='R509',
 CDS_LIB='pure_quanta',
 CDS_PART_NAME='Q_RES_0402LF-33.2,1%,1/16W,CHIA',
 WATTAGE='1/16W',
 TOLERANCE='1%',
 MATERIAL='CHIP',
 VALUE='33.2',
 PRIM_FILE='W:/<user>/logical/q_res/chips/chips.prt';

PART_NAME
 R510 'Q_RES_0402LF-33.2,1%,1/16W,CHIA':;

SECTION_NUMBER 1
 '@SCM_LIB.SCM(SCH_1):PAGE32_I126@PURE_QUANTA.Q_RES(CHIPS)':
 C_PATH='@scm_lib.scm(sch_1):page32_i126@pure_quanta.q_res(chips)',
 P_PATH='@scm_lib.scm(sch_1):page32_i126@pure_quanta.q_res(chips)',
 PATH='I126',
 DRAWING='@SCM_LIB.SCM(SCH_1):PAGE32',
 PHYS_PAGE='32',
 XY='(-1525,3775)',
 ROT='0',
 VER='1',
 PACK_TYPE='0402LF',
 LOCATION='R510',
 CDS_LIB='pure_quanta',
 CDS_PART_NAME='Q_RES_0402LF-33.2,1%,1/16W,CHIA',
 WATTAGE='1/16W',
 TOLERANCE='1%',
 MATERIAL='CHIP',
 VALUE='33.2',
 PRIM_FILE='W:/<user>/logical/q_res/chips/chips.prt';

PART_NAME
 R511 'Q_RES_0402LF-33.2,1%,1/16W,CHIA':;

SECTION_NUMBER 1
 '@SCM_LIB.SCM(SCH_1):PAGE32_I127@PURE_QUANTA.Q_RES(CHIPS)':
 C_PATH='@scm_lib.scm(sch_1):page32_i127@pure_quanta.q_res(chips)',
 P_PATH='@scm_lib.scm(sch_1):page32_i127@pure_quanta.q_res(chips)',
 PATH='I127',
 DRAWING='@SCM_LIB.SCM(SCH_1):PAGE32',
 PHYS_PAGE='32',
 XY='(-1525,3725)',
 ROT='0',
 VER='1',
 PACK_TYPE='0402LF',
 LOCATION='R511',
 CDS_LIB='pure_quanta',
 CDS_PART_NAME='Q_RES_0402LF-33.2,1%,1/16W,CHIA',
 WATTAGE='1/16W',
 TOLERANCE='1%',
 MATERIAL='CHIP',
 VALUE='33.2',
 PRIM_FILE='W:/<user>/logical/q_res/chips/chips.prt';

PART_NAME
 R512 'Q_RES_0402LF-33.2,1%,1/16W,CHIA':;

SECTION_NUMBER 1
 '@SCM_LIB.SCM(SCH_1):PAGE32_I129@PURE_QUANTA.Q_RES(CHIPS)':
 C_PATH='@scm_lib.scm(sch_1):page32_i129@pure_quanta.q_res(chips)',
 P_PATH='@scm_lib.scm(sch_1):page32_i129@pure_quanta.q_res(chips)',
 PATH='I129',
 DRAWING='@SCM_LIB.SCM(SCH_1):PAGE32',
 PHYS_PAGE='32',
 XY='(-1525,3675)',
 ROT='0',
 VER='1',
 PACK_TYPE='0402LF',
 LOCATION='R512',
 CDS_LIB='pure_quanta',
 CDS_PART_NAME='Q_RES_0402LF-33.2,1%,1/16W,CHIA',
 WATTAGE='1/16W',
 TOLERANCE='1%',
 MATERIAL='CHIP',
 VALUE='33.2',
 PRIM_FILE='W:/<user>/logical/q_res/chips/chips.prt';

PART_NAME
 R513 'Q_RES_0402LF-33.2,1%,1/16W,CHIA':;

SECTION_NUMBER 1
 '@SCM_LIB.SCM(SCH_1):PAGE32_I128@PURE_QUANTA.Q_RES(CHIPS)':
 C_PATH='@scm_lib.scm(sch_1):page32_i128@pure_quanta.q_res(chips)',
 P_PATH='@scm_lib.scm(sch_1):page32_i128@pure_quanta.q_res(chips)',
 PATH='I128',
 DRAWING='@SCM_LIB.SCM(SCH_1):PAGE32',
 PHYS_PAGE='32',
 XY='(-1525,3625)',
 ROT='0',
 VER='1',
 PACK_TYPE='0402LF',
 LOCATION='R513',
 CDS_LIB='pure_quanta',
 CDS_PART_NAME='Q_RES_0402LF-33.2,1%,1/16W,CHIA',
 WATTAGE='1/16W',
 TOLERANCE='1%',
 MATERIAL='CHIP',
 VALUE='33.2',
 PRIM_FILE='W:/<user>/logical/q_res/chips/chips.prt';

PART_NAME
 R514 'Q_RES_0402LF-33.2,1%,1/16W,CHIA':;

SECTION_NUMBER 1
 '@SCM_LIB.SCM(SCH_1):PAGE32_I94@PURE_QUANTA.Q_RES(CHIPS)':
 C_PATH='@scm_lib.scm(sch_1):page32_i94@pure_quanta.q_res(chips)',
 P_PATH='@scm_lib.scm(sch_1):page32_i94@pure_quanta.q_res(chips)',
 PATH='I94',
 DRAWING='@SCM_LIB.SCM(SCH_1):PAGE32',
 PHYS_PAGE='32',
 XY='(-700,3375)',
 ROT='0',
 VER='1',
 PACK_TYPE='0402LF',
 LOCATION='R514',
 CDS_LIB='pure_quanta',
 CDS_PART_NAME='Q_RES_0402LF-33.2,1%,1/16W,CHIA',
 WATTAGE='1/16W',
 TOLERANCE='1%',
 MATERIAL='CHIP',
 VALUE='33.2',
 PRIM_FILE='W:/<user>/logical/q_res/chips/chips.prt';

PART_NAME
 R515 'Q_RES_0402LF-33.2,1%,1/16W,CHIA':;

SECTION_NUMBER 1
 '@SCM_LIB.SCM(SCH_1):PAGE32_I96@PURE_QUANTA.Q_RES(CHIPS)':
 C_PATH='@scm_lib.scm(sch_1):page32_i96@pure_quanta.q_res(chips)',
 P_PATH='@scm_lib.scm(sch_1):page32_i96@pure_quanta.q_res(chips)',
 PATH='I96',
 DRAWING='@SCM_LIB.SCM(SCH_1):PAGE32',
 PHYS_PAGE='32',
 XY='(-700,3325)',
 ROT='0',
 VER='1',
 PACK_TYPE='0402LF',
 LOCATION='R515',
 CDS_LIB='pure_quanta',
 CDS_PART_NAME='Q_RES_0402LF-33.2,1%,1/16W,CHIA',
 WATTAGE='1/16W',
 TOLERANCE='1%',
 MATERIAL='CHIP',
 VALUE='33.2',
 PRIM_FILE='W:/<user>/logical/q_res/chips/chips.prt';

PART_NAME
 R516 'Q_RES_0402LF-33.2,1%,1/16W,CHIA':;

SECTION_NUMBER 1
 '@SCM_LIB.SCM(SCH_1):PAGE32_I95@PURE_QUANTA.Q_RES(CHIPS)':
 C_PATH='@scm_lib.scm(sch_1):page32_i95@pure_quanta.q_res(chips)',
 P_PATH='@scm_lib.scm(sch_1):page32_i95@pure_quanta.q_res(chips)',
 PATH='I95',
 DRAWING='@SCM_LIB.SCM(SCH_1):PAGE32',
 PHYS_PAGE='32',
 XY='(-700,3275)',
 ROT='0',
 VER='1',
 PACK_TYPE='0402LF',
 LOCATION='R516',
 CDS_LIB='pure_quanta',
 CDS_PART_NAME='Q_RES_0402LF-33.2,1%,1/16W,CHIA',
 WATTAGE='1/16W',
 TOLERANCE='1%',
 MATERIAL='CHIP',
 VALUE='33.2',
 PRIM_FILE='W:/<user>/logical/q_res/chips/chips.prt';

PART_NAME
 R517 'Q_RES_0402LF-33.2,1%,1/16W,CHIA':;

SECTION_NUMBER 1
 '@SCM_LIB.SCM(SCH_1):PAGE32_I97@PURE_QUANTA.Q_RES(CHIPS)':
 C_PATH='@scm_lib.scm(sch_1):page32_i97@pure_quanta.q_res(chips)',
 P_PATH='@scm_lib.scm(sch_1):page32_i97@pure_quanta.q_res(chips)',
 PATH='I97',
 DRAWING='@SCM_LIB.SCM(SCH_1):PAGE32',
 PHYS_PAGE='32',
 XY='(-700,3225)',
 ROT='0',
 VER='1',
 PACK_TYPE='0402LF',
 LOCATION='R517',
 CDS_LIB='pure_quanta',
 CDS_PART_NAME='Q_RES_0402LF-33.2,1%,1/16W,CHIA',
 WATTAGE='1/16W',
 TOLERANCE='1%',
 MATERIAL='CHIP',
 VALUE='33.2',
 PRIM_FILE='W:/<user>/logical/q_res/chips/chips.prt';

PART_NAME
 R518 'Q_RES_0402LF-33.2,1%,1/16W,CHIA':;

SECTION_NUMBER 1
 '@SCM_LIB.SCM(SCH_1):PAGE32_I23@PURE_QUANTA.Q_RES(CHIPS)':
 C_PATH='@scm_lib.scm(sch_1):page32_i23@pure_quanta.q_res(chips)',
 P_PATH='@scm_lib.scm(sch_1):page32_i23@pure_quanta.q_res(chips)',
 PATH='I23',
 DRAWING='@SCM_LIB.SCM(SCH_1):PAGE32',
 PHYS_PAGE='32',
 XY='(4250,3375)',
 ROT='0',
 VER='1',
 PACK_TYPE='0402LF',
 LOCATION='R518',
 CDS_LIB='pure_quanta',
 CDS_PART_NAME='Q_RES_0402LF-33.2,1%,1/16W,CHIA',
 WATTAGE='1/16W',
 TOLERANCE='1%',
 MATERIAL='CHIP',
 VALUE='33.2',
 PRIM_FILE='W:/<user>/logical/q_res/chips/chips.prt';

PART_NAME
 R519 'Q_RES_0402LF-0,5%,1/16W,CHIP,CA':;

SECTION_NUMBER 1
 '@SCM_LIB.SCM(SCH_1):PAGE34_I147@PURE_QUANTA.Q_RES(CHIPS)':
 C_PATH='@scm_lib.scm(sch_1):page34_i147@pure_quanta.q_res(chips)',
 P_PATH='@scm_lib.scm(sch_1):page34_i147@pure_quanta.q_res(chips)',
 PATH='I147',
 DRAWING='@SCM_LIB.SCM(SCH_1):PAGE34',
 PHYS_PAGE='34',
 XY='(-7125,4000)',
 ROT='0',
 VER='1',
 PACK_TYPE='0402LF',
 LOCATION='R519',
 CDS_LIB='pure_quanta',
 CDS_PART_NAME='Q_RES_0402LF-0,5%,1/16W,CHIP,CA',
 WATTAGE='1/16W',
 TOLERANCE='5%',
 MATERIAL='CHIP',
 VALUE='0',
 PRIM_FILE='W:/<user>/logical/q_res/chips/chips.prt';

PART_NAME
 R521 'Q_RES_0402LF-10K,1%,1/16W,CHIPA':;

SECTION_NUMBER 1
 '@SCM_LIB.SCM(SCH_1):PAGE27_I234@PURE_QUANTA.Q_RES(CHIPS)':
 C_PATH='@scm_lib.scm(sch_1):page27_i234@pure_quanta.q_res(chips)',
 P_PATH='@scm_lib.scm(sch_1):page27_i234@pure_quanta.q_res(chips)',
 PATH='I234',
 DRAWING='@SCM_LIB.SCM(SCH_1):PAGE27',
 PHYS_PAGE='27',
 XY='(-3625,2275)',
 ROT='0',
 VER='1',
 PACK_TYPE='0402LF',
 LOCATION='R521',
 CDS_LIB='pure_quanta',
 CDS_PART_NAME='Q_RES_0402LF-10K,1%,1/16W,CHIPA',
 WATTAGE='1/16W',
 TOLERANCE='1%',
 MATERIAL='CHIP',
 VALUE='10K',
 PRIM_FILE='W:/<user>/logical/q_res/chips/chips.prt';

PART_NAME
 R523 'Q_RES_0402LF-10K,1%,1/16W,CHIPA':;

SECTION_NUMBER 1
 '@SCM_LIB.SCM(SCH_1):PAGE32_I119@PURE_QUANTA.Q_RES(CHIPS)':
 C_PATH='@scm_lib.scm(sch_1):page32_i119@pure_quanta.q_res(chips)',
 P_PATH='@scm_lib.scm(sch_1):page32_i119@pure_quanta.q_res(chips)',
 PATH='I119',
 DRAWING='@SCM_LIB.SCM(SCH_1):PAGE32',
 PHYS_PAGE='32',
 XY='(-2425,275)',
 ROT='0',
 VER='1',
 PACK_TYPE='0402LF',
 LOCATION='R523',
 CDS_LIB='pure_quanta',
 CDS_PART_NAME='Q_RES_0402LF-10K,1%,1/16W,CHIPA',
 WATTAGE='1/16W',
 TOLERANCE='1%',
 MATERIAL='CHIP',
 VALUE='10K',
 PRIM_FILE='W:/<user>/logical/q_res/chips/chips.prt';

PART_NAME
 R525 'Q_RES_0402LF-0,5%,1/16W,CHIP,CA':;

SECTION_NUMBER 1
 '@SCM_LIB.SCM(SCH_1):PAGE41_I72@PURE_QUANTA.Q_RES(CHIPS)':
 C_PATH='@scm_lib.scm(sch_1):page41_i72@pure_quanta.q_res(chips)',
 P_PATH='@scm_lib.scm(sch_1):page41_i72@pure_quanta.q_res(chips)',
 PATH='I72',
 DRAWING='@SCM_LIB.SCM(SCH_1):PAGE41',
 PHYS_PAGE='41',
 XY='(-5125,4925)',
 ROT='0',
 VER='1',
 PACK_TYPE='0402LF',
 CDS_LIB='pure_quanta',
 CDS_PART_NAME='Q_RES_0402LF-0,5%,1/16W,CHIP,CA',
 WATTAGE='1/16W',
 TOLERANCE='5%',
 MATERIAL='CHIP',
 VALUE='0',
 PRIM_FILE='W:/<user>/logical/q_res/chips/chips.prt';

PART_NAME
 R526 'Q_RES_0402LF-33.2,1%,1/16W,EMPA':;

SECTION_NUMBER 1
 '@SCM_LIB.SCM(SCH_1):PAGE35_I147@PURE_QUANTA.Q_RES(CHIPS)':
 C_PATH='@scm_lib.scm(sch_1):page35_i147@pure_quanta.q_res(chips)',
 P_PATH='@scm_lib.scm(sch_1):page35_i147@pure_quanta.q_res(chips)',
 PATH='I147',
 DRAWING='@SCM_LIB.SCM(SCH_1):PAGE35',
 PHYS_PAGE='35',
 XY='(-2250,4750)',
 ROT='0',
 VER='1',
 PACK_TYPE='0402LF',
 LOCATION='R526',
 CDS_LIB='pure_quanta',
 CDS_PART_NAME='Q_RES_0402LF-33.2,1%,1/16W,EMPA',
 WATTAGE='1/16W',
 TOLERANCE='1%',
 MATERIAL='EMPTY',
 VALUE='33.2',
 PRIM_FILE='W:/<user>/logical/q_res/chips/chips.prt';

PART_NAME
 R527 'Q_RES_0402LF-0,5%,1/16W,CHIP,CA':;

SECTION_NUMBER 1
 '@SCM_LIB.SCM(SCH_1):PAGE15_I169@PURE_QUANTA.Q_RES(CHIPS)':
 C_PATH='@scm_lib.scm(sch_1):page15_i169@pure_quanta.q_res(chips)',
 P_PATH='@scm_lib.scm(sch_1):page15_i169@pure_quanta.q_res(chips)',
 PATH='I169',
 DRAWING='@SCM_LIB.SCM(SCH_1):PAGE15',
 PHYS_PAGE='15',
 XY='(3300,2675)',
 ROT='0',
 VER='1',
 PACK_TYPE='0402LF',
 LOCATION='R527',
 CDS_LIB='pure_quanta',
 CDS_PART_NAME='Q_RES_0402LF-0,5%,1/16W,CHIP,CA',
 WATTAGE='1/16W',
 TOLERANCE='5%',
 MATERIAL='CHIP',
 VALUE='0',
 PRIM_FILE='W:/<user>/logical/q_res/chips/chips.prt';

PART_NAME
 R528 'Q_RES_0402LF-0,5%,1/16W,CHIP,CA':;

SECTION_NUMBER 1
 '@SCM_LIB.SCM(SCH_1):PAGE15_I168@PURE_QUANTA.Q_RES(CHIPS)':
 C_PATH='@scm_lib.scm(sch_1):page15_i168@pure_quanta.q_res(chips)',
 P_PATH='@scm_lib.scm(sch_1):page15_i168@pure_quanta.q_res(chips)',
 PATH='I168',
 DRAWING='@SCM_LIB.SCM(SCH_1):PAGE15',
 PHYS_PAGE='15',
 XY='(3300,2625)',
 ROT='0',
 VER='1',
 PACK_TYPE='0402LF',
 LOCATION='R528',
 CDS_LIB='pure_quanta',
 CDS_PART_NAME='Q_RES_0402LF-0,5%,1/16W,CHIP,CA',
 WATTAGE='1/16W',
 TOLERANCE='5%',
 MATERIAL='CHIP',
 VALUE='0',
 PRIM_FILE='W:/<user>/logical/q_res/chips/chips.prt';

PART_NAME
 R529 'Q_RES_0402LF-100,1%,1/16W,CHIPA':;

SECTION_NUMBER 1
 '@SCM_LIB.SCM(SCH_1):PAGE52_I127@PURE_QUANTA.Q_RES(CHIPS)':
 C_PATH='@scm_lib.scm(sch_1):page52_i127@pure_quanta.q_res(chips)',
 P_PATH='@scm_lib.scm(sch_1):page52_i127@pure_quanta.q_res(chips)',
 PATH='I127',
 DRAWING='@SCM_LIB.SCM(SCH_1):PAGE52',
 PHYS_PAGE='52',
 XY='(2475,-1450)',
 ROT='0',
 VER='1',
 PACK_TYPE='0402LF',
 CDS_LIB='pure_quanta',
 CDS_PART_NAME='Q_RES_0402LF-100,1%,1/16W,CHIPA',
 WATTAGE='1/16W',
 TOLERANCE='1%',
 MATERIAL='CHIP',
 VALUE='100',
 PRIM_FILE='W:/<user>/logical/q_res/chips/chips.prt';

PART_NAME
 R530 'Q_RES_0402LF-100,1%,1/16W,CHIPA':;

SECTION_NUMBER 1
 '@SCM_LIB.SCM(SCH_1):PAGE54_I132@PURE_QUANTA.Q_RES(CHIPS)':
 C_PATH='@scm_lib.scm(sch_1):page54_i132@pure_quanta.q_res(chips)',
 P_PATH='@scm_lib.scm(sch_1):page54_i132@pure_quanta.q_res(chips)',
 PATH='I132',
 DRAWING='@SCM_LIB.SCM(SCH_1):PAGE54',
 PHYS_PAGE='54',
 XY='(-625,-625)',
 ROT='0',
 VER='1',
 PACK_TYPE='0402LF',
 CDS_LIB='pure_quanta',
 CDS_PART_NAME='Q_RES_0402LF-100,1%,1/16W,CHIPA',
 WATTAGE='1/16W',
 TOLERANCE='1%',
 MATERIAL='CHIP',
 VALUE='100',
 PRIM_FILE='W:/<user>/logical/q_res/chips/chips.prt';

PART_NAME
 R531 'Q_RES_0402LF-33.2,1%,1/16W,EMPA':;

SECTION_NUMBER 1
 '@SCM_LIB.SCM(SCH_1):PAGE35_I146@PURE_QUANTA.Q_RES(CHIPS)':
 C_PATH='@scm_lib.scm(sch_1):page35_i146@pure_quanta.q_res(chips)',
 P_PATH='@scm_lib.scm(sch_1):page35_i146@pure_quanta.q_res(chips)',
 PATH='I146',
 DRAWING='@SCM_LIB.SCM(SCH_1):PAGE35',
 PHYS_PAGE='35',
 XY='(-2250,4650)',
 ROT='0',
 VER='1',
 PACK_TYPE='0402LF',
 LOCATION='R531',
 CDS_LIB='pure_quanta',
 CDS_PART_NAME='Q_RES_0402LF-33.2,1%,1/16W,EMPA',
 WATTAGE='1/16W',
 TOLERANCE='1%',
 MATERIAL='EMPTY',
 VALUE='33.2',
 PRIM_FILE='W:/<user>/logical/q_res/chips/chips.prt';

PART_NAME
 R532 'Q_RES_0402LF-33.2,1%,1/16W,EMPA':;

SECTION_NUMBER 1
 '@SCM_LIB.SCM(SCH_1):PAGE21_I46@PURE_QUANTA.Q_RES(CHIPS)':
 C_PATH='@scm_lib.scm(sch_1):page21_i46@pure_quanta.q_res(chips)',
 P_PATH='@scm_lib.scm(sch_1):page21_i46@pure_quanta.q_res(chips)',
 PATH='I46',
 DRAWING='@SCM_LIB.SCM(SCH_1):PAGE21',
 PHYS_PAGE='21',
 XY='(3250,2100)',
 ROT='0',
 VER='1',
 PACK_TYPE='0402LF',
 LOCATION='R532',
 CDS_LIB='pure_quanta',
 CDS_PART_NAME='Q_RES_0402LF-33.2,1%,1/16W,EMPA',
 WATTAGE='1/16W',
 TOLERANCE='1%',
 MATERIAL='EMPTY',
 VALUE='33.2',
 PRIM_FILE='W:/<user>/logical/q_res/chips/chips.prt';

PART_NAME
 R536 'Q_RES_0402LF-33.2,1%,1/16W,CHIA':;

SECTION_NUMBER 1
 '@SCM_LIB.SCM(SCH_1):PAGE35_I144@PURE_QUANTA.Q_RES(CHIPS)':
 C_PATH='@scm_lib.scm(sch_1):page35_i144@pure_quanta.q_res(chips)',
 P_PATH='@scm_lib.scm(sch_1):page35_i144@pure_quanta.q_res(chips)',
 PATH='I144',
 DRAWING='@SCM_LIB.SCM(SCH_1):PAGE35',
 PHYS_PAGE='35',
 XY='(-2250,4350)',
 ROT='0',
 VER='1',
 PACK_TYPE='0402LF',
 LOCATION='R536',
 CDS_LIB='pure_quanta',
 CDS_PART_NAME='Q_RES_0402LF-33.2,1%,1/16W,CHIA',
 WATTAGE='1/16W',
 TOLERANCE='1%',
 MATERIAL='CHIP',
 VALUE='33.2',
 PRIM_FILE='W:/<user>/logical/q_res/chips/chips.prt';

PART_NAME
 R537 'Q_RES_0402LF-33.2,1%,1/16W,CHIA':;

SECTION_NUMBER 1
 '@SCM_LIB.SCM(SCH_1):PAGE35_I145@PURE_QUANTA.Q_RES(CHIPS)':
 C_PATH='@scm_lib.scm(sch_1):page35_i145@pure_quanta.q_res(chips)',
 P_PATH='@scm_lib.scm(sch_1):page35_i145@pure_quanta.q_res(chips)',
 PATH='I145',
 DRAWING='@SCM_LIB.SCM(SCH_1):PAGE35',
 PHYS_PAGE='35',
 XY='(-2250,4300)',
 ROT='0',
 VER='1',
 PACK_TYPE='0402LF',
 LOCATION='R537',
 CDS_LIB='pure_quanta',
 CDS_PART_NAME='Q_RES_0402LF-33.2,1%,1/16W,CHIA',
 WATTAGE='1/16W',
 TOLERANCE='1%',
 MATERIAL='CHIP',
 VALUE='33.2',
 PRIM_FILE='W:/<user>/logical/q_res/chips/chips.prt';

PART_NAME
 R538 'Q_RES_0402LF-100K,1%,1/16W,CHIA':;

SECTION_NUMBER 1
 '@SCM_LIB.SCM(SCH_1):PAGE31_I25@PURE_QUANTA.Q_RES(CHIPS)':
 C_PATH='@scm_lib.scm(sch_1):page31_i25@pure_quanta.q_res(chips)',
 P_PATH='@scm_lib.scm(sch_1):page31_i25@pure_quanta.q_res(chips)',
 PATH='I25',
 DRAWING='@SCM_LIB.SCM(SCH_1):PAGE31',
 PHYS_PAGE='31',
 XY='(-5900,6050)',
 ROT='0',
 VER='2',
 PACK_TYPE='0402LF',
 CDS_LIB='pure_quanta',
 CDS_PART_NAME='Q_RES_0402LF-100K,1%,1/16W,CHIA',
 WATTAGE='1/16W',
 TOLERANCE='1%',
 MATERIAL='CHIP',
 VALUE='100K',
 PRIM_FILE='W:/<user>/logical/q_res/chips/chips.prt';

PART_NAME
 R543 'Q_RES_0402LF-4.7K,1%,1/16W,EMPB':;

SECTION_NUMBER 1
 '@SCM_LIB.SCM(SCH_1):PAGE21_I147@PURE_QUANTA.Q_RES(CHIPS)':
 C_PATH='@scm_lib.scm(sch_1):page21_i147@pure_quanta.q_res(chips)',
 P_PATH='@scm_lib.scm(sch_1):page21_i147@pure_quanta.q_res(chips)',
 PATH='I147',
 DRAWING='@SCM_LIB.SCM(SCH_1):PAGE21',
 PHYS_PAGE='21',
 XY='(225,3725)',
 ROT='0',
 VER='2',
 PACK_TYPE='0402LF',
 CDS_LIB='pure_quanta',
 CDS_PART_NAME='Q_RES_0402LF-4.7K,1%,1/16W,EMPB',
 WATTAGE='1/16W',
 TOLERANCE='1%',
 MATERIAL='EMPTY',
 VALUE='4.7K',
 PRIM_FILE='W:/<user>/logical/q_res/chips/chips.prt';

PART_NAME
 R544 'Q_RES_0402LF-0,5%,1/16W,CHIP,CA':;

SECTION_NUMBER 1
 '@SCM_LIB.SCM(SCH_1):PAGE31_I74@PURE_QUANTA.Q_RES(CHIPS)':
 C_PATH='@scm_lib.scm(sch_1):page31_i74@pure_quanta.q_res(chips)',
 P_PATH='@scm_lib.scm(sch_1):page31_i74@pure_quanta.q_res(chips)',
 PATH='I74',
 DRAWING='@SCM_LIB.SCM(SCH_1):PAGE31',
 PHYS_PAGE='31',
 XY='(-6175,2825)',
 ROT='0',
 VER='1',
 PACK_TYPE='0402LF',
 LOCATION='R544',
 CDS_LIB='pure_quanta',
 CDS_PART_NAME='Q_RES_0402LF-0,5%,1/16W,CHIP,CA',
 WATTAGE='1/16W',
 TOLERANCE='5%',
 MATERIAL='CHIP',
 VALUE='0',
 PRIM_FILE='W:/<user>/logical/q_res/chips/chips.prt';

PART_NAME
 R545 'Q_RES_0402LF-0,5%,1/16W,CHIP,CA':;

SECTION_NUMBER 1
 '@SCM_LIB.SCM(SCH_1):PAGE25_I143@PURE_QUANTA.Q_RES(CHIPS)':
 C_PATH='@scm_lib.scm(sch_1):page25_i143@pure_quanta.q_res(chips)',
 P_PATH='@scm_lib.scm(sch_1):page25_i143@pure_quanta.q_res(chips)',
 PATH='I143',
 DRAWING='@SCM_LIB.SCM(SCH_1):PAGE25',
 PHYS_PAGE='25',
 XY='(2000,3500)',
 ROT='0',
 VER='1',
 PACK_TYPE='0402LF',
 CDS_LIB='pure_quanta',
 CDS_PART_NAME='Q_RES_0402LF-0,5%,1/16W,CHIP,CA',
 WATTAGE='1/16W',
 TOLERANCE='5%',
 MATERIAL='CHIP',
 VALUE='0',
 PRIM_FILE='W:/<user>/logical/q_res/chips/chips.prt';

PART_NAME
 R546 'Q_RES_0402LF-0,5%,1/16W,CHIP,CA':;

SECTION_NUMBER 1
 '@SCM_LIB.SCM(SCH_1):PAGE31_I75@PURE_QUANTA.Q_RES(CHIPS)':
 C_PATH='@scm_lib.scm(sch_1):page31_i75@pure_quanta.q_res(chips)',
 P_PATH='@scm_lib.scm(sch_1):page31_i75@pure_quanta.q_res(chips)',
 PATH='I75',
 DRAWING='@SCM_LIB.SCM(SCH_1):PAGE31',
 PHYS_PAGE='31',
 XY='(-6175,2925)',
 ROT='0',
 VER='1',
 PACK_TYPE='0402LF',
 LOCATION='R546',
 CDS_LIB='pure_quanta',
 CDS_PART_NAME='Q_RES_0402LF-0,5%,1/16W,CHIP,CA',
 WATTAGE='1/16W',
 TOLERANCE='5%',
 MATERIAL='CHIP',
 VALUE='0',
 PRIM_FILE='W:/<user>/logical/q_res/chips/chips.prt';

PART_NAME
 R547 'Q_RES_0402LF-33.2,1%,1/16W,CHIA':;

SECTION_NUMBER 1
 '@SCM_LIB.SCM(SCH_1):PAGE21_I176@PURE_QUANTA.Q_RES(CHIPS)':
 C_PATH='@scm_lib.scm(sch_1):page21_i176@pure_quanta.q_res(chips)',
 P_PATH='@scm_lib.scm(sch_1):page21_i176@pure_quanta.q_res(chips)',
 PATH='I176',
 DRAWING='@SCM_LIB.SCM(SCH_1):PAGE21',
 PHYS_PAGE='21',
 XY='(3500,2750)',
 ROT='0',
 VER='1',
 PACK_TYPE='0402LF',
 LOCATION='R547',
 CDS_LIB='pure_quanta',
 CDS_PART_NAME='Q_RES_0402LF-33.2,1%,1/16W,CHIA',
 WATTAGE='1/16W',
 TOLERANCE='1%',
 MATERIAL='CHIP',
 VALUE='33.2',
 PRIM_FILE='W:/<user>/logical/q_res/chips/chips.prt';

PART_NAME
 R548 'Q_RES_0402LF-33.2,1%,1/16W,CHIA':;

SECTION_NUMBER 1
 '@SCM_LIB.SCM(SCH_1):PAGE25_I172@PURE_QUANTA.Q_RES(CHIPS)':
 C_PATH='@scm_lib.scm(sch_1):page25_i172@pure_quanta.q_res(chips)',
 P_PATH='@scm_lib.scm(sch_1):page25_i172@pure_quanta.q_res(chips)',
 PATH='I172',
 DRAWING='@SCM_LIB.SCM(SCH_1):PAGE25',
 PHYS_PAGE='25',
 XY='(2275,3300)',
 ROT='0',
 VER='1',
 PACK_TYPE='0402LF',
 LOCATION='R548',
 CDS_LIB='pure_quanta',
 CDS_PART_NAME='Q_RES_0402LF-33.2,1%,1/16W,CHIA',
 WATTAGE='1/16W',
 TOLERANCE='1%',
 MATERIAL='CHIP',
 VALUE='33.2',
 PRIM_FILE='W:/<user>/logical/q_res/chips/chips.prt';

PART_NAME
 R549 'Q_RES_0402LF-33.2,1%,1/16W,CHIA':;

SECTION_NUMBER 1
 '@SCM_LIB.SCM(SCH_1):PAGE21_I177@PURE_QUANTA.Q_RES(CHIPS)':
 C_PATH='@scm_lib.scm(sch_1):page21_i177@pure_quanta.q_res(chips)',
 P_PATH='@scm_lib.scm(sch_1):page21_i177@pure_quanta.q_res(chips)',
 PATH='I177',
 DRAWING='@SCM_LIB.SCM(SCH_1):PAGE21',
 PHYS_PAGE='21',
 XY='(3500,2850)',
 ROT='0',
 VER='1',
 PACK_TYPE='0402LF',
 LOCATION='R549',
 CDS_LIB='pure_quanta',
 CDS_PART_NAME='Q_RES_0402LF-33.2,1%,1/16W,CHIA',
 WATTAGE='1/16W',
 TOLERANCE='1%',
 MATERIAL='CHIP',
 VALUE='33.2',
 PRIM_FILE='W:/<user>/logical/q_res/chips/chips.prt';

PART_NAME
 R550 'Q_RES_0402LF-33.2,1%,1/16W,CHIA':;

SECTION_NUMBER 1
 '@SCM_LIB.SCM(SCH_1):PAGE21_I178@PURE_QUANTA.Q_RES(CHIPS)':
 C_PATH='@scm_lib.scm(sch_1):page21_i178@pure_quanta.q_res(chips)',
 P_PATH='@scm_lib.scm(sch_1):page21_i178@pure_quanta.q_res(chips)',
 PATH='I178',
 DRAWING='@SCM_LIB.SCM(SCH_1):PAGE21',
 PHYS_PAGE='21',
 XY='(3500,2950)',
 ROT='0',
 VER='1',
 PACK_TYPE='0402LF',
 LOCATION='R550',
 CDS_LIB='pure_quanta',
 CDS_PART_NAME='Q_RES_0402LF-33.2,1%,1/16W,CHIA',
 WATTAGE='1/16W',
 TOLERANCE='1%',
 MATERIAL='CHIP',
 VALUE='33.2',
 PRIM_FILE='W:/<user>/logical/q_res/chips/chips.prt';

PART_NAME
 R551 'Q_RES_0402LF-33.2,1%,1/16W,CHIA':;

SECTION_NUMBER 1
 '@SCM_LIB.SCM(SCH_1):PAGE25_I173@PURE_QUANTA.Q_RES(CHIPS)':
 C_PATH='@scm_lib.scm(sch_1):page25_i173@pure_quanta.q_res(chips)',
 P_PATH='@scm_lib.scm(sch_1):page25_i173@pure_quanta.q_res(chips)',
 PATH='I173',
 DRAWING='@SCM_LIB.SCM(SCH_1):PAGE25',
 PHYS_PAGE='25',
 XY='(2900,2600)',
 ROT='0',
 VER='1',
 PACK_TYPE='0402LF',
 LOCATION='R551',
 CDS_LIB='pure_quanta',
 CDS_PART_NAME='Q_RES_0402LF-33.2,1%,1/16W,CHIA',
 WATTAGE='1/16W',
 TOLERANCE='1%',
 MATERIAL='CHIP',
 VALUE='33.2',
 PRIM_FILE='W:/<user>/logical/q_res/chips/chips.prt';

PART_NAME
 R552 'Q_RES_0402LF-33.2,1%,1/16W,CHIA':;

SECTION_NUMBER 1
 '@SCM_LIB.SCM(SCH_1):PAGE21_I179@PURE_QUANTA.Q_RES(CHIPS)':
 C_PATH='@scm_lib.scm(sch_1):page21_i179@pure_quanta.q_res(chips)',
 P_PATH='@scm_lib.scm(sch_1):page21_i179@pure_quanta.q_res(chips)',
 PATH='I179',
 DRAWING='@SCM_LIB.SCM(SCH_1):PAGE21',
 PHYS_PAGE='21',
 XY='(3500,3000)',
 ROT='0',
 VER='1',
 PACK_TYPE='0402LF',
 LOCATION='R552',
 CDS_LIB='pure_quanta',
 CDS_PART_NAME='Q_RES_0402LF-33.2,1%,1/16W,CHIA',
 WATTAGE='1/16W',
 TOLERANCE='1%',
 MATERIAL='CHIP',
 VALUE='33.2',
 PRIM_FILE='W:/<user>/logical/q_res/chips/chips.prt';

PART_NAME
 R553 'Q_RES_0402LF-33.2,1%,1/16W,CHIA':;

SECTION_NUMBER 1
 '@SCM_LIB.SCM(SCH_1):PAGE21_I175@PURE_QUANTA.Q_RES(CHIPS)':
 C_PATH='@scm_lib.scm(sch_1):page21_i175@pure_quanta.q_res(chips)',
 P_PATH='@scm_lib.scm(sch_1):page21_i175@pure_quanta.q_res(chips)',
 PATH='I175',
 DRAWING='@SCM_LIB.SCM(SCH_1):PAGE21',
 PHYS_PAGE='21',
 XY='(3500,2700)',
 ROT='0',
 VER='1',
 PACK_TYPE='0402LF',
 LOCATION='R553',
 CDS_LIB='pure_quanta',
 CDS_PART_NAME='Q_RES_0402LF-33.2,1%,1/16W,CHIA',
 WATTAGE='1/16W',
 TOLERANCE='1%',
 MATERIAL='CHIP',
 VALUE='33.2',
 PRIM_FILE='W:/<user>/logical/q_res/chips/chips.prt';

PART_NAME
 R554 'Q_RES_0402LF-4.7K,1%,1/16W,EMPB':;

SECTION_NUMBER 1
 '@SCM_LIB.SCM(SCH_1):PAGE25_I156@PURE_QUANTA.Q_RES(CHIPS)':
 C_PATH='@scm_lib.scm(sch_1):page25_i156@pure_quanta.q_res(chips)',
 P_PATH='@scm_lib.scm(sch_1):page25_i156@pure_quanta.q_res(chips)',
 PATH='I156',
 DRAWING='@SCM_LIB.SCM(SCH_1):PAGE25',
 PHYS_PAGE='25',
 XY='(3100,2925)',
 ROT='0',
 VER='2',
 PACK_TYPE='0402LF',
 CDS_LIB='pure_quanta',
 CDS_PART_NAME='Q_RES_0402LF-4.7K,1%,1/16W,EMPB',
 WATTAGE='1/16W',
 TOLERANCE='1%',
 MATERIAL='EMPTY',
 VALUE='4.7K',
 PRIM_FILE='W:/<user>/logical/q_res/chips/chips.prt';

PART_NAME
 R555 'Q_RES_0402LF-33.2,1%,1/16W,CHIA':;

SECTION_NUMBER 1
 '@SCM_LIB.SCM(SCH_1):PAGE25_I174@PURE_QUANTA.Q_RES(CHIPS)':
 C_PATH='@scm_lib.scm(sch_1):page25_i174@pure_quanta.q_res(chips)',
 P_PATH='@scm_lib.scm(sch_1):page25_i174@pure_quanta.q_res(chips)',
 PATH='I174',
 DRAWING='@SCM_LIB.SCM(SCH_1):PAGE25',
 PHYS_PAGE='25',
 XY='(4200,3550)',
 ROT='0',
 VER='1',
 PACK_TYPE='0402LF',
 LOCATION='R555',
 CDS_LIB='pure_quanta',
 CDS_PART_NAME='Q_RES_0402LF-33.2,1%,1/16W,CHIA',
 WATTAGE='1/16W',
 TOLERANCE='1%',
 MATERIAL='CHIP',
 VALUE='33.2',
 PRIM_FILE='W:/<user>/logical/q_res/chips/chips.prt';

PART_NAME
 R556 'Q_RES_0402LF-33.2,1%,1/16W,CHIA':;

SECTION_NUMBER 1
 '@SCM_LIB.SCM(SCH_1):PAGE25_I175@PURE_QUANTA.Q_RES(CHIPS)':
 C_PATH='@scm_lib.scm(sch_1):page25_i175@pure_quanta.q_res(chips)',
 P_PATH='@scm_lib.scm(sch_1):page25_i175@pure_quanta.q_res(chips)',
 PATH='I175',
 DRAWING='@SCM_LIB.SCM(SCH_1):PAGE25',
 PHYS_PAGE='25',
 XY='(3425,1900)',
 ROT='0',
 VER='1',
 PACK_TYPE='0402LF',
 LOCATION='R556',
 CDS_LIB='pure_quanta',
 CDS_PART_NAME='Q_RES_0402LF-33.2,1%,1/16W,CHIA',
 WATTAGE='1/16W',
 TOLERANCE='1%',
 MATERIAL='CHIP',
 VALUE='33.2',
 PRIM_FILE='W:/<user>/logical/q_res/chips/chips.prt';

PART_NAME
 R557 'Q_RES_0402LF-4.7K,1%,1/16W,CHIA':;

SECTION_NUMBER 1
 '@SCM_LIB.SCM(SCH_1):PAGE21_I173@PURE_QUANTA.Q_RES(CHIPS)':
 C_PATH='@scm_lib.scm(sch_1):page21_i173@pure_quanta.q_res(chips)',
 P_PATH='@scm_lib.scm(sch_1):page21_i173@pure_quanta.q_res(chips)',
 PATH='I173',
 DRAWING='@SCM_LIB.SCM(SCH_1):PAGE21',
 PHYS_PAGE='21',
 XY='(2975,3925)',
 ROT='0',
 VER='2',
 PACK_TYPE='0402LF',
 LOCATION='R557',
 CDS_LIB='pure_quanta',
 CDS_PART_NAME='Q_RES_0402LF-4.7K,1%,1/16W,CHIA',
 WATTAGE='1/16W',
 TOLERANCE='1%',
 MATERIAL='CHIP',
 VALUE='4.7K',
 PRIM_FILE='W:/<user>/logical/q_res/chips/chips.prt';

PART_NAME
 R558 'Q_RES_0402LF-4.7K,1%,1/16W,CHIA':;

SECTION_NUMBER 1
 '@SCM_LIB.SCM(SCH_1):PAGE21_I174@PURE_QUANTA.Q_RES(CHIPS)':
 C_PATH='@scm_lib.scm(sch_1):page21_i174@pure_quanta.q_res(chips)',
 P_PATH='@scm_lib.scm(sch_1):page21_i174@pure_quanta.q_res(chips)',
 PATH='I174',
 DRAWING='@SCM_LIB.SCM(SCH_1):PAGE21',
 PHYS_PAGE='21',
 XY='(2850,3925)',
 ROT='0',
 VER='2',
 PACK_TYPE='0402LF',
 LOCATION='R558',
 CDS_LIB='pure_quanta',
 CDS_PART_NAME='Q_RES_0402LF-4.7K,1%,1/16W,CHIA',
 WATTAGE='1/16W',
 TOLERANCE='1%',
 MATERIAL='CHIP',
 VALUE='4.7K',
 PRIM_FILE='W:/<user>/logical/q_res/chips/chips.prt';

PART_NAME
 R559 'Q_RES_0402LF-33.2,1%,1/16W,CHIA':;

SECTION_NUMBER 1
 '@SCM_LIB.SCM(SCH_1):PAGE25_I176@PURE_QUANTA.Q_RES(CHIPS)':
 C_PATH='@scm_lib.scm(sch_1):page25_i176@pure_quanta.q_res(chips)',
 P_PATH='@scm_lib.scm(sch_1):page25_i176@pure_quanta.q_res(chips)',
 PATH='I176',
 DRAWING='@SCM_LIB.SCM(SCH_1):PAGE25',
 PHYS_PAGE='25',
 XY='(3425,1825)',
 ROT='0',
 VER='1',
 PACK_TYPE='0402LF',
 LOCATION='R559',
 CDS_LIB='pure_quanta',
 CDS_PART_NAME='Q_RES_0402LF-33.2,1%,1/16W,CHIA',
 WATTAGE='1/16W',
 TOLERANCE='1%',
 MATERIAL='CHIP',
 VALUE='33.2',
 PRIM_FILE='W:/<user>/logical/q_res/chips/chips.prt';

PART_NAME
 R560 'Q_RES_0402LF-0,5%,1/16W,CHIP,CA':;

SECTION_NUMBER 1
 '@SCM_LIB.SCM(SCH_1):PAGE25_I149@PURE_QUANTA.Q_RES(CHIPS)':
 C_PATH='@scm_lib.scm(sch_1):page25_i149@pure_quanta.q_res(chips)',
 P_PATH='@scm_lib.scm(sch_1):page25_i149@pure_quanta.q_res(chips)',
 PATH='I149',
 DRAWING='@SCM_LIB.SCM(SCH_1):PAGE25',
 PHYS_PAGE='25',
 XY='(5000,3150)',
 ROT='0',
 VER='2',
 PACK_TYPE='0402LF',
 CDS_LIB='pure_quanta',
 CDS_PART_NAME='Q_RES_0402LF-0,5%,1/16W,CHIP,CA',
 WATTAGE='1/16W',
 TOLERANCE='5%',
 MATERIAL='CHIP',
 VALUE='0',
 PRIM_FILE='W:/<user>/logical/q_res/chips/chips.prt';

PART_NAME
 R561 'Q_RES_0402LF-33.2,1%,1/16W,EMPA':;

SECTION_NUMBER 1
 '@SCM_LIB.SCM(SCH_1):PAGE21_I181@PURE_QUANTA.Q_RES(CHIPS)':
 C_PATH='@scm_lib.scm(sch_1):page21_i181@pure_quanta.q_res(chips)',
 P_PATH='@scm_lib.scm(sch_1):page21_i181@pure_quanta.q_res(chips)',
 PATH='I181',
 DRAWING='@SCM_LIB.SCM(SCH_1):PAGE21',
 PHYS_PAGE='21',
 XY='(3500,3150)',
 ROT='0',
 VER='1',
 PACK_TYPE='0402LF',
 LOCATION='R561',
 CDS_LIB='pure_quanta',
 CDS_PART_NAME='Q_RES_0402LF-33.2,1%,1/16W,EMPA',
 WATTAGE='1/16W',
 TOLERANCE='1%',
 MATERIAL='EMPTY',
 VALUE='33.2',
 PRIM_FILE='W:/<user>/logical/q_res/chips/chips.prt';

PART_NAME
 R562 'Q_RES_0402LF-33.2,1%,1/16W,CHIA':;

SECTION_NUMBER 1
 '@SCM_LIB.SCM(SCH_1):PAGE21_I180@PURE_QUANTA.Q_RES(CHIPS)':
 C_PATH='@scm_lib.scm(sch_1):page21_i180@pure_quanta.q_res(chips)',
 P_PATH='@scm_lib.scm(sch_1):page21_i180@pure_quanta.q_res(chips)',
 PATH='I180',
 DRAWING='@SCM_LIB.SCM(SCH_1):PAGE21',
 PHYS_PAGE='21',
 XY='(3500,3100)',
 ROT='0',
 VER='1',
 PACK_TYPE='0402LF',
 LOCATION='R562',
 CDS_LIB='pure_quanta',
 CDS_PART_NAME='Q_RES_0402LF-33.2,1%,1/16W,CHIA',
 WATTAGE='1/16W',
 TOLERANCE='1%',
 MATERIAL='CHIP',
 VALUE='33.2',
 PRIM_FILE='W:/<user>/logical/q_res/chips/chips.prt';

PART_NAME
 R563 'Q_RES_0402LF-4.7K,1%,1/16W,CHIA':;

SECTION_NUMBER 1
 '@SCM_LIB.SCM(SCH_1):PAGE25_I3@PURE_QUANTA.Q_RES(CHIPS)':
 C_PATH='@scm_lib.scm(sch_1):page25_i3@pure_quanta.q_res(chips)',
 P_PATH='@scm_lib.scm(sch_1):page25_i3@pure_quanta.q_res(chips)',
 PATH='I3',
 DRAWING='@SCM_LIB.SCM(SCH_1):PAGE25',
 PHYS_PAGE='25',
 XY='(2875,-675)',
 ROT='2',
 VER='2',
 PACK_TYPE='0402LF',
 LOCATION='R563',
 CDS_LIB='pure_quanta',
 CDS_PART_NAME='Q_RES_0402LF-4.7K,1%,1/16W,CHIA',
 WATTAGE='1/16W',
 TOLERANCE='1%',
 MATERIAL='CHIP',
 VALUE='4.7K',
 PRIM_FILE='W:/<user>/logical/q_res/chips/chips.prt';

PART_NAME
 R564 'Q_RES_0402LF-0,5%,1/16W,EMPTY,A':;

SECTION_NUMBER 1
 '@SCM_LIB.SCM(SCH_1):PAGE10_I562@PURE_QUANTA.Q_RES(CHIPS)':
 C_PATH='@scm_lib.scm(sch_1):page10_i562@pure_quanta.q_res(chips)',
 P_PATH='@scm_lib.scm(sch_1):page10_i562@pure_quanta.q_res(chips)',
 PATH='I562',
 DRAWING='@SCM_LIB.SCM(SCH_1):PAGE10',
 PHYS_PAGE='10',
 XY='(-6450,-1250)',
 ROT='2',
 VER='1',
 PACK_TYPE='0402LF',
 CDS_LIB='pure_quanta',
 CDS_PART_NAME='Q_RES_0402LF-0,5%,1/16W,EMPTY,A',
 WATTAGE='1/16W',
 TOLERANCE='5%',
 MATERIAL='EMPTY',
 VALUE='0',
 PRIM_FILE='W:/<user>/logical/q_res/chips/chips.prt';

PART_NAME
 R565 'Q_RES_0402LF-100,1%,1/16W,CHIPA':;

SECTION_NUMBER 1
 '@SCM_LIB.SCM(SCH_1):PAGE15_I406@PURE_QUANTA.Q_RES(CHIPS)':
 C_PATH='@scm_lib.scm(sch_1):page15_i406@pure_quanta.q_res(chips)',
 P_PATH='@scm_lib.scm(sch_1):page15_i406@pure_quanta.q_res(chips)',
 PATH='I406',
 DRAWING='@SCM_LIB.SCM(SCH_1):PAGE15',
 PHYS_PAGE='15',
 XY='(4125,3375)',
 ROT='0',
 VER='1',
 PACK_TYPE='0402LF',
 LOCATION='R565',
 CDS_LIB='pure_quanta',
 CDS_PART_NAME='Q_RES_0402LF-100,1%,1/16W,CHIPA',
 WATTAGE='1/16W',
 TOLERANCE='1%',
 MATERIAL='CHIP',
 VALUE='100',
 PRIM_FILE='W:/<user>/logical/q_res/chips/chips.prt';

PART_NAME
 R566 'Q_RES_0402LF-0,5%,1/16W,CHIP,CA':;

SECTION_NUMBER 1
 '@SCM_LIB.SCM(SCH_1):PAGE15_I128@PURE_QUANTA.Q_RES(CHIPS)':
 C_PATH='@scm_lib.scm(sch_1):page15_i128@pure_quanta.q_res(chips)',
 P_PATH='@scm_lib.scm(sch_1):page15_i128@pure_quanta.q_res(chips)',
 PATH='I128',
 DRAWING='@SCM_LIB.SCM(SCH_1):PAGE15',
 PHYS_PAGE='15',
 XY='(4125,3325)',
 ROT='0',
 VER='1',
 PACK_TYPE='0402LF',
 LOCATION='R566',
 CDS_LIB='pure_quanta',
 CDS_PART_NAME='Q_RES_0402LF-0,5%,1/16W,CHIP,CA',
 WATTAGE='1/16W',
 TOLERANCE='5%',
 MATERIAL='CHIP',
 VALUE='0',
 PRIM_FILE='W:/<user>/logical/q_res/chips/chips.prt';

PART_NAME
 R567 'Q_RES_0402LF-33.2,1%,1/16W,CHIA':;

SECTION_NUMBER 1
 '@SCM_LIB.SCM(SCH_1):PAGE12_I274@PURE_QUANTA.Q_RES(CHIPS)':
 C_PATH='@scm_lib.scm(sch_1):page12_i274@pure_quanta.q_res(chips)',
 P_PATH='@scm_lib.scm(sch_1):page12_i274@pure_quanta.q_res(chips)',
 PATH='I274',
 DRAWING='@SCM_LIB.SCM(SCH_1):PAGE12',
 PHYS_PAGE='12',
 XY='(4775,-450)',
 ROT='0',
 VER='1',
 PACK_TYPE='0402LF',
 LOCATION='R567',
 CDS_LIB='pure_quanta',
 CDS_PART_NAME='Q_RES_0402LF-33.2,1%,1/16W,CHIA',
 WATTAGE='1/16W',
 TOLERANCE='1%',
 MATERIAL='CHIP',
 VALUE='33.2',
 PRIM_FILE='W:/<user>/logical/q_res/chips/chips.prt';

PART_NAME
 R568 'Q_RES_0402LF-220,1%,1/16W,CHIPA':;

SECTION_NUMBER 1
 '@SCM_LIB.SCM(SCH_1):PAGE49_I59@PURE_QUANTA.Q_RES(CHIPS)':
 C_PATH='@scm_lib.scm(sch_1):page49_i59@pure_quanta.q_res(chips)',
 P_PATH='@scm_lib.scm(sch_1):page49_i59@pure_quanta.q_res(chips)',
 PATH='I59',
 DRAWING='@SCM_LIB.SCM(SCH_1):PAGE49',
 PHYS_PAGE='49',
 XY='(-5200,3175)',
 ROT='1',
 VER='1',
 PACK_TYPE='0402LF',
 LOCATION='R568',
 CDS_LIB='pure_quanta',
 CDS_PART_NAME='Q_RES_0402LF-220,1%,1/16W,CHIPA',
 WATTAGE='1/16W',
 TOLERANCE='1%',
 MATERIAL='CHIP',
 VALUE='220',
 PRIM_FILE='W:/<user>/logical/q_res/chips/chips.prt';

PART_NAME
 R569 'Q_RES_0402LF-220,1%,1/16W,CHIPA':;

SECTION_NUMBER 1
 '@SCM_LIB.SCM(SCH_1):PAGE49_I60@PURE_QUANTA.Q_RES(CHIPS)':
 C_PATH='@scm_lib.scm(sch_1):page49_i60@pure_quanta.q_res(chips)',
 P_PATH='@scm_lib.scm(sch_1):page49_i60@pure_quanta.q_res(chips)',
 PATH='I60',
 DRAWING='@SCM_LIB.SCM(SCH_1):PAGE49',
 PHYS_PAGE='49',
 XY='(-4975,3175)',
 ROT='1',
 VER='1',
 PACK_TYPE='0402LF',
 LOCATION='R569',
 CDS_LIB='pure_quanta',
 CDS_PART_NAME='Q_RES_0402LF-220,1%,1/16W,CHIPA',
 WATTAGE='1/16W',
 TOLERANCE='1%',
 MATERIAL='CHIP',
 VALUE='220',
 PRIM_FILE='W:/<user>/logical/q_res/chips/chips.prt';

PART_NAME
 R570 'Q_RES_0402LF-33.2,1%,1/16W,CHIA':;

SECTION_NUMBER 1
 '@SCM_LIB.SCM(SCH_1):PAGE12_I275@PURE_QUANTA.Q_RES(CHIPS)':
 C_PATH='@scm_lib.scm(sch_1):page12_i275@pure_quanta.q_res(chips)',
 P_PATH='@scm_lib.scm(sch_1):page12_i275@pure_quanta.q_res(chips)',
 PATH='I275',
 DRAWING='@SCM_LIB.SCM(SCH_1):PAGE12',
 PHYS_PAGE='12',
 XY='(4775,-500)',
 ROT='0',
 VER='1',
 PACK_TYPE='0402LF',
 LOCATION='R570',
 CDS_LIB='pure_quanta',
 CDS_PART_NAME='Q_RES_0402LF-33.2,1%,1/16W,CHIA',
 WATTAGE='1/16W',
 TOLERANCE='1%',
 MATERIAL='CHIP',
 VALUE='33.2',
 PRIM_FILE='W:/<user>/logical/q_res/chips/chips.prt';

PART_NAME
 R571 'Q_RES_0402LF-0,5%,1/16W,CHIP,CA':;

SECTION_NUMBER 1
 '@SCM_LIB.SCM(SCH_1):PAGE34_I35@PURE_QUANTA.Q_RES(CHIPS)':
 C_PATH='@scm_lib.scm(sch_1):page34_i35@pure_quanta.q_res(chips)',
 P_PATH='@scm_lib.scm(sch_1):page34_i35@pure_quanta.q_res(chips)',
 PATH='I35',
 DRAWING='@SCM_LIB.SCM(SCH_1):PAGE34',
 PHYS_PAGE='34',
 XY='(-7050,3500)',
 ROT='0',
 VER='1',
 PACK_TYPE='0402LF',
 LOCATION='R571',
 CDS_LIB='pure_quanta',
 CDS_PART_NAME='Q_RES_0402LF-0,5%,1/16W,CHIP,CA',
 WATTAGE='1/16W',
 TOLERANCE='5%',
 MATERIAL='CHIP',
 VALUE='0',
 PRIM_FILE='W:/<user>/logical/q_res/chips/chips.prt';

PART_NAME
 R574 'Q_RES_0402LF-0,5%,1/16W,CHIP,CA':;

SECTION_NUMBER 1
 '@SCM_LIB.SCM(SCH_1):PAGE35_I76@PURE_QUANTA.Q_RES(CHIPS)':
 C_PATH='@scm_lib.scm(sch_1):page35_i76@pure_quanta.q_res(chips)',
 P_PATH='@scm_lib.scm(sch_1):page35_i76@pure_quanta.q_res(chips)',
 PATH='I76',
 DRAWING='@SCM_LIB.SCM(SCH_1):PAGE35',
 SEC_TYPE='0402LF',
 PHYS_PAGE='35',
 XY='(-7300,3400)',
 ROT='0',
 VER='1',
 PACK_TYPE='0402LF',
 LOCATION='R574',
 SEC='1',
 CDS_LIB='pure_quanta',
 CDS_PART_NAME='Q_RES_0402LF-0,5%,1/16W,CHIP,CA',
 WATTAGE='1/16W',
 TOLERANCE='5%',
 MATERIAL='CHIP',
 VALUE='0',
 PRIM_FILE='W:/<user>/logical/q_res/chips/chips.prt';

PART_NAME
 R575 'Q_RES_0402LF-0,5%,1/16W,CHIP,CA':;

SECTION_NUMBER 1
 '@SCM_LIB.SCM(SCH_1):PAGE36_I2@PURE_QUANTA.Q_RES(CHIPS)':
 C_PATH='@scm_lib.scm(sch_1):page36_i2@pure_quanta.q_res(chips)',
 P_PATH='@scm_lib.scm(sch_1):page36_i2@pure_quanta.q_res(chips)',
 PATH='I2',
 DRAWING='@SCM_LIB.SCM(SCH_1):PAGE36',
 SEC_TYPE='0402LF',
 PHYS_PAGE='36',
 XY='(-7250,5275)',
 ROT='0',
 VER='1',
 PACK_TYPE='0402LF',
 LOCATION='R575',
 SEC='1',
 CDS_LIB='pure_quanta',
 CDS_PART_NAME='Q_RES_0402LF-0,5%,1/16W,CHIP,CA',
 WATTAGE='1/16W',
 TOLERANCE='5%',
 MATERIAL='CHIP',
 VALUE='0',
 PRIM_FILE='W:/<user>/logical/q_res/chips/chips.prt';

PART_NAME
 R577 'Q_RES_0402LF-0,5%,1/16W,CHIP,CA':;

SECTION_NUMBER 1
 '@SCM_LIB.SCM(SCH_1):PAGE36_I3@PURE_QUANTA.Q_RES(CHIPS)':
 C_PATH='@scm_lib.scm(sch_1):page36_i3@pure_quanta.q_res(chips)',
 P_PATH='@scm_lib.scm(sch_1):page36_i3@pure_quanta.q_res(chips)',
 PATH='I3',
 DRAWING='@SCM_LIB.SCM(SCH_1):PAGE36',
 SEC_TYPE='0402LF',
 PHYS_PAGE='36',
 XY='(-7250,5125)',
 ROT='0',
 VER='1',
 PACK_TYPE='0402LF',
 LOCATION='R577',
 SEC='1',
 CDS_LIB='pure_quanta',
 CDS_PART_NAME='Q_RES_0402LF-0,5%,1/16W,CHIP,CA',
 WATTAGE='1/16W',
 TOLERANCE='5%',
 MATERIAL='CHIP',
 VALUE='0',
 PRIM_FILE='W:/<user>/logical/q_res/chips/chips.prt';

PART_NAME
 R578 'Q_RES_0402LF-0,5%,1/16W,CHIP,CA':;

SECTION_NUMBER 1
 '@SCM_LIB.SCM(SCH_1):PAGE36_I8@PURE_QUANTA.Q_RES(CHIPS)':
 C_PATH='@scm_lib.scm(sch_1):page36_i8@pure_quanta.q_res(chips)',
 P_PATH='@scm_lib.scm(sch_1):page36_i8@pure_quanta.q_res(chips)',
 PATH='I8',
 DRAWING='@SCM_LIB.SCM(SCH_1):PAGE36',
 SEC_TYPE='0402LF',
 PHYS_PAGE='36',
 XY='(-7250,5075)',
 ROT='0',
 VER='1',
 PACK_TYPE='0402LF',
 LOCATION='R578',
 SEC='1',
 CDS_LIB='pure_quanta',
 CDS_PART_NAME='Q_RES_0402LF-0,5%,1/16W,CHIP,CA',
 WATTAGE='1/16W',
 TOLERANCE='5%',
 MATERIAL='CHIP',
 VALUE='0',
 PRIM_FILE='W:/<user>/logical/q_res/chips/chips.prt';

PART_NAME
 R579 'Q_RES_0402LF-0,5%,1/16W,CHIP,CA':;

SECTION_NUMBER 1
 '@SCM_LIB.SCM(SCH_1):PAGE36_I7@PURE_QUANTA.Q_RES(CHIPS)':
 C_PATH='@scm_lib.scm(sch_1):page36_i7@pure_quanta.q_res(chips)',
 P_PATH='@scm_lib.scm(sch_1):page36_i7@pure_quanta.q_res(chips)',
 PATH='I7',
 DRAWING='@SCM_LIB.SCM(SCH_1):PAGE36',
 SEC_TYPE='0402LF',
 PHYS_PAGE='36',
 XY='(-7250,4975)',
 ROT='0',
 VER='1',
 PACK_TYPE='0402LF',
 LOCATION='R579',
 SEC='1',
 CDS_LIB='pure_quanta',
 CDS_PART_NAME='Q_RES_0402LF-0,5%,1/16W,CHIP,CA',
 WATTAGE='1/16W',
 TOLERANCE='5%',
 MATERIAL='CHIP',
 VALUE='0',
 PRIM_FILE='W:/<user>/logical/q_res/chips/chips.prt';

PART_NAME
 R580 'Q_RES_0402LF-33.2,1%,1/16W,CHIA':;

SECTION_NUMBER 1
 '@SCM_LIB.SCM(SCH_1):PAGE12_I321@PURE_QUANTA.Q_RES(CHIPS)':
 C_PATH='@scm_lib.scm(sch_1):page12_i321@pure_quanta.q_res(chips)',
 P_PATH='@scm_lib.scm(sch_1):page12_i321@pure_quanta.q_res(chips)',
 PATH='I321',
 DRAWING='@SCM_LIB.SCM(SCH_1):PAGE12',
 PHYS_PAGE='12',
 XY='(2075,-950)',
 ROT='0',
 VER='1',
 PACK_TYPE='0402LF',
 LOCATION='R580',
 CDS_LIB='pure_quanta',
 CDS_PART_NAME='Q_RES_0402LF-33.2,1%,1/16W,CHIA',
 WATTAGE='1/16W',
 TOLERANCE='1%',
 MATERIAL='CHIP',
 VALUE='33.2',
 PRIM_FILE='W:/<user>/logical/q_res/chips/chips.prt';

PART_NAME
 R582 'Q_RES_0402LF-33.2,1%,1/16W,CHIA':;

SECTION_NUMBER 1
 '@SCM_LIB.SCM(SCH_1):PAGE12_I318@PURE_QUANTA.Q_RES(CHIPS)':
 C_PATH='@scm_lib.scm(sch_1):page12_i318@pure_quanta.q_res(chips)',
 P_PATH='@scm_lib.scm(sch_1):page12_i318@pure_quanta.q_res(chips)',
 PATH='I318',
 DRAWING='@SCM_LIB.SCM(SCH_1):PAGE12',
 PHYS_PAGE='12',
 XY='(2075,-1000)',
 ROT='0',
 VER='1',
 PACK_TYPE='0402LF',
 LOCATION='R582',
 CDS_LIB='pure_quanta',
 CDS_PART_NAME='Q_RES_0402LF-33.2,1%,1/16W,CHIA',
 WATTAGE='1/16W',
 TOLERANCE='1%',
 MATERIAL='CHIP',
 VALUE='33.2',
 PRIM_FILE='W:/<user>/logical/q_res/chips/chips.prt';

PART_NAME
 R583 'Q_RES_0402LF-33.2,1%,1/16W,CHIA':;

SECTION_NUMBER 1
 '@SCM_LIB.SCM(SCH_1):PAGE12_I319@PURE_QUANTA.Q_RES(CHIPS)':
 C_PATH='@scm_lib.scm(sch_1):page12_i319@pure_quanta.q_res(chips)',
 P_PATH='@scm_lib.scm(sch_1):page12_i319@pure_quanta.q_res(chips)',
 PATH='I319',
 DRAWING='@SCM_LIB.SCM(SCH_1):PAGE12',
 PHYS_PAGE='12',
 XY='(2075,-1050)',
 ROT='0',
 VER='1',
 PACK_TYPE='0402LF',
 LOCATION='R583',
 CDS_LIB='pure_quanta',
 CDS_PART_NAME='Q_RES_0402LF-33.2,1%,1/16W,CHIA',
 WATTAGE='1/16W',
 TOLERANCE='1%',
 MATERIAL='CHIP',
 VALUE='33.2',
 PRIM_FILE='W:/<user>/logical/q_res/chips/chips.prt';

PART_NAME
 R584 'Q_RES_0402LF-33.2,1%,1/16W,CHIA':;

SECTION_NUMBER 1
 '@SCM_LIB.SCM(SCH_1):PAGE12_I320@PURE_QUANTA.Q_RES(CHIPS)':
 C_PATH='@scm_lib.scm(sch_1):page12_i320@pure_quanta.q_res(chips)',
 P_PATH='@scm_lib.scm(sch_1):page12_i320@pure_quanta.q_res(chips)',
 PATH='I320',
 DRAWING='@SCM_LIB.SCM(SCH_1):PAGE12',
 PHYS_PAGE='12',
 XY='(2075,-1100)',
 ROT='0',
 VER='1',
 PACK_TYPE='0402LF',
 LOCATION='R584',
 CDS_LIB='pure_quanta',
 CDS_PART_NAME='Q_RES_0402LF-33.2,1%,1/16W,CHIA',
 WATTAGE='1/16W',
 TOLERANCE='1%',
 MATERIAL='CHIP',
 VALUE='33.2',
 PRIM_FILE='W:/<user>/logical/q_res/chips/chips.prt';

PART_NAME
 R585 'Q_RES_0402LF-33.2,1%,1/16W,CHIA':;

SECTION_NUMBER 1
 '@SCM_LIB.SCM(SCH_1):PAGE15_I404@PURE_QUANTA.Q_RES(CHIPS)':
 C_PATH='@scm_lib.scm(sch_1):page15_i404@pure_quanta.q_res(chips)',
 P_PATH='@scm_lib.scm(sch_1):page15_i404@pure_quanta.q_res(chips)',
 PATH='I404',
 DRAWING='@SCM_LIB.SCM(SCH_1):PAGE15',
 PHYS_PAGE='15',
 XY='(-725,4025)',
 ROT='0',
 VER='1',
 PACK_TYPE='0402LF',
 LOCATION='R585',
 CDS_LIB='pure_quanta',
 CDS_PART_NAME='Q_RES_0402LF-33.2,1%,1/16W,CHIA',
 WATTAGE='1/16W',
 TOLERANCE='1%',
 MATERIAL='CHIP',
 VALUE='33.2',
 PRIM_FILE='W:/<user>/logical/q_res/chips/chips.prt';

PART_NAME
 R586 'Q_RES_0402LF-4.7K,1%,1/16W,CHIA':;

SECTION_NUMBER 1
 '@SCM_LIB.SCM(SCH_1):PAGE42_I67@PURE_QUANTA.Q_RES(CHIPS)':
 C_PATH='@scm_lib.scm(sch_1):page42_i67@pure_quanta.q_res(chips)',
 P_PATH='@scm_lib.scm(sch_1):page42_i67@pure_quanta.q_res(chips)',
 PATH='I67',
 DRAWING='@SCM_LIB.SCM(SCH_1):PAGE42',
 PHYS_PAGE='42',
 XY='(8500,4300)',
 ROT='0',
 VER='1',
 PACK_TYPE='0402LF',
 LOCATION='R586',
 CDS_LIB='pure_quanta',
 CDS_PART_NAME='Q_RES_0402LF-4.7K,1%,1/16W,CHIA',
 WATTAGE='1/16W',
 TOLERANCE='1%',
 MATERIAL='CHIP',
 VALUE='4.7K',
 PRIM_FILE='W:/<user>/logical/q_res/chips/chips.prt';

PART_NAME
 R589 'Q_RES_0402LF-33.2,1%,1/16W,CHIA':;

SECTION_NUMBER 1
 '@SCM_LIB.SCM(SCH_1):PAGE12_I316@PURE_QUANTA.Q_RES(CHIPS)':
 C_PATH='@scm_lib.scm(sch_1):page12_i316@pure_quanta.q_res(chips)',
 P_PATH='@scm_lib.scm(sch_1):page12_i316@pure_quanta.q_res(chips)',
 PATH='I316',
 DRAWING='@SCM_LIB.SCM(SCH_1):PAGE12',
 PHYS_PAGE='12',
 XY='(4125,1650)',
 ROT='0',
 VER='1',
 PACK_TYPE='0402LF',
 LOCATION='R589',
 CDS_LIB='pure_quanta',
 CDS_PART_NAME='Q_RES_0402LF-33.2,1%,1/16W,CHIA',
 WATTAGE='1/16W',
 TOLERANCE='1%',
 MATERIAL='CHIP',
 VALUE='33.2',
 PRIM_FILE='W:/<user>/logical/q_res/chips/chips.prt';

PART_NAME
 R590 'Q_RES_0402LF-33.2,1%,1/16W,CHIA':;

SECTION_NUMBER 1
 '@SCM_LIB.SCM(SCH_1):PAGE12_I317@PURE_QUANTA.Q_RES(CHIPS)':
 C_PATH='@scm_lib.scm(sch_1):page12_i317@pure_quanta.q_res(chips)',
 P_PATH='@scm_lib.scm(sch_1):page12_i317@pure_quanta.q_res(chips)',
 PATH='I317',
 DRAWING='@SCM_LIB.SCM(SCH_1):PAGE12',
 PHYS_PAGE='12',
 XY='(4125,1600)',
 ROT='0',
 VER='1',
 PACK_TYPE='0402LF',
 LOCATION='R590',
 CDS_LIB='pure_quanta',
 CDS_PART_NAME='Q_RES_0402LF-33.2,1%,1/16W,CHIA',
 WATTAGE='1/16W',
 TOLERANCE='1%',
 MATERIAL='CHIP',
 VALUE='33.2',
 PRIM_FILE='W:/<user>/logical/q_res/chips/chips.prt';

PART_NAME
 R592 'Q_RES_0402LF-4.7K,1%,1/16W,CHIA':;

SECTION_NUMBER 1
 '@SCM_LIB.SCM(SCH_1):PAGE25_I171@PURE_QUANTA.Q_RES(CHIPS)':
 C_PATH='@scm_lib.scm(sch_1):page25_i171@pure_quanta.q_res(chips)',
 P_PATH='@scm_lib.scm(sch_1):page25_i171@pure_quanta.q_res(chips)',
 PATH='I171',
 DRAWING='@SCM_LIB.SCM(SCH_1):PAGE25',
 PHYS_PAGE='25',
 XY='(3900,1525)',
 ROT='0',
 VER='2',
 PACK_TYPE='0402LF',
 LOCATION='R592',
 CDS_LIB='pure_quanta',
 CDS_PART_NAME='Q_RES_0402LF-4.7K,1%,1/16W,CHIA',
 WATTAGE='1/16W',
 TOLERANCE='1%',
 MATERIAL='CHIP',
 VALUE='4.7K',
 PRIM_FILE='W:/<user>/logical/q_res/chips/chips.prt';

PART_NAME
 R593 'Q_RES_0402LF-4.7K,1%,1/16W,EMPA':;

SECTION_NUMBER 1
 '@SCM_LIB.SCM(SCH_1):PAGE42_I39@PURE_QUANTA.Q_RES(CHIPS)':
 C_PATH='@scm_lib.scm(sch_1):page42_i39@pure_quanta.q_res(chips)',
 P_PATH='@scm_lib.scm(sch_1):page42_i39@pure_quanta.q_res(chips)',
 PATH='I39',
 DRAWING='@SCM_LIB.SCM(SCH_1):PAGE42',
 PHYS_PAGE='42',
 XY='(8500,3400)',
 ROT='0',
 VER='1',
 PACK_TYPE='0402LF',
 LOCATION='R593',
 CDS_LIB='pure_quanta',
 CDS_PART_NAME='Q_RES_0402LF-4.7K,1%,1/16W,EMPA',
 WATTAGE='1/16W',
 TOLERANCE='1%',
 MATERIAL='EMPTY',
 VALUE='4.7K',
 PRIM_FILE='W:/<user>/logical/q_res/chips/chips.prt';

PART_NAME
 R594 'Q_RES_0402LF-33.2,1%,1/16W,CHIA':;

SECTION_NUMBER 1
 '@SCM_LIB.SCM(SCH_1):PAGE44_I360@PURE_QUANTA.Q_RES(CHIPS)':
 C_PATH='@scm_lib.scm(sch_1):page44_i360@pure_quanta.q_res(chips)',
 P_PATH='@scm_lib.scm(sch_1):page44_i360@pure_quanta.q_res(chips)',
 PATH='I360',
 DRAWING='@SCM_LIB.SCM(SCH_1):PAGE44',
 PHYS_PAGE='44',
 XY='(-2425,-125)',
 ROT='0',
 VER='1',
 PACK_TYPE='0402LF',
 LOCATION='R594',
 CDS_LIB='pure_quanta',
 CDS_PART_NAME='Q_RES_0402LF-33.2,1%,1/16W,CHIA',
 WATTAGE='1/16W',
 TOLERANCE='1%',
 MATERIAL='CHIP',
 VALUE='33.2',
 PRIM_FILE='W:/<user>/logical/q_res/chips/chips.prt';

PART_NAME
 R595 'Q_RES_0402LF-4.7K,1%,1/16W,EMPA':;

SECTION_NUMBER 1
 '@SCM_LIB.SCM(SCH_1):PAGE42_I37@PURE_QUANTA.Q_RES(CHIPS)':
 C_PATH='@scm_lib.scm(sch_1):page42_i37@pure_quanta.q_res(chips)',
 P_PATH='@scm_lib.scm(sch_1):page42_i37@pure_quanta.q_res(chips)',
 PATH='I37',
 DRAWING='@SCM_LIB.SCM(SCH_1):PAGE42',
 PHYS_PAGE='42',
 XY='(8500,3250)',
 ROT='0',
 VER='1',
 PACK_TYPE='0402LF',
 LOCATION='R595',
 CDS_LIB='pure_quanta',
 CDS_PART_NAME='Q_RES_0402LF-4.7K,1%,1/16W,EMPA',
 WATTAGE='1/16W',
 TOLERANCE='1%',
 MATERIAL='EMPTY',
 VALUE='4.7K',
 PRIM_FILE='W:/<user>/logical/q_res/chips/chips.prt';

PART_NAME
 R597 'Q_RES_0402LF-750,1%,1/16W,CHIPA':;

SECTION_NUMBER 1
 '@SCM_LIB.SCM(SCH_1):PAGE47_I18@PURE_QUANTA.Q_RES(CHIPS)':
 C_PATH='@scm_lib.scm(sch_1):page47_i18@pure_quanta.q_res(chips)',
 P_PATH='@scm_lib.scm(sch_1):page47_i18@pure_quanta.q_res(chips)',
 PATH='I18',
 DRAWING='@SCM_LIB.SCM(SCH_1):PAGE47',
 PHYS_PAGE='47',
 XY='(2675,3500)',
 ROT='0',
 VER='1',
 PACK_TYPE='0402LF',
 LOCATION='R597',
 CDS_LIB='pure_quanta',
 CDS_PART_NAME='Q_RES_0402LF-750,1%,1/16W,CHIPA',
 WATTAGE='1/16W',
 TOLERANCE='1%',
 MATERIAL='CHIP',
 VALUE='750',
 PRIM_FILE='W:/<user>/logical/q_res/chips/chips.prt';

PART_NAME
 R598 'Q_RES_0402LF-750,1%,1/16W,CHIPA':;

SECTION_NUMBER 1
 '@SCM_LIB.SCM(SCH_1):PAGE47_I20@PURE_QUANTA.Q_RES(CHIPS)':
 C_PATH='@scm_lib.scm(sch_1):page47_i20@pure_quanta.q_res(chips)',
 P_PATH='@scm_lib.scm(sch_1):page47_i20@pure_quanta.q_res(chips)',
 PATH='I20',
 DRAWING='@SCM_LIB.SCM(SCH_1):PAGE47',
 PHYS_PAGE='47',
 XY='(2675,3200)',
 ROT='0',
 VER='1',
 PACK_TYPE='0402LF',
 LOCATION='R598',
 CDS_LIB='pure_quanta',
 CDS_PART_NAME='Q_RES_0402LF-750,1%,1/16W,CHIPA',
 WATTAGE='1/16W',
 TOLERANCE='1%',
 MATERIAL='CHIP',
 VALUE='750',
 PRIM_FILE='W:/<user>/logical/q_res/chips/chips.prt';

PART_NAME
 R599 'Q_RES_0402LF-750,1%,1/16W,CHIPA':;

SECTION_NUMBER 1
 '@SCM_LIB.SCM(SCH_1):PAGE47_I23@PURE_QUANTA.Q_RES(CHIPS)':
 C_PATH='@scm_lib.scm(sch_1):page47_i23@pure_quanta.q_res(chips)',
 P_PATH='@scm_lib.scm(sch_1):page47_i23@pure_quanta.q_res(chips)',
 PATH='I23',
 DRAWING='@SCM_LIB.SCM(SCH_1):PAGE47',
 PHYS_PAGE='47',
 XY='(2675,2900)',
 ROT='0',
 VER='1',
 PACK_TYPE='0402LF',
 LOCATION='R599',
 CDS_LIB='pure_quanta',
 CDS_PART_NAME='Q_RES_0402LF-750,1%,1/16W,CHIPA',
 WATTAGE='1/16W',
 TOLERANCE='1%',
 MATERIAL='CHIP',
 VALUE='750',
 PRIM_FILE='W:/<user>/logical/q_res/chips/chips.prt';

PART_NAME
 R600 'Q_RES_0402LF-750,1%,1/16W,CHIPA':;

SECTION_NUMBER 1
 '@SCM_LIB.SCM(SCH_1):PAGE47_I25@PURE_QUANTA.Q_RES(CHIPS)':
 C_PATH='@scm_lib.scm(sch_1):page47_i25@pure_quanta.q_res(chips)',
 P_PATH='@scm_lib.scm(sch_1):page47_i25@pure_quanta.q_res(chips)',
 PATH='I25',
 DRAWING='@SCM_LIB.SCM(SCH_1):PAGE47',
 PHYS_PAGE='47',
 XY='(2675,2600)',
 ROT='0',
 VER='1',
 PACK_TYPE='0402LF',
 LOCATION='R600',
 CDS_LIB='pure_quanta',
 CDS_PART_NAME='Q_RES_0402LF-750,1%,1/16W,CHIPA',
 WATTAGE='1/16W',
 TOLERANCE='1%',
 MATERIAL='CHIP',
 VALUE='750',
 PRIM_FILE='W:/<user>/logical/q_res/chips/chips.prt';

PART_NAME
 R601 'Q_RES_0402LF-750,1%,1/16W,CHIPA':;

SECTION_NUMBER 1
 '@SCM_LIB.SCM(SCH_1):PAGE47_I31@PURE_QUANTA.Q_RES(CHIPS)':
 C_PATH='@scm_lib.scm(sch_1):page47_i31@pure_quanta.q_res(chips)',
 P_PATH='@scm_lib.scm(sch_1):page47_i31@pure_quanta.q_res(chips)',
 PATH='I31',
 DRAWING='@SCM_LIB.SCM(SCH_1):PAGE47',
 PHYS_PAGE='47',
 XY='(2675,2300)',
 ROT='0',
 VER='1',
 PACK_TYPE='0402LF',
 LOCATION='R601',
 CDS_LIB='pure_quanta',
 CDS_PART_NAME='Q_RES_0402LF-750,1%,1/16W,CHIPA',
 WATTAGE='1/16W',
 TOLERANCE='1%',
 MATERIAL='CHIP',
 VALUE='750',
 PRIM_FILE='W:/<user>/logical/q_res/chips/chips.prt';

PART_NAME
 R602 'Q_RES_0402LF-750,1%,1/16W,CHIPA':;

SECTION_NUMBER 1
 '@SCM_LIB.SCM(SCH_1):PAGE47_I33@PURE_QUANTA.Q_RES(CHIPS)':
 C_PATH='@scm_lib.scm(sch_1):page47_i33@pure_quanta.q_res(chips)',
 P_PATH='@scm_lib.scm(sch_1):page47_i33@pure_quanta.q_res(chips)',
 PATH='I33',
 DRAWING='@SCM_LIB.SCM(SCH_1):PAGE47',
 PHYS_PAGE='47',
 XY='(2675,2000)',
 ROT='0',
 VER='1',
 PACK_TYPE='0402LF',
 LOCATION='R602',
 CDS_LIB='pure_quanta',
 CDS_PART_NAME='Q_RES_0402LF-750,1%,1/16W,CHIPA',
 WATTAGE='1/16W',
 TOLERANCE='1%',
 MATERIAL='CHIP',
 VALUE='750',
 PRIM_FILE='W:/<user>/logical/q_res/chips/chips.prt';

PART_NAME
 R603 'Q_RES_0402LF-750,1%,1/16W,CHIPA':;

SECTION_NUMBER 1
 '@SCM_LIB.SCM(SCH_1):PAGE47_I35@PURE_QUANTA.Q_RES(CHIPS)':
 C_PATH='@scm_lib.scm(sch_1):page47_i35@pure_quanta.q_res(chips)',
 P_PATH='@scm_lib.scm(sch_1):page47_i35@pure_quanta.q_res(chips)',
 PATH='I35',
 DRAWING='@SCM_LIB.SCM(SCH_1):PAGE47',
 PHYS_PAGE='47',
 XY='(2675,1700)',
 ROT='0',
 VER='1',
 PACK_TYPE='0402LF',
 LOCATION='R603',
 CDS_LIB='pure_quanta',
 CDS_PART_NAME='Q_RES_0402LF-750,1%,1/16W,CHIPA',
 WATTAGE='1/16W',
 TOLERANCE='1%',
 MATERIAL='CHIP',
 VALUE='750',
 PRIM_FILE='W:/<user>/logical/q_res/chips/chips.prt';

PART_NAME
 R604 'Q_RES_0402LF-750,1%,1/16W,CHIPA':;

SECTION_NUMBER 1
 '@SCM_LIB.SCM(SCH_1):PAGE47_I37@PURE_QUANTA.Q_RES(CHIPS)':
 C_PATH='@scm_lib.scm(sch_1):page47_i37@pure_quanta.q_res(chips)',
 P_PATH='@scm_lib.scm(sch_1):page47_i37@pure_quanta.q_res(chips)',
 PATH='I37',
 DRAWING='@SCM_LIB.SCM(SCH_1):PAGE47',
 PHYS_PAGE='47',
 XY='(2675,1400)',
 ROT='0',
 VER='1',
 PACK_TYPE='0402LF',
 LOCATION='R604',
 CDS_LIB='pure_quanta',
 CDS_PART_NAME='Q_RES_0402LF-750,1%,1/16W,CHIPA',
 WATTAGE='1/16W',
 TOLERANCE='1%',
 MATERIAL='CHIP',
 VALUE='750',
 PRIM_FILE='W:/<user>/logical/q_res/chips/chips.prt';

PART_NAME
 R607 'Q_RES_0402LF-4.7K,1%,1/16W,CHIA':;

SECTION_NUMBER 1
 '@SCM_LIB.SCM(SCH_1):PAGE42_I29@PURE_QUANTA.Q_RES(CHIPS)':
 C_PATH='@scm_lib.scm(sch_1):page42_i29@pure_quanta.q_res(chips)',
 P_PATH='@scm_lib.scm(sch_1):page42_i29@pure_quanta.q_res(chips)',
 PATH='I29',
 DRAWING='@SCM_LIB.SCM(SCH_1):PAGE42',
 PHYS_PAGE='42',
 XY='(8500,2650)',
 ROT='0',
 VER='1',
 PACK_TYPE='0402LF',
 LOCATION='R607',
 CDS_LIB='pure_quanta',
 CDS_PART_NAME='Q_RES_0402LF-4.7K,1%,1/16W,CHIA',
 WATTAGE='1/16W',
 TOLERANCE='1%',
 MATERIAL='CHIP',
 VALUE='4.7K',
 PRIM_FILE='W:/<user>/logical/q_res/chips/chips.prt';

PART_NAME
 R608 'Q_RES_0402LF-4.7K,1%,1/16W,CHIA':;

SECTION_NUMBER 1
 '@SCM_LIB.SCM(SCH_1):PAGE42_I27@PURE_QUANTA.Q_RES(CHIPS)':
 C_PATH='@scm_lib.scm(sch_1):page42_i27@pure_quanta.q_res(chips)',
 P_PATH='@scm_lib.scm(sch_1):page42_i27@pure_quanta.q_res(chips)',
 PATH='I27',
 DRAWING='@SCM_LIB.SCM(SCH_1):PAGE42',
 PHYS_PAGE='42',
 XY='(8500,2500)',
 ROT='0',
 VER='1',
 PACK_TYPE='0402LF',
 LOCATION='R608',
 CDS_LIB='pure_quanta',
 CDS_PART_NAME='Q_RES_0402LF-4.7K,1%,1/16W,CHIA',
 WATTAGE='1/16W',
 TOLERANCE='1%',
 MATERIAL='CHIP',
 VALUE='4.7K',
 PRIM_FILE='W:/<user>/logical/q_res/chips/chips.prt';

PART_NAME
 R610 'Q_RES_0402LF-2.2K,5%,1/16W,CHIA':;

SECTION_NUMBER 1
 '@SCM_LIB.SCM(SCH_1):PAGE27_I237@PURE_QUANTA.Q_RES(CHIPS)':
 C_PATH='@scm_lib.scm(sch_1):page27_i237@pure_quanta.q_res(chips)',
 P_PATH='@scm_lib.scm(sch_1):page27_i237@pure_quanta.q_res(chips)',
 PATH='I237',
 DRAWING='@SCM_LIB.SCM(SCH_1):PAGE27',
 PHYS_PAGE='27',
 XY='(-3625,1975)',
 ROT='0',
 VER='1',
 PACK_TYPE='0402LF',
 LOCATION='R610',
 CDS_LIB='pure_quanta',
 CDS_PART_NAME='Q_RES_0402LF-2.2K,5%,1/16W,CHIA',
 WATTAGE='1/16W',
 TOLERANCE='5%',
 MATERIAL='CHIP',
 VALUE='2.2K',
 PRIM_FILE='W:/<user>/logical/q_res/chips/chips.prt';

PART_NAME
 R614 'Q_RES_0402LF-100K,1%,1/16W,CHIA':;

SECTION_NUMBER 1
 '@SCM_LIB.SCM(SCH_1):PAGE22_I35@PURE_QUANTA.Q_RES(CHIPS)':
 C_PATH='@scm_lib.scm(sch_1):page22_i35@pure_quanta.q_res(chips)',
 P_PATH='@scm_lib.scm(sch_1):page22_i35@pure_quanta.q_res(chips)',
 PATH='I35',
 DRAWING='@SCM_LIB.SCM(SCH_1):PAGE22',
 PHYS_PAGE='22',
 XY='(-2000,725)',
 ROT='0',
 VER='2',
 PACK_TYPE='0402LF',
 LOCATION='R614',
 CDS_LIB='pure_quanta',
 CDS_PART_NAME='Q_RES_0402LF-100K,1%,1/16W,CHIA',
 WATTAGE='1/16W',
 TOLERANCE='1%',
 MATERIAL='CHIP',
 VALUE='100K',
 PRIM_FILE='W:/<user>/logical/q_res/chips/chips.prt';

PART_NAME
 R615 'Q_RES_0402LF-4.7K,1%,1/16W,EMPB':;

SECTION_NUMBER 1
 '@SCM_LIB.SCM(SCH_1):PAGE48_I33@PURE_QUANTA.Q_RES(CHIPS)':
 C_PATH='@scm_lib.scm(sch_1):page48_i33@pure_quanta.q_res(chips)',
 P_PATH='@scm_lib.scm(sch_1):page48_i33@pure_quanta.q_res(chips)',
 PATH='I33',
 DRAWING='@SCM_LIB.SCM(SCH_1):PAGE48',
 PHYS_PAGE='48',
 XY='(-2225,3850)',
 ROT='0',
 VER='2',
 PACK_TYPE='0402LF',
 CDS_LIB='pure_quanta',
 CDS_PART_NAME='Q_RES_0402LF-4.7K,1%,1/16W,EMPB',
 WATTAGE='1/16W',
 TOLERANCE='1%',
 MATERIAL='EMPTY',
 VALUE='4.7K',
 PRIM_FILE='W:/<user>/logical/q_res/chips/chips.prt';

PART_NAME
 R616 'Q_RES_0402LF-0,5%,1/16W,CHIP,CA':;

SECTION_NUMBER 1
 '@SCM_LIB.SCM(SCH_1):PAGE48_I40@PURE_QUANTA.Q_RES(CHIPS)':
 C_PATH='@scm_lib.scm(sch_1):page48_i40@pure_quanta.q_res(chips)',
 P_PATH='@scm_lib.scm(sch_1):page48_i40@pure_quanta.q_res(chips)',
 PATH='I40',
 DRAWING='@SCM_LIB.SCM(SCH_1):PAGE48',
 PHYS_PAGE='48',
 XY='(-1150,2000)',
 ROT='6',
 VER='1',
 PACK_TYPE='0402LF',
 LOCATION='R616',
 CDS_LIB='pure_quanta',
 CDS_PART_NAME='Q_RES_0402LF-0,5%,1/16W,CHIP,CA',
 WATTAGE='1/16W',
 TOLERANCE='5%',
 MATERIAL='CHIP',
 VALUE='0',
 PRIM_FILE='W:/<user>/logical/q_res/chips/chips.prt';

PART_NAME
 R618 'Q_RES_0402LF-0,5%,1/16W,CHIP,CA':;

SECTION_NUMBER 1
 '@SCM_LIB.SCM(SCH_1):PAGE31_I76@PURE_QUANTA.Q_RES(CHIPS)':
 C_PATH='@scm_lib.scm(sch_1):page31_i76@pure_quanta.q_res(chips)',
 P_PATH='@scm_lib.scm(sch_1):page31_i76@pure_quanta.q_res(chips)',
 PATH='I76',
 DRAWING='@SCM_LIB.SCM(SCH_1):PAGE31',
 PHYS_PAGE='31',
 XY='(-6075,1225)',
 ROT='0',
 VER='1',
 PACK_TYPE='0402LF',
 LOCATION='R618',
 CDS_LIB='pure_quanta',
 CDS_PART_NAME='Q_RES_0402LF-0,5%,1/16W,CHIP,CA',
 WATTAGE='1/16W',
 TOLERANCE='5%',
 MATERIAL='CHIP',
 VALUE='0',
 PRIM_FILE='W:/<user>/logical/q_res/chips/chips.prt';

PART_NAME
 R619 'Q_RES_0402LF-8.2K,5%,1/16W,EMPA':;

SECTION_NUMBER 1
 '@SCM_LIB.SCM(SCH_1):PAGE49_I26@PURE_QUANTA.Q_RES(CHIPS)':
 C_PATH='@scm_lib.scm(sch_1):page49_i26@pure_quanta.q_res(chips)',
 P_PATH='@scm_lib.scm(sch_1):page49_i26@pure_quanta.q_res(chips)',
 PATH='I26',
 DRAWING='@SCM_LIB.SCM(SCH_1):PAGE49',
 PHYS_PAGE='49',
 XY='(-6350,1025)',
 ROT='0',
 VER='2',
 PACK_TYPE='0402LF',
 LOCATION='R619',
 CDS_LIB='pure_quanta',
 CDS_PART_NAME='Q_RES_0402LF-8.2K,5%,1/16W,EMPA',
 WATTAGE='1/16W',
 TOLERANCE='5%',
 MATERIAL='EMPTY',
 VALUE='8.2K',
 PRIM_FILE='W:/<user>/logical/q_res/chips/chips.prt';

PART_NAME
 R620 'Q_RES_0402LF-100K,1%,1/16W,CHIA':;

SECTION_NUMBER 1
 '@SCM_LIB.SCM(SCH_1):PAGE48_I39@PURE_QUANTA.Q_RES(CHIPS)':
 C_PATH='@scm_lib.scm(sch_1):page48_i39@pure_quanta.q_res(chips)',
 P_PATH='@scm_lib.scm(sch_1):page48_i39@pure_quanta.q_res(chips)',
 PATH='I39',
 DRAWING='@SCM_LIB.SCM(SCH_1):PAGE48',
 PHYS_PAGE='48',
 XY='(-375,1750)',
 ROT='0',
 VER='2',
 PACK_TYPE='0402LF',
 LOCATION='R620',
 CDS_LIB='pure_quanta',
 CDS_PART_NAME='Q_RES_0402LF-100K,1%,1/16W,CHIA',
 WATTAGE='1/16W',
 TOLERANCE='1%',
 MATERIAL='CHIP',
 VALUE='100K',
 PRIM_FILE='W:/<user>/logical/q_res/chips/chips.prt';

PART_NAME
 R621 'Q_RES_0402LF-4.7K,1%,1/16W,CHIA':;

SECTION_NUMBER 1
 '@SCM_LIB.SCM(SCH_1):PAGE42_I13@PURE_QUANTA.Q_RES(CHIPS)':
 C_PATH='@scm_lib.scm(sch_1):page42_i13@pure_quanta.q_res(chips)',
 P_PATH='@scm_lib.scm(sch_1):page42_i13@pure_quanta.q_res(chips)',
 PATH='I13',
 DRAWING='@SCM_LIB.SCM(SCH_1):PAGE42',
 PHYS_PAGE='42',
 XY='(8500,1450)',
 ROT='0',
 VER='1',
 PACK_TYPE='0402LF',
 LOCATION='R621',
 CDS_LIB='pure_quanta',
 CDS_PART_NAME='Q_RES_0402LF-4.7K,1%,1/16W,CHIA',
 WATTAGE='1/16W',
 TOLERANCE='1%',
 MATERIAL='CHIP',
 VALUE='4.7K',
 PRIM_FILE='W:/<user>/logical/q_res/chips/chips.prt';

PART_NAME
 R623 'Q_RES_0402LF-4.7K,1%,1/16W,EMPA':;

SECTION_NUMBER 1
 '@SCM_LIB.SCM(SCH_1):PAGE15_I152@PURE_QUANTA.Q_RES(CHIPS)':
 C_PATH='@scm_lib.scm(sch_1):page15_i152@pure_quanta.q_res(chips)',
 P_PATH='@scm_lib.scm(sch_1):page15_i152@pure_quanta.q_res(chips)',
 PATH='I152',
 DRAWING='@SCM_LIB.SCM(SCH_1):PAGE15',
 PHYS_PAGE='15',
 XY='(-2900,4275)',
 ROT='0',
 VER='2',
 PACK_TYPE='0402LF',
 LOCATION='R623',
 CDS_LIB='pure_quanta',
 CDS_PART_NAME='Q_RES_0402LF-4.7K,1%,1/16W,EMPA',
 WATTAGE='1/16W',
 TOLERANCE='1%',
 MATERIAL='EMPTY',
 VALUE='4.7K',
 PRIM_FILE='W:/<user>/logical/q_res/chips/chips.prt';

PART_NAME
 R624 'Q_RES_0402LF-4.7K,1%,1/16W,CHIA':;

SECTION_NUMBER 1
 '@SCM_LIB.SCM(SCH_1):PAGE48_I48@PURE_QUANTA.Q_RES(CHIPS)':
 C_PATH='@scm_lib.scm(sch_1):page48_i48@pure_quanta.q_res(chips)',
 P_PATH='@scm_lib.scm(sch_1):page48_i48@pure_quanta.q_res(chips)',
 PATH='I48',
 DRAWING='@SCM_LIB.SCM(SCH_1):PAGE48',
 PHYS_PAGE='48',
 XY='(-575,800)',
 ROT='0',
 VER='2',
 PACK_TYPE='0402LF',
 LOCATION='R624',
 CDS_LIB='pure_quanta',
 CDS_PART_NAME='Q_RES_0402LF-4.7K,1%,1/16W,CHIA',
 WATTAGE='1/16W',
 TOLERANCE='1%',
 MATERIAL='CHIP',
 VALUE='4.7K',
 PRIM_FILE='W:/<user>/logical/q_res/chips/chips.prt';

PART_NAME
 R625 'Q_RES_0402LF-4.7K,1%,1/16W,CHIA':;

SECTION_NUMBER 1
 '@SCM_LIB.SCM(SCH_1):PAGE34_I17@PURE_QUANTA.Q_RES(CHIPS)':
 C_PATH='@scm_lib.scm(sch_1):page34_i17@pure_quanta.q_res(chips)',
 P_PATH='@scm_lib.scm(sch_1):page34_i17@pure_quanta.q_res(chips)',
 PATH='I17',
 DRAWING='@SCM_LIB.SCM(SCH_1):PAGE34',
 PHYS_PAGE='34',
 XY='(-8750,6150)',
 ROT='2',
 VER='2',
 PACK_TYPE='0402LF',
 LOCATION='R625',
 CDS_LIB='pure_quanta',
 CDS_PART_NAME='Q_RES_0402LF-4.7K,1%,1/16W,CHIA',
 WATTAGE='1/16W',
 TOLERANCE='1%',
 MATERIAL='CHIP',
 VALUE='4.7K',
 PRIM_FILE='W:/<user>/logical/q_res/chips/chips.prt';

PART_NAME
 R626 'Q_RES_0402LF-0,5%,1/16W,CHIP,CA':;

SECTION_NUMBER 1
 '@SCM_LIB.SCM(SCH_1):PAGE28_I161@PURE_QUANTA.Q_RES(CHIPS)':
 C_PATH='@scm_lib.scm(sch_1):page28_i161@pure_quanta.q_res(chips)',
 P_PATH='@scm_lib.scm(sch_1):page28_i161@pure_quanta.q_res(chips)',
 PATH='I161',
 DRAWING='@SCM_LIB.SCM(SCH_1):PAGE28',
 PHYS_PAGE='28',
 XY='(3800,300)',
 ROT='2',
 VER='1',
 PACK_TYPE='0402LF',
 LOCATION='R626',
 CDS_LIB='pure_quanta',
 CDS_PART_NAME='Q_RES_0402LF-0,5%,1/16W,CHIP,CA',
 WATTAGE='1/16W',
 TOLERANCE='5%',
 MATERIAL='CHIP',
 VALUE='0',
 PRIM_FILE='W:/<user>/logical/q_res/chips/chips.prt';

PART_NAME
 R627 'Q_RES_0402LF-4.7K,1%,1/16W,CHIA':;

SECTION_NUMBER 1
 '@SCM_LIB.SCM(SCH_1):PAGE42_I7@PURE_QUANTA.Q_RES(CHIPS)':
 C_PATH='@scm_lib.scm(sch_1):page42_i7@pure_quanta.q_res(chips)',
 P_PATH='@scm_lib.scm(sch_1):page42_i7@pure_quanta.q_res(chips)',
 PATH='I7',
 DRAWING='@SCM_LIB.SCM(SCH_1):PAGE42',
 PHYS_PAGE='42',
 XY='(8500,625)',
 ROT='0',
 VER='1',
 PACK_TYPE='0402LF',
 LOCATION='R627',
 CDS_LIB='pure_quanta',
 CDS_PART_NAME='Q_RES_0402LF-4.7K,1%,1/16W,CHIA',
 WATTAGE='1/16W',
 TOLERANCE='1%',
 MATERIAL='CHIP',
 VALUE='4.7K',
 PRIM_FILE='W:/<user>/logical/q_res/chips/chips.prt';

PART_NAME
 R628 'Q_RES_0402LF-100,1%,1/16W,CHIPA':;

SECTION_NUMBER 1
 '@SCM_LIB.SCM(SCH_1):PAGE31_I77@PURE_QUANTA.Q_RES(CHIPS)':
 C_PATH='@scm_lib.scm(sch_1):page31_i77@pure_quanta.q_res(chips)',
 P_PATH='@scm_lib.scm(sch_1):page31_i77@pure_quanta.q_res(chips)',
 PATH='I77',
 DRAWING='@SCM_LIB.SCM(SCH_1):PAGE31',
 PHYS_PAGE='31',
 XY='(-6075,1325)',
 ROT='0',
 VER='1',
 PACK_TYPE='0402LF',
 LOCATION='R628',
 CDS_LIB='pure_quanta',
 CDS_PART_NAME='Q_RES_0402LF-100,1%,1/16W,CHIPA',
 WATTAGE='1/16W',
 TOLERANCE='1%',
 MATERIAL='CHIP',
 VALUE='100',
 PRIM_FILE='W:/<user>/logical/q_res/chips/chips.prt';

PART_NAME
 R629 'Q_RES_0402LF-0,5%,1/16W,CHIP,CA':;

SECTION_NUMBER 1
 '@SCM_LIB.SCM(SCH_1):PAGE31_I78@PURE_QUANTA.Q_RES(CHIPS)':
 C_PATH='@scm_lib.scm(sch_1):page31_i78@pure_quanta.q_res(chips)',
 P_PATH='@scm_lib.scm(sch_1):page31_i78@pure_quanta.q_res(chips)',
 PATH='I78',
 DRAWING='@SCM_LIB.SCM(SCH_1):PAGE31',
 PHYS_PAGE='31',
 XY='(-2550,2225)',
 ROT='0',
 VER='1',
 PACK_TYPE='0402LF',
 LOCATION='R629',
 CDS_LIB='pure_quanta',
 CDS_PART_NAME='Q_RES_0402LF-0,5%,1/16W,CHIP,CA',
 WATTAGE='1/16W',
 TOLERANCE='5%',
 MATERIAL='CHIP',
 VALUE='0',
 PRIM_FILE='W:/<user>/logical/q_res/chips/chips.prt';

PART_NAME
 R630 'Q_RES_0402LF-4.7K,1%,1/16W,CHIA':;

SECTION_NUMBER 1
 '@SCM_LIB.SCM(SCH_1):PAGE31_I79@PURE_QUANTA.Q_RES(CHIPS)':
 C_PATH='@scm_lib.scm(sch_1):page31_i79@pure_quanta.q_res(chips)',
 P_PATH='@scm_lib.scm(sch_1):page31_i79@pure_quanta.q_res(chips)',
 PATH='I79',
 DRAWING='@SCM_LIB.SCM(SCH_1):PAGE31',
 PHYS_PAGE='31',
 XY='(-2175,2325)',
 ROT='0',
 VER='2',
 PACK_TYPE='0402LF',
 LOCATION='R630',
 CDS_LIB='pure_quanta',
 CDS_PART_NAME='Q_RES_0402LF-4.7K,1%,1/16W,CHIA',
 WATTAGE='1/16W',
 TOLERANCE='1%',
 MATERIAL='CHIP',
 VALUE='4.7K',
 PRIM_FILE='W:/<user>/logical/q_res/chips/chips.prt';

PART_NAME
 R631 'Q_RES_0402LF-16.9K,1%,1/16W,CHA':;

SECTION_NUMBER 1
 '@SCM_LIB.SCM(SCH_1):PAGE51_I62@PURE_QUANTA.Q_RES(CHIPS)':
 C_PATH='@scm_lib.scm(sch_1):page51_i62@pure_quanta.q_res(chips)',
 P_PATH='@scm_lib.scm(sch_1):page51_i62@pure_quanta.q_res(chips)',
 PATH='I62',
 DRAWING='@SCM_LIB.SCM(SCH_1):PAGE51',
 PHYS_PAGE='51',
 XY='(325,3600)',
 ROT='0',
 VER='2',
 PACK_TYPE='0402LF',
 CDS_LIB='pure_quanta',
 CDS_PART_NAME='Q_RES_0402LF-16.9K,1%,1/16W,CHA',
 WATTAGE='1/16W',
 TOLERANCE='1%',
 MATERIAL='CHIP',
 VALUE='16.9K',
 PRIM_FILE='W:/<user>/logical/q_res/chips/chips.prt';

PART_NAME
 R632 'Q_RES_0402LF-0,5%,1/16W,CHIP,CA':;

SECTION_NUMBER 1
 '@SCM_LIB.SCM(SCH_1):PAGE28_I153@PURE_QUANTA.Q_RES(CHIPS)':
 C_PATH='@scm_lib.scm(sch_1):page28_i153@pure_quanta.q_res(chips)',
 P_PATH='@scm_lib.scm(sch_1):page28_i153@pure_quanta.q_res(chips)',
 PATH='I153',
 DRAWING='@SCM_LIB.SCM(SCH_1):PAGE28',
 PHYS_PAGE='28',
 XY='(-2400,-1325)',
 ROT='0',
 VER='1',
 PACK_TYPE='0402LF',
 LOCATION='R632',
 CDS_LIB='pure_quanta',
 CDS_PART_NAME='Q_RES_0402LF-0,5%,1/16W,CHIP,CA',
 WATTAGE='1/16W',
 TOLERANCE='5%',
 MATERIAL='CHIP',
 VALUE='0',
 PRIM_FILE='W:/<user>/logical/q_res/chips/chips.prt';

PART_NAME
 R633 'Q_RES_0402LF-1K,1%,1/16W,EMPTYA':;

SECTION_NUMBER 1
 '@SCM_LIB.SCM(SCH_1):PAGE22_I81@PURE_QUANTA.Q_RES(CHIPS)':
 C_PATH='@scm_lib.scm(sch_1):page22_i81@pure_quanta.q_res(chips)',
 P_PATH='@scm_lib.scm(sch_1):page22_i81@pure_quanta.q_res(chips)',
 PATH='I81',
 DRAWING='@SCM_LIB.SCM(SCH_1):PAGE22',
 SEC_TYPE='0402LF',
 PHYS_PAGE='22',
 XY='(-1725,3050)',
 ROT='0',
 VER='2',
 PACK_TYPE='0402LF',
 LOCATION='R633',
 SEC='1',
 CDS_LIB='pure_quanta',
 CDS_PART_NAME='Q_RES_0402LF-1K,1%,1/16W,EMPTYA',
 WATTAGE='1/16W',
 TOLERANCE='1%',
 MATERIAL='EMPTY',
 VALUE='1K',
 PRIM_FILE='W:/<user>/logical/q_res/chips/chips.prt';

PART_NAME
 R634 'Q_RES_0402LF-0,5%,1/16W,CHIP,CA':;

SECTION_NUMBER 1
 '@SCM_LIB.SCM(SCH_1):PAGE34_I37@PURE_QUANTA.Q_RES(CHIPS)':
 C_PATH='@scm_lib.scm(sch_1):page34_i37@pure_quanta.q_res(chips)',
 P_PATH='@scm_lib.scm(sch_1):page34_i37@pure_quanta.q_res(chips)',
 PATH='I37',
 DRAWING='@SCM_LIB.SCM(SCH_1):PAGE34',
 PHYS_PAGE='34',
 XY='(-7000,4750)',
 ROT='0',
 VER='1',
 PACK_TYPE='0402LF',
 LOCATION='R634',
 CDS_LIB='pure_quanta',
 CDS_PART_NAME='Q_RES_0402LF-0,5%,1/16W,CHIP,CA',
 WATTAGE='1/16W',
 TOLERANCE='5%',
 MATERIAL='CHIP',
 VALUE='0',
 PRIM_FILE='W:/<user>/logical/q_res/chips/chips.prt';

PART_NAME
 R635 'Q_RES_0402LF-33.2,1%,1/16W,CHIA':;

SECTION_NUMBER 1
 '@SCM_LIB.SCM(SCH_1):PAGE36_I80@PURE_QUANTA.Q_RES(CHIPS)':
 C_PATH='@scm_lib.scm(sch_1):page36_i80@pure_quanta.q_res(chips)',
 P_PATH='@scm_lib.scm(sch_1):page36_i80@pure_quanta.q_res(chips)',
 PATH='I80',
 DRAWING='@SCM_LIB.SCM(SCH_1):PAGE36',
 PHYS_PAGE='36',
 XY='(-7250,4825)',
 ROT='0',
 VER='1',
 PACK_TYPE='0402LF',
 LOCATION='R635',
 CDS_LIB='pure_quanta',
 CDS_PART_NAME='Q_RES_0402LF-33.2,1%,1/16W,CHIA',
 WATTAGE='1/16W',
 TOLERANCE='1%',
 MATERIAL='CHIP',
 VALUE='33.2',
 PRIM_FILE='W:/<user>/logical/q_res/chips/chips.prt';

PART_NAME
 R636 'Q_RES_0402LF-0,5%,1/16W,CHIP,CA':;

SECTION_NUMBER 1
 '@SCM_LIB.SCM(SCH_1):PAGE22_I10@PURE_QUANTA.Q_RES(CHIPS)':
 C_PATH='@scm_lib.scm(sch_1):page22_i10@pure_quanta.q_res(chips)',
 P_PATH='@scm_lib.scm(sch_1):page22_i10@pure_quanta.q_res(chips)',
 PATH='I10',
 DRAWING='@SCM_LIB.SCM(SCH_1):PAGE22',
 PHYS_PAGE='22',
 XY='(-2025,4200)',
 ROT='0',
 VER='1',
 PACK_TYPE='0402LF',
 LOCATION='R636',
 CDS_LIB='pure_quanta',
 CDS_PART_NAME='Q_RES_0402LF-0,5%,1/16W,CHIP,CA',
 WATTAGE='1/16W',
 TOLERANCE='5%',
 MATERIAL='CHIP',
 VALUE='0',
 PRIM_FILE='W:/<user>/logical/q_res/chips/chips.prt';

PART_NAME
 R637 'Q_RES_0402LF-0,5%,1/16W,CHIP,CA':;

SECTION_NUMBER 1
 '@SCM_LIB.SCM(SCH_1):PAGE13_I337@PURE_QUANTA.Q_RES(CHIPS)':
 C_PATH='@scm_lib.scm(sch_1):page13_i337@pure_quanta.q_res(chips)',
 P_PATH='@scm_lib.scm(sch_1):page13_i337@pure_quanta.q_res(chips)',
 PATH='I337',
 DRAWING='@SCM_LIB.SCM(SCH_1):PAGE13',
 PHYS_PAGE='13',
 XY='(3650,3125)',
 ROT='0',
 VER='1',
 PACK_TYPE='0402LF',
 LOCATION='R637',
 CDS_LIB='pure_quanta',
 CDS_PART_NAME='Q_RES_0402LF-0,5%,1/16W,CHIP,CA',
 WATTAGE='1/16W',
 TOLERANCE='5%',
 MATERIAL='CHIP',
 VALUE='0',
 PRIM_FILE='W:/<user>/logical/q_res/chips/chips.prt';

PART_NAME
 R638 'Q_RES_0402LF-33.2,1%,1/16W,CHIA':;

SECTION_NUMBER 1
 '@SCM_LIB.SCM(SCH_1):PAGE35_I143@PURE_QUANTA.Q_RES(CHIPS)':
 C_PATH='@scm_lib.scm(sch_1):page35_i143@pure_quanta.q_res(chips)',
 P_PATH='@scm_lib.scm(sch_1):page35_i143@pure_quanta.q_res(chips)',
 PATH='I143',
 DRAWING='@SCM_LIB.SCM(SCH_1):PAGE35',
 PHYS_PAGE='35',
 XY='(-1800,4000)',
 ROT='0',
 VER='1',
 PACK_TYPE='0402LF',
 LOCATION='R638',
 CDS_LIB='pure_quanta',
 CDS_PART_NAME='Q_RES_0402LF-33.2,1%,1/16W,CHIA',
 WATTAGE='1/16W',
 TOLERANCE='1%',
 MATERIAL='CHIP',
 VALUE='33.2',
 PRIM_FILE='W:/<user>/logical/q_res/chips/chips.prt';

PART_NAME
 R639 'Q_RES_0402LF-33.2,1%,1/16W,CHIA':;

SECTION_NUMBER 1
 '@SCM_LIB.SCM(SCH_1):PAGE32_I88@PURE_QUANTA.Q_RES(CHIPS)':
 C_PATH='@scm_lib.scm(sch_1):page32_i88@pure_quanta.q_res(chips)',
 P_PATH='@scm_lib.scm(sch_1):page32_i88@pure_quanta.q_res(chips)',
 PATH='I88',
 DRAWING='@SCM_LIB.SCM(SCH_1):PAGE32',
 PHYS_PAGE='32',
 XY='(-425,1725)',
 ROT='0',
 VER='1',
 PACK_TYPE='0402LF',
 LOCATION='R639',
 CDS_LIB='pure_quanta',
 CDS_PART_NAME='Q_RES_0402LF-33.2,1%,1/16W,CHIA',
 WATTAGE='1/16W',
 TOLERANCE='1%',
 MATERIAL='CHIP',
 VALUE='33.2',
 PRIM_FILE='W:/<user>/logical/q_res/chips/chips.prt';

PART_NAME
 R640 'Q_RES_0402LF-4.7K,1%,1/16W,EMPA':;

SECTION_NUMBER 1
 '@SCM_LIB.SCM(SCH_1):PAGE42_I56@PURE_QUANTA.Q_RES(CHIPS)':
 C_PATH='@scm_lib.scm(sch_1):page42_i56@pure_quanta.q_res(chips)',
 P_PATH='@scm_lib.scm(sch_1):page42_i56@pure_quanta.q_res(chips)',
 PATH='I56',
 DRAWING='@SCM_LIB.SCM(SCH_1):PAGE42',
 PHYS_PAGE='42',
 XY='(8475,300)',
 ROT='0',
 VER='1',
 PACK_TYPE='0402LF',
 LOCATION='R640',
 CDS_LIB='pure_quanta',
 CDS_PART_NAME='Q_RES_0402LF-4.7K,1%,1/16W,EMPA',
 WATTAGE='1/16W',
 TOLERANCE='1%',
 MATERIAL='EMPTY',
 VALUE='4.7K',
 PRIM_FILE='W:/<user>/logical/q_res/chips/chips.prt';

PART_NAME
 R641 'Q_RES_0402LF-4.7K,1%,1/16W,EMPA':;

SECTION_NUMBER 1
 '@SCM_LIB.SCM(SCH_1):PAGE42_I53@PURE_QUANTA.Q_RES(CHIPS)':
 C_PATH='@scm_lib.scm(sch_1):page42_i53@pure_quanta.q_res(chips)',
 P_PATH='@scm_lib.scm(sch_1):page42_i53@pure_quanta.q_res(chips)',
 PATH='I53',
 DRAWING='@SCM_LIB.SCM(SCH_1):PAGE42',
 PHYS_PAGE='42',
 XY='(11950,4200)',
 ROT='0',
 VER='1',
 PACK_TYPE='0402LF',
 LOCATION='R641',
 CDS_LIB='pure_quanta',
 CDS_PART_NAME='Q_RES_0402LF-4.7K,1%,1/16W,EMPA',
 WATTAGE='1/16W',
 TOLERANCE='1%',
 MATERIAL='EMPTY',
 VALUE='4.7K',
 PRIM_FILE='W:/<user>/logical/q_res/chips/chips.prt';

PART_NAME
 R642 'Q_RES_0402LF-100K,1%,1/16W,CHIA':;

SECTION_NUMBER 1
 '@SCM_LIB.SCM(SCH_1):PAGE42_I58@PURE_QUANTA.Q_RES(CHIPS)':
 C_PATH='@scm_lib.scm(sch_1):page42_i58@pure_quanta.q_res(chips)',
 P_PATH='@scm_lib.scm(sch_1):page42_i58@pure_quanta.q_res(chips)',
 PATH='I58',
 DRAWING='@SCM_LIB.SCM(SCH_1):PAGE42',
 PHYS_PAGE='42',
 XY='(8475,75)',
 ROT='0',
 VER='1',
 PACK_TYPE='0402LF',
 LOCATION='R642',
 CDS_LIB='pure_quanta',
 CDS_PART_NAME='Q_RES_0402LF-100K,1%,1/16W,CHIA',
 WATTAGE='1/16W',
 TOLERANCE='1%',
 MATERIAL='CHIP',
 VALUE='100K',
 PRIM_FILE='W:/<user>/logical/q_res/chips/chips.prt';

PART_NAME
 R643 'Q_RES_0402LF-33.2,1%,1/16W,CHIA':;

SECTION_NUMBER 1
 '@SCM_LIB.SCM(SCH_1):PAGE13_I344@PURE_QUANTA.Q_RES(CHIPS)':
 C_PATH='@scm_lib.scm(sch_1):page13_i344@pure_quanta.q_res(chips)',
 P_PATH='@scm_lib.scm(sch_1):page13_i344@pure_quanta.q_res(chips)',
 PATH='I344',
 DRAWING='@SCM_LIB.SCM(SCH_1):PAGE13',
 PHYS_PAGE='13',
 XY='(-1825,3675)',
 ROT='0',
 VER='1',
 PACK_TYPE='0402LF',
 LOCATION='R643',
 CDS_LIB='pure_quanta',
 CDS_PART_NAME='Q_RES_0402LF-33.2,1%,1/16W,CHIA',
 WATTAGE='1/16W',
 TOLERANCE='1%',
 MATERIAL='CHIP',
 VALUE='33.2',
 PRIM_FILE='W:/<user>/logical/q_res/chips/chips.prt';

PART_NAME
 R644 'Q_RES_0402LF-33.2,1%,1/16W,CHIA':;

SECTION_NUMBER 1
 '@SCM_LIB.SCM(SCH_1):PAGE15_I345@PURE_QUANTA.Q_RES(CHIPS)':
 C_PATH='@scm_lib.scm(sch_1):page15_i345@pure_quanta.q_res(chips)',
 P_PATH='@scm_lib.scm(sch_1):page15_i345@pure_quanta.q_res(chips)',
 PATH='I345',
 DRAWING='@SCM_LIB.SCM(SCH_1):PAGE15',
 PHYS_PAGE='15',
 XY='(4025,3725)',
 ROT='2',
 VER='1',
 PACK_TYPE='0402LF',
 LOCATION='R644',
 CDS_LIB='pure_quanta',
 CDS_PART_NAME='Q_RES_0402LF-33.2,1%,1/16W,CHIA',
 WATTAGE='1/16W',
 TOLERANCE='1%',
 MATERIAL='CHIP',
 VALUE='33.2',
 PRIM_FILE='W:/<user>/logical/q_res/chips/chips.prt';

PART_NAME
 R645 'Q_RES_0603LF-0,5%,1/10W,EMPTY,A':;

SECTION_NUMBER 1
 '@SCM_LIB.SCM(SCH_1):PAGE17_I278@PURE_QUANTA.Q_RES(CHIPS)':
 C_PATH='@scm_lib.scm(sch_1):page17_i278@pure_quanta.q_res(chips)',
 P_PATH='@scm_lib.scm(sch_1):page17_i278@pure_quanta.q_res(chips)',
 PATH='I278',
 DRAWING='@SCM_LIB.SCM(SCH_1):PAGE17',
 PHYS_PAGE='17',
 XY='(4350,800)',
 ROT='0',
 VER='2',
 PACK_TYPE='0603LF',
 LOCATION='R645',
 CDS_LIB='pure_quanta',
 CDS_PART_NAME='Q_RES_0603LF-0,5%,1/10W,EMPTY,A',
 WATTAGE='1/10W',
 TOLERANCE='5%',
 MATERIAL='EMPTY',
 VALUE='0',
 PRIM_FILE='W:/<user>/logical/q_res/chips/chips.prt';

PART_NAME
 R646 'Q_RES_0603LF-0,5%,1/10W,EMPTY,A':;

SECTION_NUMBER 1
 '@SCM_LIB.SCM(SCH_1):PAGE17_I279@PURE_QUANTA.Q_RES(CHIPS)':
 C_PATH='@scm_lib.scm(sch_1):page17_i279@pure_quanta.q_res(chips)',
 P_PATH='@scm_lib.scm(sch_1):page17_i279@pure_quanta.q_res(chips)',
 PATH='I279',
 DRAWING='@SCM_LIB.SCM(SCH_1):PAGE17',
 PHYS_PAGE='17',
 XY='(4350,0)',
 ROT='0',
 VER='2',
 PACK_TYPE='0603LF',
 LOCATION='R646',
 CDS_LIB='pure_quanta',
 CDS_PART_NAME='Q_RES_0603LF-0,5%,1/10W,EMPTY,A',
 WATTAGE='1/10W',
 TOLERANCE='5%',
 MATERIAL='EMPTY',
 VALUE='0',
 PRIM_FILE='W:/<user>/logical/q_res/chips/chips.prt';

PART_NAME
 R647 'Q_RES_0402LF-33.2,1%,1/16W,EMPA':;

SECTION_NUMBER 1
 '@SCM_LIB.SCM(SCH_1):PAGE21_I45@PURE_QUANTA.Q_RES(CHIPS)':
 C_PATH='@scm_lib.scm(sch_1):page21_i45@pure_quanta.q_res(chips)',
 P_PATH='@scm_lib.scm(sch_1):page21_i45@pure_quanta.q_res(chips)',
 PATH='I45',
 DRAWING='@SCM_LIB.SCM(SCH_1):PAGE21',
 PHYS_PAGE='21',
 XY='(3250,2000)',
 ROT='0',
 VER='1',
 PACK_TYPE='0402LF',
 LOCATION='R647',
 CDS_LIB='pure_quanta',
 CDS_PART_NAME='Q_RES_0402LF-33.2,1%,1/16W,EMPA',
 WATTAGE='1/16W',
 TOLERANCE='1%',
 MATERIAL='EMPTY',
 VALUE='33.2',
 PRIM_FILE='W:/<user>/logical/q_res/chips/chips.prt';

PART_NAME
 R648 'Q_RES_0402LF-33.2,1%,1/16W,EMPA':;

SECTION_NUMBER 1
 '@SCM_LIB.SCM(SCH_1):PAGE21_I43@PURE_QUANTA.Q_RES(CHIPS)':
 C_PATH='@scm_lib.scm(sch_1):page21_i43@pure_quanta.q_res(chips)',
 P_PATH='@scm_lib.scm(sch_1):page21_i43@pure_quanta.q_res(chips)',
 PATH='I43',
 DRAWING='@SCM_LIB.SCM(SCH_1):PAGE21',
 PHYS_PAGE='21',
 XY='(3250,1950)',
 ROT='0',
 VER='1',
 PACK_TYPE='0402LF',
 LOCATION='R648',
 CDS_LIB='pure_quanta',
 CDS_PART_NAME='Q_RES_0402LF-33.2,1%,1/16W,EMPA',
 WATTAGE='1/16W',
 TOLERANCE='1%',
 MATERIAL='EMPTY',
 VALUE='33.2',
 PRIM_FILE='W:/<user>/logical/q_res/chips/chips.prt';

PART_NAME
 R649 'Q_RES_0402LF-33.2,1%,1/16W,EMPA':;

SECTION_NUMBER 1
 '@SCM_LIB.SCM(SCH_1):PAGE21_I42@PURE_QUANTA.Q_RES(CHIPS)':
 C_PATH='@scm_lib.scm(sch_1):page21_i42@pure_quanta.q_res(chips)',
 P_PATH='@scm_lib.scm(sch_1):page21_i42@pure_quanta.q_res(chips)',
 PATH='I42',
 DRAWING='@SCM_LIB.SCM(SCH_1):PAGE21',
 PHYS_PAGE='21',
 XY='(3250,1850)',
 ROT='0',
 VER='1',
 PACK_TYPE='0402LF',
 LOCATION='R649',
 CDS_LIB='pure_quanta',
 CDS_PART_NAME='Q_RES_0402LF-33.2,1%,1/16W,EMPA',
 WATTAGE='1/16W',
 TOLERANCE='1%',
 MATERIAL='EMPTY',
 VALUE='33.2',
 PRIM_FILE='W:/<user>/logical/q_res/chips/chips.prt';

PART_NAME
 R650 'Q_RES_0402LF-33.2,1%,1/16W,EMPA':;

SECTION_NUMBER 1
 '@SCM_LIB.SCM(SCH_1):PAGE21_I99@PURE_QUANTA.Q_RES(CHIPS)':
 C_PATH='@scm_lib.scm(sch_1):page21_i99@pure_quanta.q_res(chips)',
 P_PATH='@scm_lib.scm(sch_1):page21_i99@pure_quanta.q_res(chips)',
 PATH='I99',
 DRAWING='@SCM_LIB.SCM(SCH_1):PAGE21',
 PHYS_PAGE='21',
 XY='(175,2300)',
 ROT='0',
 VER='1',
 PACK_TYPE='0402LF',
 LOCATION='R650',
 CDS_LIB='pure_quanta',
 CDS_PART_NAME='Q_RES_0402LF-33.2,1%,1/16W,EMPA',
 WATTAGE='1/16W',
 TOLERANCE='1%',
 MATERIAL='EMPTY',
 VALUE='33.2',
 PRIM_FILE='W:/<user>/logical/q_res/chips/chips.prt';

PART_NAME
 R651 'Q_RES_0402LF-33.2,1%,1/16W,EMPA':;

SECTION_NUMBER 1
 '@SCM_LIB.SCM(SCH_1):PAGE21_I98@PURE_QUANTA.Q_RES(CHIPS)':
 C_PATH='@scm_lib.scm(sch_1):page21_i98@pure_quanta.q_res(chips)',
 P_PATH='@scm_lib.scm(sch_1):page21_i98@pure_quanta.q_res(chips)',
 PATH='I98',
 DRAWING='@SCM_LIB.SCM(SCH_1):PAGE21',
 PHYS_PAGE='21',
 XY='(175,2250)',
 ROT='0',
 VER='1',
 PACK_TYPE='0402LF',
 LOCATION='R651',
 CDS_LIB='pure_quanta',
 CDS_PART_NAME='Q_RES_0402LF-33.2,1%,1/16W,EMPA',
 WATTAGE='1/16W',
 TOLERANCE='1%',
 MATERIAL='EMPTY',
 VALUE='33.2',
 PRIM_FILE='W:/<user>/logical/q_res/chips/chips.prt';

PART_NAME
 R652 'Q_RES_0402LF-33.2,1%,1/16W,EMPA':;

SECTION_NUMBER 1
 '@SCM_LIB.SCM(SCH_1):PAGE21_I101@PURE_QUANTA.Q_RES(CHIPS)':
 C_PATH='@scm_lib.scm(sch_1):page21_i101@pure_quanta.q_res(chips)',
 P_PATH='@scm_lib.scm(sch_1):page21_i101@pure_quanta.q_res(chips)',
 PATH='I101',
 DRAWING='@SCM_LIB.SCM(SCH_1):PAGE21',
 PHYS_PAGE='21',
 XY='(175,2200)',
 ROT='0',
 VER='1',
 PACK_TYPE='0402LF',
 LOCATION='R652',
 CDS_LIB='pure_quanta',
 CDS_PART_NAME='Q_RES_0402LF-33.2,1%,1/16W,EMPA',
 WATTAGE='1/16W',
 TOLERANCE='1%',
 MATERIAL='EMPTY',
 VALUE='33.2',
 PRIM_FILE='W:/<user>/logical/q_res/chips/chips.prt';

PART_NAME
 R653 'Q_RES_0402LF-33.2,1%,1/16W,EMPA':;

SECTION_NUMBER 1
 '@SCM_LIB.SCM(SCH_1):PAGE21_I100@PURE_QUANTA.Q_RES(CHIPS)':
 C_PATH='@scm_lib.scm(sch_1):page21_i100@pure_quanta.q_res(chips)',
 P_PATH='@scm_lib.scm(sch_1):page21_i100@pure_quanta.q_res(chips)',
 PATH='I100',
 DRAWING='@SCM_LIB.SCM(SCH_1):PAGE21',
 PHYS_PAGE='21',
 XY='(175,2150)',
 ROT='0',
 VER='1',
 PACK_TYPE='0402LF',
 LOCATION='R653',
 CDS_LIB='pure_quanta',
 CDS_PART_NAME='Q_RES_0402LF-33.2,1%,1/16W,EMPA',
 WATTAGE='1/16W',
 TOLERANCE='1%',
 MATERIAL='EMPTY',
 VALUE='33.2',
 PRIM_FILE='W:/<user>/logical/q_res/chips/chips.prt';

PART_NAME
 R654 'Q_RES_0402LF-33.2,1%,1/16W,EMPA':;

SECTION_NUMBER 1
 '@SCM_LIB.SCM(SCH_1):PAGE21_I33@PURE_QUANTA.Q_RES(CHIPS)':
 C_PATH='@scm_lib.scm(sch_1):page21_i33@pure_quanta.q_res(chips)',
 P_PATH='@scm_lib.scm(sch_1):page21_i33@pure_quanta.q_res(chips)',
 PATH='I33',
 DRAWING='@SCM_LIB.SCM(SCH_1):PAGE21',
 PHYS_PAGE='21',
 XY='(3250,2250)',
 ROT='0',
 VER='1',
 PACK_TYPE='0402LF',
 LOCATION='R654',
 CDS_LIB='pure_quanta',
 CDS_PART_NAME='Q_RES_0402LF-33.2,1%,1/16W,EMPA',
 WATTAGE='1/16W',
 TOLERANCE='1%',
 MATERIAL='EMPTY',
 VALUE='33.2',
 PRIM_FILE='W:/<user>/logical/q_res/chips/chips.prt';

PART_NAME
 R655 'Q_RES_0402LF-10K,1%,1/16W,EMPTB':;

SECTION_NUMBER 1
 '@SCM_LIB.SCM(SCH_1):PAGE21_I67@PURE_QUANTA.Q_RES(CHIPS)':
 C_PATH='@scm_lib.scm(sch_1):page21_i67@pure_quanta.q_res(chips)',
 P_PATH='@scm_lib.scm(sch_1):page21_i67@pure_quanta.q_res(chips)',
 PATH='I67',
 DRAWING='@SCM_LIB.SCM(SCH_1):PAGE21',
 PHYS_PAGE='21',
 XY='(-2475,4325)',
 ROT='0',
 VER='1',
 PACK_TYPE='0402LF',
 LOCATION='R655',
 CDS_LIB='pure_quanta',
 CDS_PART_NAME='Q_RES_0402LF-10K,1%,1/16W,EMPTB',
 WATTAGE='1/16W',
 TOLERANCE='1%',
 MATERIAL='EMPTY',
 VALUE='10K',
 PRIM_FILE='W:/<user>/logical/q_res/chips/chips.prt';

PART_NAME
 R656 'Q_RES_0402LF-10K,1%,1/16W,EMPTB':;

SECTION_NUMBER 1
 '@SCM_LIB.SCM(SCH_1):PAGE21_I66@PURE_QUANTA.Q_RES(CHIPS)':
 C_PATH='@scm_lib.scm(sch_1):page21_i66@pure_quanta.q_res(chips)',
 P_PATH='@scm_lib.scm(sch_1):page21_i66@pure_quanta.q_res(chips)',
 PATH='I66',
 DRAWING='@SCM_LIB.SCM(SCH_1):PAGE21',
 PHYS_PAGE='21',
 XY='(-2475,4275)',
 ROT='0',
 VER='1',
 PACK_TYPE='0402LF',
 LOCATION='R656',
 CDS_LIB='pure_quanta',
 CDS_PART_NAME='Q_RES_0402LF-10K,1%,1/16W,EMPTB',
 WATTAGE='1/16W',
 TOLERANCE='1%',
 MATERIAL='EMPTY',
 VALUE='10K',
 PRIM_FILE='W:/<user>/logical/q_res/chips/chips.prt';

PART_NAME
 R657 'Q_RES_0402LF-10K,1%,1/16W,EMPTB':;

SECTION_NUMBER 1
 '@SCM_LIB.SCM(SCH_1):PAGE21_I63@PURE_QUANTA.Q_RES(CHIPS)':
 C_PATH='@scm_lib.scm(sch_1):page21_i63@pure_quanta.q_res(chips)',
 P_PATH='@scm_lib.scm(sch_1):page21_i63@pure_quanta.q_res(chips)',
 PATH='I63',
 DRAWING='@SCM_LIB.SCM(SCH_1):PAGE21',
 PHYS_PAGE='21',
 XY='(-2475,4225)',
 ROT='0',
 VER='1',
 PACK_TYPE='0402LF',
 LOCATION='R657',
 CDS_LIB='pure_quanta',
 CDS_PART_NAME='Q_RES_0402LF-10K,1%,1/16W,EMPTB',
 WATTAGE='1/16W',
 TOLERANCE='1%',
 MATERIAL='EMPTY',
 VALUE='10K',
 PRIM_FILE='W:/<user>/logical/q_res/chips/chips.prt';

PART_NAME
 R658 'Q_RES_0402LF-10K,1%,1/16W,EMPTB':;

SECTION_NUMBER 1
 '@SCM_LIB.SCM(SCH_1):PAGE21_I62@PURE_QUANTA.Q_RES(CHIPS)':
 C_PATH='@scm_lib.scm(sch_1):page21_i62@pure_quanta.q_res(chips)',
 P_PATH='@scm_lib.scm(sch_1):page21_i62@pure_quanta.q_res(chips)',
 PATH='I62',
 DRAWING='@SCM_LIB.SCM(SCH_1):PAGE21',
 PHYS_PAGE='21',
 XY='(-2475,4175)',
 ROT='0',
 VER='1',
 PACK_TYPE='0402LF',
 LOCATION='R658',
 CDS_LIB='pure_quanta',
 CDS_PART_NAME='Q_RES_0402LF-10K,1%,1/16W,EMPTB',
 WATTAGE='1/16W',
 TOLERANCE='1%',
 MATERIAL='EMPTY',
 VALUE='10K',
 PRIM_FILE='W:/<user>/logical/q_res/chips/chips.prt';

PART_NAME
 R659 'Q_RES_0402LF-10K,1%,1/16W,EMPTB':;

SECTION_NUMBER 1
 '@SCM_LIB.SCM(SCH_1):PAGE21_I64@PURE_QUANTA.Q_RES(CHIPS)':
 C_PATH='@scm_lib.scm(sch_1):page21_i64@pure_quanta.q_res(chips)',
 P_PATH='@scm_lib.scm(sch_1):page21_i64@pure_quanta.q_res(chips)',
 PATH='I64',
 DRAWING='@SCM_LIB.SCM(SCH_1):PAGE21',
 PHYS_PAGE='21',
 XY='(-2475,4125)',
 ROT='0',
 VER='1',
 PACK_TYPE='0402LF',
 LOCATION='R659',
 CDS_LIB='pure_quanta',
 CDS_PART_NAME='Q_RES_0402LF-10K,1%,1/16W,EMPTB',
 WATTAGE='1/16W',
 TOLERANCE='1%',
 MATERIAL='EMPTY',
 VALUE='10K',
 PRIM_FILE='W:/<user>/logical/q_res/chips/chips.prt';

PART_NAME
 R660 'Q_RES_0402LF-10K,1%,1/16W,EMPTB':;

SECTION_NUMBER 1
 '@SCM_LIB.SCM(SCH_1):PAGE21_I61@PURE_QUANTA.Q_RES(CHIPS)':
 C_PATH='@scm_lib.scm(sch_1):page21_i61@pure_quanta.q_res(chips)',
 P_PATH='@scm_lib.scm(sch_1):page21_i61@pure_quanta.q_res(chips)',
 PATH='I61',
 DRAWING='@SCM_LIB.SCM(SCH_1):PAGE21',
 PHYS_PAGE='21',
 XY='(-2475,4075)',
 ROT='0',
 VER='1',
 PACK_TYPE='0402LF',
 LOCATION='R660',
 CDS_LIB='pure_quanta',
 CDS_PART_NAME='Q_RES_0402LF-10K,1%,1/16W,EMPTB',
 WATTAGE='1/16W',
 TOLERANCE='1%',
 MATERIAL='EMPTY',
 VALUE='10K',
 PRIM_FILE='W:/<user>/logical/q_res/chips/chips.prt';

PART_NAME
 R661 'Q_RES_0402LF-10K,1%,1/16W,EMPTB':;

SECTION_NUMBER 1
 '@SCM_LIB.SCM(SCH_1):PAGE21_I60@PURE_QUANTA.Q_RES(CHIPS)':
 C_PATH='@scm_lib.scm(sch_1):page21_i60@pure_quanta.q_res(chips)',
 P_PATH='@scm_lib.scm(sch_1):page21_i60@pure_quanta.q_res(chips)',
 PATH='I60',
 DRAWING='@SCM_LIB.SCM(SCH_1):PAGE21',
 PHYS_PAGE='21',
 XY='(-2475,4025)',
 ROT='0',
 VER='1',
 PACK_TYPE='0402LF',
 LOCATION='R661',
 CDS_LIB='pure_quanta',
 CDS_PART_NAME='Q_RES_0402LF-10K,1%,1/16W,EMPTB',
 WATTAGE='1/16W',
 TOLERANCE='1%',
 MATERIAL='EMPTY',
 VALUE='10K',
 PRIM_FILE='W:/<user>/logical/q_res/chips/chips.prt';

PART_NAME
 R662 'Q_RES_0402LF-10K,1%,1/16W,EMPTB':;

SECTION_NUMBER 1
 '@SCM_LIB.SCM(SCH_1):PAGE21_I58@PURE_QUANTA.Q_RES(CHIPS)':
 C_PATH='@scm_lib.scm(sch_1):page21_i58@pure_quanta.q_res(chips)',
 P_PATH='@scm_lib.scm(sch_1):page21_i58@pure_quanta.q_res(chips)',
 PATH='I58',
 DRAWING='@SCM_LIB.SCM(SCH_1):PAGE21',
 PHYS_PAGE='21',
 XY='(-2475,3975)',
 ROT='0',
 VER='1',
 PACK_TYPE='0402LF',
 LOCATION='R662',
 CDS_LIB='pure_quanta',
 CDS_PART_NAME='Q_RES_0402LF-10K,1%,1/16W,EMPTB',
 WATTAGE='1/16W',
 TOLERANCE='1%',
 MATERIAL='EMPTY',
 VALUE='10K',
 PRIM_FILE='W:/<user>/logical/q_res/chips/chips.prt';

PART_NAME
 R663 'Q_RES_0402LF-10K,1%,1/16W,EMPTB':;

SECTION_NUMBER 1
 '@SCM_LIB.SCM(SCH_1):PAGE21_I59@PURE_QUANTA.Q_RES(CHIPS)':
 C_PATH='@scm_lib.scm(sch_1):page21_i59@pure_quanta.q_res(chips)',
 P_PATH='@scm_lib.scm(sch_1):page21_i59@pure_quanta.q_res(chips)',
 PATH='I59',
 DRAWING='@SCM_LIB.SCM(SCH_1):PAGE21',
 PHYS_PAGE='21',
 XY='(-2475,3925)',
 ROT='0',
 VER='1',
 PACK_TYPE='0402LF',
 LOCATION='R663',
 CDS_LIB='pure_quanta',
 CDS_PART_NAME='Q_RES_0402LF-10K,1%,1/16W,EMPTB',
 WATTAGE='1/16W',
 TOLERANCE='1%',
 MATERIAL='EMPTY',
 VALUE='10K',
 PRIM_FILE='W:/<user>/logical/q_res/chips/chips.prt';

PART_NAME
 R664 'Q_RES_0402LF-1K,1%,1/16W,EMPTYB':;

SECTION_NUMBER 1
 '@SCM_LIB.SCM(SCH_1):PAGE21_I128@PURE_QUANTA.Q_RES(CHIPS)':
 C_PATH='@scm_lib.scm(sch_1):page21_i128@pure_quanta.q_res(chips)',
 P_PATH='@scm_lib.scm(sch_1):page21_i128@pure_quanta.q_res(chips)',
 PATH='I128',
 DRAWING='@SCM_LIB.SCM(SCH_1):PAGE21',
 SEC_TYPE='0402LF',
 PHYS_PAGE='21',
 XY='(4675,3650)',
 ROT='0',
 VER='2',
 PACK_TYPE='0402LF',
 LOCATION='R664',
 SEC='1',
 CDS_LIB='pure_quanta',
 CDS_PART_NAME='Q_RES_0402LF-1K,1%,1/16W,EMPTYB',
 WATTAGE='1/16W',
 TOLERANCE='1%',
 MATERIAL='EMPTY',
 VALUE='1K',
 PRIM_FILE='W:/<user>/logical/q_res/chips/chips.prt';

PART_NAME
 R665 'Q_RES_0402LF-1K,1%,1/16W,EMPTYB':;

SECTION_NUMBER 1
 '@SCM_LIB.SCM(SCH_1):PAGE21_I125@PURE_QUANTA.Q_RES(CHIPS)':
 C_PATH='@scm_lib.scm(sch_1):page21_i125@pure_quanta.q_res(chips)',
 P_PATH='@scm_lib.scm(sch_1):page21_i125@pure_quanta.q_res(chips)',
 PATH='I125',
 DRAWING='@SCM_LIB.SCM(SCH_1):PAGE21',
 SEC_TYPE='0402LF',
 PHYS_PAGE='21',
 XY='(4950,3650)',
 ROT='0',
 VER='2',
 PACK_TYPE='0402LF',
 LOCATION='R665',
 SEC='1',
 CDS_LIB='pure_quanta',
 CDS_PART_NAME='Q_RES_0402LF-1K,1%,1/16W,EMPTYB',
 WATTAGE='1/16W',
 TOLERANCE='1%',
 MATERIAL='EMPTY',
 VALUE='1K',
 PRIM_FILE='W:/<user>/logical/q_res/chips/chips.prt';

PART_NAME
 R666 'Q_RES_0402LF-0,5%,1/16W,CHIP,CA':;

SECTION_NUMBER 1
 '@SCM_LIB.SCM(SCH_1):PAGE29_I124@PURE_QUANTA.Q_RES(CHIPS)':
 C_PATH='@scm_lib.scm(sch_1):page29_i124@pure_quanta.q_res(chips)',
 P_PATH='@scm_lib.scm(sch_1):page29_i124@pure_quanta.q_res(chips)',
 PATH='I124',
 DRAWING='@SCM_LIB.SCM(SCH_1):PAGE29',
 PHYS_PAGE='29',
 XY='(-775,3400)',
 ROT='2',
 VER='1',
 PACK_TYPE='0402LF',
 LOCATION='R666',
 CDS_LIB='pure_quanta',
 CDS_PART_NAME='Q_RES_0402LF-0,5%,1/16W,CHIP,CA',
 WATTAGE='1/16W',
 TOLERANCE='5%',
 MATERIAL='CHIP',
 VALUE='0',
 PRIM_FILE='W:/<user>/logical/q_res/chips/chips.prt';

PART_NAME
 R667 'Q_RES_0402LF-4.7K,1%,1/16W,CHIA':;

SECTION_NUMBER 1
 '@SCM_LIB.SCM(SCH_1):PAGE28_I147@PURE_QUANTA.Q_RES(CHIPS)':
 C_PATH='@scm_lib.scm(sch_1):page28_i147@pure_quanta.q_res(chips)',
 P_PATH='@scm_lib.scm(sch_1):page28_i147@pure_quanta.q_res(chips)',
 PATH='I147',
 DRAWING='@SCM_LIB.SCM(SCH_1):PAGE28',
 PHYS_PAGE='28',
 XY='(-1775,-325)',
 ROT='2',
 VER='2',
 PACK_TYPE='0402LF',
 LOCATION='R667',
 CDS_LIB='pure_quanta',
 CDS_PART_NAME='Q_RES_0402LF-4.7K,1%,1/16W,CHIA',
 WATTAGE='1/16W',
 TOLERANCE='1%',
 MATERIAL='CHIP',
 VALUE='4.7K',
 PRIM_FILE='W:/<user>/logical/q_res/chips/chips.prt';

PART_NAME
 R668 'Q_RES_0402LF-0,5%,1/16W,CHIP,CA':;

SECTION_NUMBER 1
 '@SCM_LIB.SCM(SCH_1):PAGE29_I111@PURE_QUANTA.Q_RES(CHIPS)':
 C_PATH='@scm_lib.scm(sch_1):page29_i111@pure_quanta.q_res(chips)',
 P_PATH='@scm_lib.scm(sch_1):page29_i111@pure_quanta.q_res(chips)',
 PATH='I111',
 DRAWING='@SCM_LIB.SCM(SCH_1):PAGE29',
 PHYS_PAGE='29',
 XY='(-800,2075)',
 ROT='2',
 VER='1',
 PACK_TYPE='0402LF',
 LOCATION='R668',
 CDS_LIB='pure_quanta',
 CDS_PART_NAME='Q_RES_0402LF-0,5%,1/16W,CHIP,CA',
 WATTAGE='1/16W',
 TOLERANCE='5%',
 MATERIAL='CHIP',
 VALUE='0',
 PRIM_FILE='W:/<user>/logical/q_res/chips/chips.prt';

PART_NAME
 R669 'Q_RES_0402LF-0,5%,1/16W,CHIP,CA':;

SECTION_NUMBER 1
 '@SCM_LIB.SCM(SCH_1):PAGE47_I48@PURE_QUANTA.Q_RES(CHIPS)':
 C_PATH='@scm_lib.scm(sch_1):page47_i48@pure_quanta.q_res(chips)',
 P_PATH='@scm_lib.scm(sch_1):page47_i48@pure_quanta.q_res(chips)',
 PATH='I48',
 DRAWING='@SCM_LIB.SCM(SCH_1):PAGE47',
 PHYS_PAGE='47',
 XY='(1600,3650)',
 ROT='2',
 VER='1',
 PACK_TYPE='0402LF',
 LOCATION='R669',
 CDS_LIB='pure_quanta',
 CDS_PART_NAME='Q_RES_0402LF-0,5%,1/16W,CHIP,CA',
 WATTAGE='1/16W',
 TOLERANCE='5%',
 MATERIAL='CHIP',
 VALUE='0',
 PRIM_FILE='W:/<user>/logical/q_res/chips/chips.prt';

PART_NAME
 R670 'Q_RES_0402LF-0,5%,1/16W,CHIP,CA':;

SECTION_NUMBER 1
 '@SCM_LIB.SCM(SCH_1):PAGE28_I104@PURE_QUANTA.Q_RES(CHIPS)':
 C_PATH='@scm_lib.scm(sch_1):page28_i104@pure_quanta.q_res(chips)',
 P_PATH='@scm_lib.scm(sch_1):page28_i104@pure_quanta.q_res(chips)',
 PATH='I104',
 DRAWING='@SCM_LIB.SCM(SCH_1):PAGE28',
 PHYS_PAGE='28',
 XY='(-150,3375)',
 ROT='0',
 VER='1',
 PACK_TYPE='0402LF',
 LOCATION='R670',
 CDS_LIB='pure_quanta',
 CDS_PART_NAME='Q_RES_0402LF-0,5%,1/16W,CHIP,CA',
 WATTAGE='1/16W',
 TOLERANCE='5%',
 MATERIAL='CHIP',
 VALUE='0',
 PRIM_FILE='W:/<user>/logical/q_res/chips/chips.prt';

PART_NAME
 R671 'Q_RES_0402LF-0,5%,1/16W,CHIP,CA':;

SECTION_NUMBER 1
 '@SCM_LIB.SCM(SCH_1):PAGE29_I141@PURE_QUANTA.Q_RES(CHIPS)':
 C_PATH='@scm_lib.scm(sch_1):page29_i141@pure_quanta.q_res(chips)',
 P_PATH='@scm_lib.scm(sch_1):page29_i141@pure_quanta.q_res(chips)',
 PATH='I141',
 DRAWING='@SCM_LIB.SCM(SCH_1):PAGE29',
 PHYS_PAGE='29',
 XY='(-50,500)',
 ROT='0',
 VER='1',
 PACK_TYPE='0402LF',
 LOCATION='R671',
 CDS_LIB='pure_quanta',
 CDS_PART_NAME='Q_RES_0402LF-0,5%,1/16W,CHIP,CA',
 WATTAGE='1/16W',
 TOLERANCE='5%',
 MATERIAL='CHIP',
 VALUE='0',
 PRIM_FILE='W:/<user>/logical/q_res/chips/chips.prt';

PART_NAME
 R672 'Q_RES_0402LF-0,5%,1/16W,CHIP,CA':;

SECTION_NUMBER 1
 '@SCM_LIB.SCM(SCH_1):PAGE29_I144@PURE_QUANTA.Q_RES(CHIPS)':
 C_PATH='@scm_lib.scm(sch_1):page29_i144@pure_quanta.q_res(chips)',
 P_PATH='@scm_lib.scm(sch_1):page29_i144@pure_quanta.q_res(chips)',
 PATH='I144',
 DRAWING='@SCM_LIB.SCM(SCH_1):PAGE29',
 PHYS_PAGE='29',
 XY='(-50,-125)',
 ROT='0',
 VER='1',
 PACK_TYPE='0402LF',
 LOCATION='R672',
 CDS_LIB='pure_quanta',
 CDS_PART_NAME='Q_RES_0402LF-0,5%,1/16W,CHIP,CA',
 WATTAGE='1/16W',
 TOLERANCE='5%',
 MATERIAL='CHIP',
 VALUE='0',
 PRIM_FILE='W:/<user>/logical/q_res/chips/chips.prt';

PART_NAME
 R673 'Q_RES_0402LF-0,5%,1/16W,CHIP,CA':;

SECTION_NUMBER 1
 '@SCM_LIB.SCM(SCH_1):PAGE29_I122@PURE_QUANTA.Q_RES(CHIPS)':
 C_PATH='@scm_lib.scm(sch_1):page29_i122@pure_quanta.q_res(chips)',
 P_PATH='@scm_lib.scm(sch_1):page29_i122@pure_quanta.q_res(chips)',
 PATH='I122',
 DRAWING='@SCM_LIB.SCM(SCH_1):PAGE29',
 PHYS_PAGE='29',
 XY='(-775,4250)',
 ROT='2',
 VER='1',
 PACK_TYPE='0402LF',
 LOCATION='R673',
 CDS_LIB='pure_quanta',
 CDS_PART_NAME='Q_RES_0402LF-0,5%,1/16W,CHIP,CA',
 WATTAGE='1/16W',
 TOLERANCE='5%',
 MATERIAL='CHIP',
 VALUE='0',
 PRIM_FILE='W:/<user>/logical/q_res/chips/chips.prt';

PART_NAME
 R674 'Q_RES_0402LF-0,5%,1/16W,CHIP,CA':;

SECTION_NUMBER 1
 '@SCM_LIB.SCM(SCH_1):PAGE47_I50@PURE_QUANTA.Q_RES(CHIPS)':
 C_PATH='@scm_lib.scm(sch_1):page47_i50@pure_quanta.q_res(chips)',
 P_PATH='@scm_lib.scm(sch_1):page47_i50@pure_quanta.q_res(chips)',
 PATH='I50',
 DRAWING='@SCM_LIB.SCM(SCH_1):PAGE47',
 PHYS_PAGE='47',
 XY='(1600,3350)',
 ROT='2',
 VER='1',
 PACK_TYPE='0402LF',
 LOCATION='R674',
 CDS_LIB='pure_quanta',
 CDS_PART_NAME='Q_RES_0402LF-0,5%,1/16W,CHIP,CA',
 WATTAGE='1/16W',
 TOLERANCE='5%',
 MATERIAL='CHIP',
 VALUE='0',
 PRIM_FILE='W:/<user>/logical/q_res/chips/chips.prt';

PART_NAME
 R675 'Q_RES_0402LF-0,5%,1/16W,CHIP,CA':;

SECTION_NUMBER 1
 '@SCM_LIB.SCM(SCH_1):PAGE29_I109@PURE_QUANTA.Q_RES(CHIPS)':
 C_PATH='@scm_lib.scm(sch_1):page29_i109@pure_quanta.q_res(chips)',
 P_PATH='@scm_lib.scm(sch_1):page29_i109@pure_quanta.q_res(chips)',
 PATH='I109',
 DRAWING='@SCM_LIB.SCM(SCH_1):PAGE29',
 PHYS_PAGE='29',
 XY='(-900,2925)',
 ROT='2',
 VER='1',
 PACK_TYPE='0402LF',
 LOCATION='R675',
 CDS_LIB='pure_quanta',
 CDS_PART_NAME='Q_RES_0402LF-0,5%,1/16W,CHIP,CA',
 WATTAGE='1/16W',
 TOLERANCE='5%',
 MATERIAL='CHIP',
 VALUE='0',
 PRIM_FILE='W:/<user>/logical/q_res/chips/chips.prt';

PART_NAME
 R676 'Q_RES_0402LF-0,5%,1/16W,CHIP,CA':;

SECTION_NUMBER 1
 '@SCM_LIB.SCM(SCH_1):PAGE47_I52@PURE_QUANTA.Q_RES(CHIPS)':
 C_PATH='@scm_lib.scm(sch_1):page47_i52@pure_quanta.q_res(chips)',
 P_PATH='@scm_lib.scm(sch_1):page47_i52@pure_quanta.q_res(chips)',
 PATH='I52',
 DRAWING='@SCM_LIB.SCM(SCH_1):PAGE47',
 PHYS_PAGE='47',
 XY='(1600,3050)',
 ROT='2',
 VER='1',
 PACK_TYPE='0402LF',
 LOCATION='R676',
 CDS_LIB='pure_quanta',
 CDS_PART_NAME='Q_RES_0402LF-0,5%,1/16W,CHIP,CA',
 WATTAGE='1/16W',
 TOLERANCE='5%',
 MATERIAL='CHIP',
 VALUE='0',
 PRIM_FILE='W:/<user>/logical/q_res/chips/chips.prt';

PART_NAME
 R677 'Q_RES_0402LF-10K,1%,1/16W,CHIPA':;

SECTION_NUMBER 1
 '@SCM_LIB.SCM(SCH_1):PAGE51_I57@PURE_QUANTA.Q_RES(CHIPS)':
 C_PATH='@scm_lib.scm(sch_1):page51_i57@pure_quanta.q_res(chips)',
 P_PATH='@scm_lib.scm(sch_1):page51_i57@pure_quanta.q_res(chips)',
 PATH='I57',
 DRAWING='@SCM_LIB.SCM(SCH_1):PAGE51',
 PHYS_PAGE='51',
 XY='(325,3200)',
 ROT='0',
 VER='2',
 PACK_TYPE='0402LF',
 CDS_LIB='pure_quanta',
 CDS_PART_NAME='Q_RES_0402LF-10K,1%,1/16W,CHIPA',
 WATTAGE='1/16W',
 TOLERANCE='1%',
 MATERIAL='CHIP',
 VALUE='10K',
 PRIM_FILE='W:/<user>/logical/q_res/chips/chips.prt';

PART_NAME
 R678 'Q_RES_0402LF-33.2,1%,1/16W,EMPA':;

SECTION_NUMBER 1
 '@SCM_LIB.SCM(SCH_1):PAGE13_I239@PURE_QUANTA.Q_RES(CHIPS)':
 C_PATH='@scm_lib.scm(sch_1):page13_i239@pure_quanta.q_res(chips)',
 P_PATH='@scm_lib.scm(sch_1):page13_i239@pure_quanta.q_res(chips)',
 PATH='I239',
 DRAWING='@SCM_LIB.SCM(SCH_1):PAGE13',
 PHYS_PAGE='13',
 XY='(3350,4750)',
 ROT='0',
 VER='1',
 PACK_TYPE='0402LF',
 LOCATION='R678',
 CDS_LIB='pure_quanta',
 CDS_PART_NAME='Q_RES_0402LF-33.2,1%,1/16W,EMPA',
 WATTAGE='1/16W',
 TOLERANCE='1%',
 MATERIAL='EMPTY',
 VALUE='33.2',
 PRIM_FILE='W:/<user>/logical/q_res/chips/chips.prt';

PART_NAME
 R679 'Q_RES_0402LF-33.2,1%,1/16W,EMPA':;

SECTION_NUMBER 1
 '@SCM_LIB.SCM(SCH_1):PAGE13_I247@PURE_QUANTA.Q_RES(CHIPS)':
 C_PATH='@scm_lib.scm(sch_1):page13_i247@pure_quanta.q_res(chips)',
 P_PATH='@scm_lib.scm(sch_1):page13_i247@pure_quanta.q_res(chips)',
 PATH='I247',
 DRAWING='@SCM_LIB.SCM(SCH_1):PAGE13',
 PHYS_PAGE='13',
 XY='(3350,4700)',
 ROT='0',
 VER='1',
 PACK_TYPE='0402LF',
 LOCATION='R679',
 CDS_LIB='pure_quanta',
 CDS_PART_NAME='Q_RES_0402LF-33.2,1%,1/16W,EMPA',
 WATTAGE='1/16W',
 TOLERANCE='1%',
 MATERIAL='EMPTY',
 VALUE='33.2',
 PRIM_FILE='W:/<user>/logical/q_res/chips/chips.prt';

PART_NAME
 R680 'Q_RES_0402LF-33.2,1%,1/16W,EMPA':;

SECTION_NUMBER 1
 '@SCM_LIB.SCM(SCH_1):PAGE13_I248@PURE_QUANTA.Q_RES(CHIPS)':
 C_PATH='@scm_lib.scm(sch_1):page13_i248@pure_quanta.q_res(chips)',
 P_PATH='@scm_lib.scm(sch_1):page13_i248@pure_quanta.q_res(chips)',
 PATH='I248',
 DRAWING='@SCM_LIB.SCM(SCH_1):PAGE13',
 PHYS_PAGE='13',
 XY='(3350,4650)',
 ROT='0',
 VER='1',
 PACK_TYPE='0402LF',
 LOCATION='R680',
 CDS_LIB='pure_quanta',
 CDS_PART_NAME='Q_RES_0402LF-33.2,1%,1/16W,EMPA',
 WATTAGE='1/16W',
 TOLERANCE='1%',
 MATERIAL='EMPTY',
 VALUE='33.2',
 PRIM_FILE='W:/<user>/logical/q_res/chips/chips.prt';

PART_NAME
 R681 'Q_RES_0402LF-33.2,1%,1/16W,EMPA':;

SECTION_NUMBER 1
 '@SCM_LIB.SCM(SCH_1):PAGE13_I245@PURE_QUANTA.Q_RES(CHIPS)':
 C_PATH='@scm_lib.scm(sch_1):page13_i245@pure_quanta.q_res(chips)',
 P_PATH='@scm_lib.scm(sch_1):page13_i245@pure_quanta.q_res(chips)',
 PATH='I245',
 DRAWING='@SCM_LIB.SCM(SCH_1):PAGE13',
 PHYS_PAGE='13',
 XY='(3350,4600)',
 ROT='0',
 VER='1',
 PACK_TYPE='0402LF',
 LOCATION='R681',
 CDS_LIB='pure_quanta',
 CDS_PART_NAME='Q_RES_0402LF-33.2,1%,1/16W,EMPA',
 WATTAGE='1/16W',
 TOLERANCE='1%',
 MATERIAL='EMPTY',
 VALUE='33.2',
 PRIM_FILE='W:/<user>/logical/q_res/chips/chips.prt';

PART_NAME
 R682 'Q_RES_0402LF-33.2,1%,1/16W,EMPA':;

SECTION_NUMBER 1
 '@SCM_LIB.SCM(SCH_1):PAGE13_I246@PURE_QUANTA.Q_RES(CHIPS)':
 C_PATH='@scm_lib.scm(sch_1):page13_i246@pure_quanta.q_res(chips)',
 P_PATH='@scm_lib.scm(sch_1):page13_i246@pure_quanta.q_res(chips)',
 PATH='I246',
 DRAWING='@SCM_LIB.SCM(SCH_1):PAGE13',
 PHYS_PAGE='13',
 XY='(3350,4550)',
 ROT='0',
 VER='1',
 PACK_TYPE='0402LF',
 LOCATION='R682',
 CDS_LIB='pure_quanta',
 CDS_PART_NAME='Q_RES_0402LF-33.2,1%,1/16W,EMPA',
 WATTAGE='1/16W',
 TOLERANCE='1%',
 MATERIAL='EMPTY',
 VALUE='33.2',
 PRIM_FILE='W:/<user>/logical/q_res/chips/chips.prt';

PART_NAME
 R683 'Q_RES_0402LF-4.7K,1%,1/16W,CHIA':;

SECTION_NUMBER 1
 '@SCM_LIB.SCM(SCH_1):PAGE13_I188@PURE_QUANTA.Q_RES(CHIPS)':
 C_PATH='@scm_lib.scm(sch_1):page13_i188@pure_quanta.q_res(chips)',
 P_PATH='@scm_lib.scm(sch_1):page13_i188@pure_quanta.q_res(chips)',
 PATH='I188',
 DRAWING='@SCM_LIB.SCM(SCH_1):PAGE13',
 PHYS_PAGE='13',
 XY='(2750,175)',
 ROT='0',
 VER='1',
 PACK_TYPE='0402LF',
 LOCATION='R683',
 CDS_LIB='pure_quanta',
 CDS_PART_NAME='Q_RES_0402LF-4.7K,1%,1/16W,CHIA',
 WATTAGE='1/16W',
 TOLERANCE='1%',
 MATERIAL='CHIP',
 VALUE='4.7K',
 PRIM_FILE='W:/<user>/logical/q_res/chips/chips.prt';

PART_NAME
 R684 'Q_RES_0402LF-1K,1%,1/16W,EMPTYB':;

SECTION_NUMBER 1
 '@SCM_LIB.SCM(SCH_1):PAGE14_I163@PURE_QUANTA.Q_RES(CHIPS)':
 C_PATH='@scm_lib.scm(sch_1):page14_i163@pure_quanta.q_res(chips)',
 P_PATH='@scm_lib.scm(sch_1):page14_i163@pure_quanta.q_res(chips)',
 PATH='I163',
 DRAWING='@SCM_LIB.SCM(SCH_1):PAGE14',
 SEC_TYPE='0402LF',
 PHYS_PAGE='14',
 XY='(-3100,975)',
 ROT='0',
 VER='2',
 PACK_TYPE='0402LF',
 LOCATION='R684',
 SEC='1',
 CDS_LIB='pure_quanta',
 CDS_PART_NAME='Q_RES_0402LF-1K,1%,1/16W,EMPTYB',
 WATTAGE='1/16W',
 TOLERANCE='1%',
 MATERIAL='EMPTY',
 VALUE='1K',
 PRIM_FILE='W:/<user>/logical/q_res/chips/chips.prt';

PART_NAME
 R685 'Q_RES_0402LF-1K,1%,1/16W,EMPTYB':;

SECTION_NUMBER 1
 '@SCM_LIB.SCM(SCH_1):PAGE14_I165@PURE_QUANTA.Q_RES(CHIPS)':
 C_PATH='@scm_lib.scm(sch_1):page14_i165@pure_quanta.q_res(chips)',
 P_PATH='@scm_lib.scm(sch_1):page14_i165@pure_quanta.q_res(chips)',
 PATH='I165',
 DRAWING='@SCM_LIB.SCM(SCH_1):PAGE14',
 SEC_TYPE='0402LF',
 PHYS_PAGE='14',
 XY='(-2875,975)',
 ROT='0',
 VER='2',
 PACK_TYPE='0402LF',
 LOCATION='R685',
 SEC='1',
 CDS_LIB='pure_quanta',
 CDS_PART_NAME='Q_RES_0402LF-1K,1%,1/16W,EMPTYB',
 WATTAGE='1/16W',
 TOLERANCE='1%',
 MATERIAL='EMPTY',
 VALUE='1K',
 PRIM_FILE='W:/<user>/logical/q_res/chips/chips.prt';

PART_NAME
 R686 'Q_RES_0402LF-4.7K,1%,1/16W,EMPB':;

SECTION_NUMBER 1
 '@SCM_LIB.SCM(SCH_1):PAGE14_I164@PURE_QUANTA.Q_RES(CHIPS)':
 C_PATH='@scm_lib.scm(sch_1):page14_i164@pure_quanta.q_res(chips)',
 P_PATH='@scm_lib.scm(sch_1):page14_i164@pure_quanta.q_res(chips)',
 PATH='I164',
 DRAWING='@SCM_LIB.SCM(SCH_1):PAGE14',
 PHYS_PAGE='14',
 XY='(-3100,1600)',
 ROT='0',
 VER='2',
 PACK_TYPE='0402LF',
 LOCATION='R686',
 CDS_LIB='pure_quanta',
 CDS_PART_NAME='Q_RES_0402LF-4.7K,1%,1/16W,EMPB',
 WATTAGE='1/16W',
 TOLERANCE='1%',
 MATERIAL='EMPTY',
 VALUE='4.7K',
 PRIM_FILE='W:/<user>/logical/q_res/chips/chips.prt';

PART_NAME
 R687 'Q_RES_0402LF-4.7K,1%,1/16W,EMPB':;

SECTION_NUMBER 1
 '@SCM_LIB.SCM(SCH_1):PAGE14_I166@PURE_QUANTA.Q_RES(CHIPS)':
 C_PATH='@scm_lib.scm(sch_1):page14_i166@pure_quanta.q_res(chips)',
 P_PATH='@scm_lib.scm(sch_1):page14_i166@pure_quanta.q_res(chips)',
 PATH='I166',
 DRAWING='@SCM_LIB.SCM(SCH_1):PAGE14',
 PHYS_PAGE='14',
 XY='(-2875,1600)',
 ROT='0',
 VER='2',
 PACK_TYPE='0402LF',
 LOCATION='R687',
 CDS_LIB='pure_quanta',
 CDS_PART_NAME='Q_RES_0402LF-4.7K,1%,1/16W,EMPB',
 WATTAGE='1/16W',
 TOLERANCE='1%',
 MATERIAL='EMPTY',
 VALUE='4.7K',
 PRIM_FILE='W:/<user>/logical/q_res/chips/chips.prt';

PART_NAME
 R688 'Q_RES_0402LF-33.2,1%,1/16W,CHIA':;

SECTION_NUMBER 1
 '@SCM_LIB.SCM(SCH_1):PAGE13_I383@PURE_QUANTA.Q_RES(CHIPS)':
 C_PATH='@scm_lib.scm(sch_1):page13_i383@pure_quanta.q_res(chips)',
 P_PATH='@scm_lib.scm(sch_1):page13_i383@pure_quanta.q_res(chips)',
 PATH='I383',
 DRAWING='@SCM_LIB.SCM(SCH_1):PAGE13',
 PHYS_PAGE='13',
 XY='(3275,1275)',
 ROT='0',
 VER='1',
 PACK_TYPE='0402LF',
 LOCATION='R688',
 CDS_LIB='pure_quanta',
 CDS_PART_NAME='Q_RES_0402LF-33.2,1%,1/16W,CHIA',
 WATTAGE='1/16W',
 TOLERANCE='1%',
 MATERIAL='CHIP',
 VALUE='33.2',
 PRIM_FILE='W:/<user>/logical/q_res/chips/chips.prt';

PART_NAME
 R689 'Q_RES_0402LF-33.2,1%,1/16W,EMPA':;

SECTION_NUMBER 1
 '@SCM_LIB.SCM(SCH_1):PAGE13_I398@PURE_QUANTA.Q_RES(CHIPS)':
 C_PATH='@scm_lib.scm(sch_1):page13_i398@pure_quanta.q_res(chips)',
 P_PATH='@scm_lib.scm(sch_1):page13_i398@pure_quanta.q_res(chips)',
 PATH='I398',
 DRAWING='@SCM_LIB.SCM(SCH_1):PAGE13',
 PHYS_PAGE='13',
 XY='(-2175,1375)',
 ROT='0',
 VER='1',
 PACK_TYPE='0402LF',
 LOCATION='R689',
 CDS_LIB='pure_quanta',
 CDS_PART_NAME='Q_RES_0402LF-33.2,1%,1/16W,EMPA',
 WATTAGE='1/16W',
 TOLERANCE='1%',
 MATERIAL='EMPTY',
 VALUE='33.2',
 PRIM_FILE='W:/<user>/logical/q_res/chips/chips.prt';

PART_NAME
 R690 'Q_RES_0402LF-33.2,1%,1/16W,CHIA':;

SECTION_NUMBER 1
 '@SCM_LIB.SCM(SCH_1):PAGE35_I149@PURE_QUANTA.Q_RES(CHIPS)':
 C_PATH='@scm_lib.scm(sch_1):page35_i149@pure_quanta.q_res(chips)',
 P_PATH='@scm_lib.scm(sch_1):page35_i149@pure_quanta.q_res(chips)',
 PATH='I149',
 DRAWING='@SCM_LIB.SCM(SCH_1):PAGE35',
 PHYS_PAGE='35',
 XY='(-2250,4900)',
 ROT='0',
 VER='1',
 PACK_TYPE='0402LF',
 LOCATION='R690',
 CDS_LIB='pure_quanta',
 CDS_PART_NAME='Q_RES_0402LF-33.2,1%,1/16W,CHIA',
 WATTAGE='1/16W',
 TOLERANCE='1%',
 MATERIAL='CHIP',
 VALUE='33.2',
 PRIM_FILE='W:/<user>/logical/q_res/chips/chips.prt';

PART_NAME
 R691 'Q_RES_0402LF-33.2,1%,1/16W,CHIA':;

SECTION_NUMBER 1
 '@SCM_LIB.SCM(SCH_1):PAGE35_I148@PURE_QUANTA.Q_RES(CHIPS)':
 C_PATH='@scm_lib.scm(sch_1):page35_i148@pure_quanta.q_res(chips)',
 P_PATH='@scm_lib.scm(sch_1):page35_i148@pure_quanta.q_res(chips)',
 PATH='I148',
 DRAWING='@SCM_LIB.SCM(SCH_1):PAGE35',
 PHYS_PAGE='35',
 XY='(-2250,4800)',
 ROT='0',
 VER='1',
 PACK_TYPE='0402LF',
 LOCATION='R691',
 CDS_LIB='pure_quanta',
 CDS_PART_NAME='Q_RES_0402LF-33.2,1%,1/16W,CHIA',
 WATTAGE='1/16W',
 TOLERANCE='1%',
 MATERIAL='CHIP',
 VALUE='33.2',
 PRIM_FILE='W:/<user>/logical/q_res/chips/chips.prt';

PART_NAME
 R692 'Q_RES_0402LF-2.2K,5%,1/16W,CHIA':;

SECTION_NUMBER 1
 '@SCM_LIB.SCM(SCH_1):PAGE27_I238@PURE_QUANTA.Q_RES(CHIPS)':
 C_PATH='@scm_lib.scm(sch_1):page27_i238@pure_quanta.q_res(chips)',
 P_PATH='@scm_lib.scm(sch_1):page27_i238@pure_quanta.q_res(chips)',
 PATH='I238',
 DRAWING='@SCM_LIB.SCM(SCH_1):PAGE27',
 PHYS_PAGE='27',
 XY='(-3625,1875)',
 ROT='0',
 VER='1',
 PACK_TYPE='0402LF',
 LOCATION='R692',
 CDS_LIB='pure_quanta',
 CDS_PART_NAME='Q_RES_0402LF-2.2K,5%,1/16W,CHIA',
 WATTAGE='1/16W',
 TOLERANCE='5%',
 MATERIAL='CHIP',
 VALUE='2.2K',
 PRIM_FILE='W:/<user>/logical/q_res/chips/chips.prt';

PART_NAME
 R693 'Q_RES_0402LF-33.2,1%,1/16W,CHIA':;

SECTION_NUMBER 1
 '@SCM_LIB.SCM(SCH_1):PAGE29_I222@PURE_QUANTA.Q_RES(CHIPS)':
 C_PATH='@scm_lib.scm(sch_1):page29_i222@pure_quanta.q_res(chips)',
 P_PATH='@scm_lib.scm(sch_1):page29_i222@pure_quanta.q_res(chips)',
 PATH='I222',
 DRAWING='@SCM_LIB.SCM(SCH_1):PAGE29',
 PHYS_PAGE='29',
 XY='(2050,375)',
 ROT='0',
 VER='1',
 PACK_TYPE='0402LF',
 LOCATION='R693',
 CDS_LIB='pure_quanta',
 CDS_PART_NAME='Q_RES_0402LF-33.2,1%,1/16W,CHIA',
 WATTAGE='1/16W',
 TOLERANCE='1%',
 MATERIAL='CHIP',
 VALUE='33.2',
 PRIM_FILE='W:/<user>/logical/q_res/chips/chips.prt';

PART_NAME
 R694 'Q_RES_0402LF-100,1%,1/16W,CHIPA':;

SECTION_NUMBER 1
 '@SCM_LIB.SCM(SCH_1):PAGE29_I155@PURE_QUANTA.Q_RES(CHIPS)':
 C_PATH='@scm_lib.scm(sch_1):page29_i155@pure_quanta.q_res(chips)',
 P_PATH='@scm_lib.scm(sch_1):page29_i155@pure_quanta.q_res(chips)',
 PATH='I155',
 DRAWING='@SCM_LIB.SCM(SCH_1):PAGE29',
 PHYS_PAGE='29',
 XY='(-3600,-1275)',
 ROT='2',
 VER='2',
 PACK_TYPE='0402LF',
 LOCATION='R694',
 CDS_LIB='pure_quanta',
 CDS_PART_NAME='Q_RES_0402LF-100,1%,1/16W,CHIPA',
 WATTAGE='1/16W',
 TOLERANCE='1%',
 MATERIAL='CHIP',
 VALUE='100',
 PRIM_FILE='W:/<user>/logical/q_res/chips/chips.prt';

PART_NAME
 R695 'Q_RES_0402LF-0,5%,1/16W,CHIP,CA':;

SECTION_NUMBER 1
 '@SCM_LIB.SCM(SCH_1):PAGE47_I54@PURE_QUANTA.Q_RES(CHIPS)':
 C_PATH='@scm_lib.scm(sch_1):page47_i54@pure_quanta.q_res(chips)',
 P_PATH='@scm_lib.scm(sch_1):page47_i54@pure_quanta.q_res(chips)',
 PATH='I54',
 DRAWING='@SCM_LIB.SCM(SCH_1):PAGE47',
 PHYS_PAGE='47',
 XY='(1600,2750)',
 ROT='2',
 VER='1',
 PACK_TYPE='0402LF',
 LOCATION='R695',
 CDS_LIB='pure_quanta',
 CDS_PART_NAME='Q_RES_0402LF-0,5%,1/16W,CHIP,CA',
 WATTAGE='1/16W',
 TOLERANCE='5%',
 MATERIAL='CHIP',
 VALUE='0',
 PRIM_FILE='W:/<user>/logical/q_res/chips/chips.prt';

PART_NAME
 R696 'Q_RES_0402LF-0,5%,1/16W,CHIP,CA':;

SECTION_NUMBER 1
 '@SCM_LIB.SCM(SCH_1):PAGE47_I56@PURE_QUANTA.Q_RES(CHIPS)':
 C_PATH='@scm_lib.scm(sch_1):page47_i56@pure_quanta.q_res(chips)',
 P_PATH='@scm_lib.scm(sch_1):page47_i56@pure_quanta.q_res(chips)',
 PATH='I56',
 DRAWING='@SCM_LIB.SCM(SCH_1):PAGE47',
 PHYS_PAGE='47',
 XY='(1600,2450)',
 ROT='2',
 VER='1',
 PACK_TYPE='0402LF',
 LOCATION='R696',
 CDS_LIB='pure_quanta',
 CDS_PART_NAME='Q_RES_0402LF-0,5%,1/16W,CHIP,CA',
 WATTAGE='1/16W',
 TOLERANCE='5%',
 MATERIAL='CHIP',
 VALUE='0',
 PRIM_FILE='W:/<user>/logical/q_res/chips/chips.prt';

PART_NAME
 R697 'Q_RES_0402LF-0,5%,1/16W,CHIP,CA':;

SECTION_NUMBER 1
 '@SCM_LIB.SCM(SCH_1):PAGE47_I58@PURE_QUANTA.Q_RES(CHIPS)':
 C_PATH='@scm_lib.scm(sch_1):page47_i58@pure_quanta.q_res(chips)',
 P_PATH='@scm_lib.scm(sch_1):page47_i58@pure_quanta.q_res(chips)',
 PATH='I58',
 DRAWING='@SCM_LIB.SCM(SCH_1):PAGE47',
 PHYS_PAGE='47',
 XY='(1600,2150)',
 ROT='2',
 VER='1',
 PACK_TYPE='0402LF',
 LOCATION='R697',
 CDS_LIB='pure_quanta',
 CDS_PART_NAME='Q_RES_0402LF-0,5%,1/16W,CHIP,CA',
 WATTAGE='1/16W',
 TOLERANCE='5%',
 MATERIAL='CHIP',
 VALUE='0',
 PRIM_FILE='W:/<user>/logical/q_res/chips/chips.prt';

PART_NAME
 R698 'Q_RES_0402LF-0,5%,1/16W,CHIP,CA':;

SECTION_NUMBER 1
 '@SCM_LIB.SCM(SCH_1):PAGE47_I60@PURE_QUANTA.Q_RES(CHIPS)':
 C_PATH='@scm_lib.scm(sch_1):page47_i60@pure_quanta.q_res(chips)',
 P_PATH='@scm_lib.scm(sch_1):page47_i60@pure_quanta.q_res(chips)',
 PATH='I60',
 DRAWING='@SCM_LIB.SCM(SCH_1):PAGE47',
 PHYS_PAGE='47',
 XY='(1600,1850)',
 ROT='2',
 VER='1',
 PACK_TYPE='0402LF',
 LOCATION='R698',
 CDS_LIB='pure_quanta',
 CDS_PART_NAME='Q_RES_0402LF-0,5%,1/16W,CHIP,CA',
 WATTAGE='1/16W',
 TOLERANCE='5%',
 MATERIAL='CHIP',
 VALUE='0',
 PRIM_FILE='W:/<user>/logical/q_res/chips/chips.prt';

PART_NAME
 R699 'Q_RES_0402LF-4.7K,1%,1/16W,EMPA':;

SECTION_NUMBER 1
 '@SCM_LIB.SCM(SCH_1):PAGE27_I163@PURE_QUANTA.Q_RES(CHIPS)':
 C_PATH='@scm_lib.scm(sch_1):page27_i163@pure_quanta.q_res(chips)',
 P_PATH='@scm_lib.scm(sch_1):page27_i163@pure_quanta.q_res(chips)',
 PATH='I163',
 DRAWING='@SCM_LIB.SCM(SCH_1):PAGE27',
 PHYS_PAGE='27',
 XY='(2500,500)',
 ROT='0',
 VER='1',
 PACK_TYPE='0402LF',
 LOCATION='R699',
 CDS_LIB='pure_quanta',
 CDS_PART_NAME='Q_RES_0402LF-4.7K,1%,1/16W,EMPA',
 WATTAGE='1/16W',
 TOLERANCE='1%',
 MATERIAL='EMPTY',
 VALUE='4.7K',
 PRIM_FILE='W:/<user>/logical/q_res/chips/chips.prt';

PART_NAME
 R700 'Q_RES_0402LF-0,5%,1/16W,CHIP,CA':;

SECTION_NUMBER 1
 '@SCM_LIB.SCM(SCH_1):PAGE47_I62@PURE_QUANTA.Q_RES(CHIPS)':
 C_PATH='@scm_lib.scm(sch_1):page47_i62@pure_quanta.q_res(chips)',
 P_PATH='@scm_lib.scm(sch_1):page47_i62@pure_quanta.q_res(chips)',
 PATH='I62',
 DRAWING='@SCM_LIB.SCM(SCH_1):PAGE47',
 PHYS_PAGE='47',
 XY='(1600,1550)',
 ROT='2',
 VER='1',
 PACK_TYPE='0402LF',
 LOCATION='R700',
 CDS_LIB='pure_quanta',
 CDS_PART_NAME='Q_RES_0402LF-0,5%,1/16W,CHIP,CA',
 WATTAGE='1/16W',
 TOLERANCE='5%',
 MATERIAL='CHIP',
 VALUE='0',
 PRIM_FILE='W:/<user>/logical/q_res/chips/chips.prt';

PART_NAME
 R701 'Q_RES_0402LF-0,5%,1/16W,CHIP,CA':;

SECTION_NUMBER 1
 '@SCM_LIB.SCM(SCH_1):PAGE28_I125@PURE_QUANTA.Q_RES(CHIPS)':
 C_PATH='@scm_lib.scm(sch_1):page28_i125@pure_quanta.q_res(chips)',
 P_PATH='@scm_lib.scm(sch_1):page28_i125@pure_quanta.q_res(chips)',
 PATH='I125',
 DRAWING='@SCM_LIB.SCM(SCH_1):PAGE28',
 PHYS_PAGE='28',
 XY='(2000,-1125)',
 ROT='2',
 VER='1',
 PACK_TYPE='0402LF',
 LOCATION='R701',
 CDS_LIB='pure_quanta',
 CDS_PART_NAME='Q_RES_0402LF-0,5%,1/16W,CHIP,CA',
 WATTAGE='1/16W',
 TOLERANCE='5%',
 MATERIAL='CHIP',
 VALUE='0',
 PRIM_FILE='W:/<user>/logical/q_res/chips/chips.prt';

PART_NAME
 R702 'Q_RES_0402LF-0,5%,1/16W,CHIP,CA':;

SECTION_NUMBER 1
 '@SCM_LIB.SCM(SCH_1):PAGE28_I126@PURE_QUANTA.Q_RES(CHIPS)':
 C_PATH='@scm_lib.scm(sch_1):page28_i126@pure_quanta.q_res(chips)',
 P_PATH='@scm_lib.scm(sch_1):page28_i126@pure_quanta.q_res(chips)',
 PATH='I126',
 DRAWING='@SCM_LIB.SCM(SCH_1):PAGE28',
 PHYS_PAGE='28',
 XY='(2000,-1175)',
 ROT='2',
 VER='1',
 PACK_TYPE='0402LF',
 LOCATION='R702',
 CDS_LIB='pure_quanta',
 CDS_PART_NAME='Q_RES_0402LF-0,5%,1/16W,CHIP,CA',
 WATTAGE='1/16W',
 TOLERANCE='5%',
 MATERIAL='CHIP',
 VALUE='0',
 PRIM_FILE='W:/<user>/logical/q_res/chips/chips.prt';

PART_NAME
 R703 'Q_RES_0402LF-0,5%,1/16W,CHIP,CA':;

SECTION_NUMBER 1
 '@SCM_LIB.SCM(SCH_1):PAGE28_I127@PURE_QUANTA.Q_RES(CHIPS)':
 C_PATH='@scm_lib.scm(sch_1):page28_i127@pure_quanta.q_res(chips)',
 P_PATH='@scm_lib.scm(sch_1):page28_i127@pure_quanta.q_res(chips)',
 PATH='I127',
 DRAWING='@SCM_LIB.SCM(SCH_1):PAGE28',
 PHYS_PAGE='28',
 XY='(2000,-1225)',
 ROT='2',
 VER='1',
 PACK_TYPE='0402LF',
 LOCATION='R703',
 CDS_LIB='pure_quanta',
 CDS_PART_NAME='Q_RES_0402LF-0,5%,1/16W,CHIP,CA',
 WATTAGE='1/16W',
 TOLERANCE='5%',
 MATERIAL='CHIP',
 VALUE='0',
 PRIM_FILE='W:/<user>/logical/q_res/chips/chips.prt';

PART_NAME
 R705 'Q_RES_0402LF-33.2,1%,1/16W,CHIA':;

SECTION_NUMBER 1
 '@SCM_LIB.SCM(SCH_1):PAGE12_I353@PURE_QUANTA.Q_RES(CHIPS)':
 C_PATH='@scm_lib.scm(sch_1):page12_i353@pure_quanta.q_res(chips)',
 P_PATH='@scm_lib.scm(sch_1):page12_i353@pure_quanta.q_res(chips)',
 PATH='I353',
 DRAWING='@SCM_LIB.SCM(SCH_1):PAGE12',
 PHYS_PAGE='12',
 XY='(-850,750)',
 ROT='0',
 VER='1',
 PACK_TYPE='0402LF',
 LOCATION='R705',
 CDS_LIB='pure_quanta',
 CDS_PART_NAME='Q_RES_0402LF-33.2,1%,1/16W,CHIA',
 WATTAGE='1/16W',
 TOLERANCE='1%',
 MATERIAL='CHIP',
 VALUE='33.2',
 PRIM_FILE='W:/<user>/logical/q_res/chips/chips.prt';

PART_NAME
 R706 'Q_RES_0402LF-4.7K,1%,1/16W,CHIA':;

SECTION_NUMBER 1
 '@SCM_LIB.SCM(SCH_1):PAGE12_I354@PURE_QUANTA.Q_RES(CHIPS)':
 C_PATH='@scm_lib.scm(sch_1):page12_i354@pure_quanta.q_res(chips)',
 P_PATH='@scm_lib.scm(sch_1):page12_i354@pure_quanta.q_res(chips)',
 PATH='I354',
 DRAWING='@SCM_LIB.SCM(SCH_1):PAGE12',
 PHYS_PAGE='12',
 XY='(-2550,3225)',
 ROT='0',
 VER='1',
 PACK_TYPE='0402LF',
 LOCATION='R706',
 CDS_LIB='pure_quanta',
 CDS_PART_NAME='Q_RES_0402LF-4.7K,1%,1/16W,CHIA',
 WATTAGE='1/16W',
 TOLERANCE='1%',
 MATERIAL='CHIP',
 VALUE='4.7K',
 PRIM_FILE='W:/<user>/logical/q_res/chips/chips.prt';

PART_NAME
 R707 'Q_RES_0402LF-0,5%,1/16W,CHIP,CA':;

SECTION_NUMBER 1
 '@SCM_LIB.SCM(SCH_1):PAGE29_I201@PURE_QUANTA.Q_RES(CHIPS)':
 C_PATH='@scm_lib.scm(sch_1):page29_i201@pure_quanta.q_res(chips)',
 P_PATH='@scm_lib.scm(sch_1):page29_i201@pure_quanta.q_res(chips)',
 PATH='I201',
 DRAWING='@SCM_LIB.SCM(SCH_1):PAGE29',
 PHYS_PAGE='29',
 XY='(3575,-450)',
 ROT='2',
 VER='1',
 PACK_TYPE='0402LF',
 LOCATION='R707',
 CDS_LIB='pure_quanta',
 CDS_PART_NAME='Q_RES_0402LF-0,5%,1/16W,CHIP,CA',
 WATTAGE='1/16W',
 TOLERANCE='5%',
 MATERIAL='CHIP',
 VALUE='0',
 PRIM_FILE='W:/<user>/logical/q_res/chips/chips.prt';

PART_NAME
 R708 'Q_RES_0402LF-0,5%,1/16W,CHIP,CA':;

SECTION_NUMBER 1
 '@SCM_LIB.SCM(SCH_1):PAGE55_I38@PURE_QUANTA.Q_RES(CHIPS)':
 C_PATH='@scm_lib.scm(sch_1):page55_i38@pure_quanta.q_res(chips)',
 P_PATH='@scm_lib.scm(sch_1):page55_i38@pure_quanta.q_res(chips)',
 PATH='I38',
 DRAWING='@SCM_LIB.SCM(SCH_1):PAGE55',
 PHYS_PAGE='55',
 XY='(-1700,675)',
 ROT='0',
 VER='1',
 PACK_TYPE='0402LF',
 LOCATION='R708',
 CDS_LIB='pure_quanta',
 CDS_PART_NAME='Q_RES_0402LF-0,5%,1/16W,CHIP,CA',
 WATTAGE='1/16W',
 TOLERANCE='5%',
 MATERIAL='CHIP',
 VALUE='0',
 PRIM_FILE='W:/<user>/logical/q_res/chips/chips.prt';

PART_NAME
 R709 'Q_RES_0402LF-2.2K,5%,1/16W,CHIA':;

SECTION_NUMBER 1
 '@SCM_LIB.SCM(SCH_1):PAGE52_I145@PURE_QUANTA.Q_RES(CHIPS)':
 C_PATH='@scm_lib.scm(sch_1):page52_i145@pure_quanta.q_res(chips)',
 P_PATH='@scm_lib.scm(sch_1):page52_i145@pure_quanta.q_res(chips)',
 PATH='I145',
 DRAWING='@SCM_LIB.SCM(SCH_1):PAGE52',
 PHYS_PAGE='52',
 XY='(-625,-1700)',
 ROT='0',
 VER='1',
 PACK_TYPE='0402LF',
 LOCATION='R709',
 CDS_LIB='pure_quanta',
 CDS_PART_NAME='Q_RES_0402LF-2.2K,5%,1/16W,CHIA',
 WATTAGE='1/16W',
 TOLERANCE='5%',
 MATERIAL='CHIP',
 VALUE='2.2K',
 PRIM_FILE='W:/<user>/logical/q_res/chips/chips.prt';

PART_NAME
 R710 'Q_RES_0402LF-100K,1%,1/16W,CHIA':;

SECTION_NUMBER 1
 '@SCM_LIB.SCM(SCH_1):PAGE22_I55@PURE_QUANTA.Q_RES(CHIPS)':
 C_PATH='@scm_lib.scm(sch_1):page22_i55@pure_quanta.q_res(chips)',
 P_PATH='@scm_lib.scm(sch_1):page22_i55@pure_quanta.q_res(chips)',
 PATH='I55',
 DRAWING='@SCM_LIB.SCM(SCH_1):PAGE22',
 PHYS_PAGE='22',
 XY='(-250,0)',
 ROT='0',
 VER='2',
 PACK_TYPE='0402LF',
 LOCATION='R710',
 CDS_LIB='pure_quanta',
 CDS_PART_NAME='Q_RES_0402LF-100K,1%,1/16W,CHIA',
 WATTAGE='1/16W',
 TOLERANCE='1%',
 MATERIAL='CHIP',
 VALUE='100K',
 PRIM_FILE='W:/<user>/logical/q_res/chips/chips.prt';

PART_NAME
 R711 'Q_RES_0402LF-0,5%,1/16W,EMPTY,A':;

SECTION_NUMBER 1
 '@SCM_LIB.SCM(SCH_1):PAGE22_I49@PURE_QUANTA.Q_RES(CHIPS)':
 C_PATH='@scm_lib.scm(sch_1):page22_i49@pure_quanta.q_res(chips)',
 P_PATH='@scm_lib.scm(sch_1):page22_i49@pure_quanta.q_res(chips)',
 PATH='I49',
 DRAWING='@SCM_LIB.SCM(SCH_1):PAGE22',
 PHYS_PAGE='22',
 XY='(-2425,1800)',
 ROT='0',
 VER='1',
 PACK_TYPE='0402LF',
 LOCATION='R711',
 CDS_LIB='pure_quanta',
 CDS_PART_NAME='Q_RES_0402LF-0,5%,1/16W,EMPTY,A',
 WATTAGE='1/16W',
 TOLERANCE='5%',
 MATERIAL='EMPTY',
 VALUE='0',
 PRIM_FILE='W:/<user>/logical/q_res/chips/chips.prt';

PART_NAME
 R712 'Q_RES_0402LF-10K,1%,1/16W,EMPTA':;

SECTION_NUMBER 1
 '@SCM_LIB.SCM(SCH_1):PAGE29_I153@PURE_QUANTA.Q_RES(CHIPS)':
 C_PATH='@scm_lib.scm(sch_1):page29_i153@pure_quanta.q_res(chips)',
 P_PATH='@scm_lib.scm(sch_1):page29_i153@pure_quanta.q_res(chips)',
 PATH='I153',
 DRAWING='@SCM_LIB.SCM(SCH_1):PAGE29',
 PHYS_PAGE='29',
 XY='(-3800,-725)',
 ROT='0',
 VER='2',
 PACK_TYPE='0402LF',
 LOCATION='R712',
 CDS_LIB='pure_quanta',
 CDS_PART_NAME='Q_RES_0402LF-10K,1%,1/16W,EMPTA',
 WATTAGE='1/16W',
 TOLERANCE='1%',
 MATERIAL='EMPTY',
 VALUE='10K',
 PRIM_FILE='W:/<user>/logical/q_res/chips/chips.prt';

PART_NAME
 R713 'Q_RES_0402LF-33.2,1%,1/16W,CHIA':;

SECTION_NUMBER 1
 '@SCM_LIB.SCM(SCH_1):PAGE17_I228@PURE_QUANTA.Q_RES(CHIPS)':
 C_PATH='@scm_lib.scm(sch_1):page17_i228@pure_quanta.q_res(chips)',
 P_PATH='@scm_lib.scm(sch_1):page17_i228@pure_quanta.q_res(chips)',
 PATH='I228',
 DRAWING='@SCM_LIB.SCM(SCH_1):PAGE17',
 PHYS_PAGE='17',
 XY='(3775,-1175)',
 ROT='0',
 VER='1',
 PACK_TYPE='0402LF',
 LOCATION='R713',
 CDS_LIB='pure_quanta',
 CDS_PART_NAME='Q_RES_0402LF-33.2,1%,1/16W,CHIA',
 WATTAGE='1/16W',
 TOLERANCE='1%',
 MATERIAL='CHIP',
 VALUE='33.2',
 PRIM_FILE='W:/<user>/logical/q_res/chips/chips.prt';

PART_NAME
 R714 'Q_RES_0402LF-2K,1%,1/16W,CHIP,A':;

SECTION_NUMBER 1
 '@SCM_LIB.SCM(SCH_1):PAGE27_I165@PURE_QUANTA.Q_RES(CHIPS)':
 C_PATH='@scm_lib.scm(sch_1):page27_i165@pure_quanta.q_res(chips)',
 P_PATH='@scm_lib.scm(sch_1):page27_i165@pure_quanta.q_res(chips)',
 PATH='I165',
 DRAWING='@SCM_LIB.SCM(SCH_1):PAGE27',
 PHYS_PAGE='27',
 XY='(2225,-675)',
 ROT='0',
 VER='1',
 PACK_TYPE='0402LF',
 LOCATION='R714',
 CDS_LIB='pure_quanta',
 CDS_PART_NAME='Q_RES_0402LF-2K,1%,1/16W,CHIP,A',
 WATTAGE='1/16W',
 TOLERANCE='1%',
 MATERIAL='CHIP',
 VALUE='2K',
 PRIM_FILE='W:/<user>/logical/q_res/chips/chips.prt';

PART_NAME
 R715 'Q_RES_0402LF-33.2,1%,1/16W,CHIA':;

SECTION_NUMBER 1
 '@SCM_LIB.SCM(SCH_1):PAGE30_I225@PURE_QUANTA.Q_RES(CHIPS)':
 C_PATH='@scm_lib.scm(sch_1):page30_i225@pure_quanta.q_res(chips)',
 P_PATH='@scm_lib.scm(sch_1):page30_i225@pure_quanta.q_res(chips)',
 PATH='I225',
 DRAWING='@SCM_LIB.SCM(SCH_1):PAGE30',
 SEC_TYPE='0402LF',
 PHYS_PAGE='30',
 XY='(1275,2150)',
 ROT='0',
 VER='1',
 PACK_TYPE='0402LF',
 LOCATION='R715',
 SEC='1',
 CDS_LIB='pure_quanta',
 CDS_PART_NAME='Q_RES_0402LF-33.2,1%,1/16W,CHIA',
 WATTAGE='1/16W',
 TOLERANCE='1%',
 MATERIAL='CHIP',
 VALUE='33.2',
 PRIM_FILE='W:/<user>/logical/q_res/chips/chips.prt';

PART_NAME
 R716 'Q_RES_0402LF-10K,1%,1/16W,CHIPA':;

SECTION_NUMBER 1
 '@SCM_LIB.SCM(SCH_1):PAGE17_I230@PURE_QUANTA.Q_RES(CHIPS)':
 C_PATH='@scm_lib.scm(sch_1):page17_i230@pure_quanta.q_res(chips)',
 P_PATH='@scm_lib.scm(sch_1):page17_i230@pure_quanta.q_res(chips)',
 PATH='I230',
 DRAWING='@SCM_LIB.SCM(SCH_1):PAGE17',
 PHYS_PAGE='17',
 XY='(2825,-600)',
 ROT='0',
 VER='2',
 PACK_TYPE='0402LF',
 LOCATION='R716',
 CDS_LIB='pure_quanta',
 CDS_PART_NAME='Q_RES_0402LF-10K,1%,1/16W,CHIPA',
 WATTAGE='1/16W',
 TOLERANCE='1%',
 MATERIAL='CHIP',
 VALUE='10K',
 PRIM_FILE='W:/<user>/logical/q_res/chips/chips.prt';

PART_NAME
 R717 'Q_RES_0402LF-4.7K,1%,1/16W,CHIA':;

SECTION_NUMBER 1
 '@SCM_LIB.SCM(SCH_1):PAGE15_I174@PURE_QUANTA.Q_RES(CHIPS)':
 C_PATH='@scm_lib.scm(sch_1):page15_i174@pure_quanta.q_res(chips)',
 P_PATH='@scm_lib.scm(sch_1):page15_i174@pure_quanta.q_res(chips)',
 PATH='I174',
 DRAWING='@SCM_LIB.SCM(SCH_1):PAGE15',
 PHYS_PAGE='15',
 XY='(4425,4000)',
 ROT='0',
 VER='1',
 PACK_TYPE='0402LF',
 LOCATION='R717',
 CDS_LIB='pure_quanta',
 CDS_PART_NAME='Q_RES_0402LF-4.7K,1%,1/16W,CHIA',
 WATTAGE='1/16W',
 TOLERANCE='1%',
 MATERIAL='CHIP',
 VALUE='4.7K',
 PRIM_FILE='W:/<user>/logical/q_res/chips/chips.prt';

PART_NAME
 R718 'Q_RES_0402LF-33.2,1%,1/16W,CHIA':;

SECTION_NUMBER 1
 '@SCM_LIB.SCM(SCH_1):PAGE34_I157@PURE_QUANTA.Q_RES(CHIPS)':
 C_PATH='@scm_lib.scm(sch_1):page34_i157@pure_quanta.q_res(chips)',
 P_PATH='@scm_lib.scm(sch_1):page34_i157@pure_quanta.q_res(chips)',
 PATH='I157',
 DRAWING='@SCM_LIB.SCM(SCH_1):PAGE34',
 PHYS_PAGE='34',
 XY='(-7000,4950)',
 ROT='0',
 VER='1',
 PACK_TYPE='0402LF',
 LOCATION='R718',
 CDS_LIB='pure_quanta',
 CDS_PART_NAME='Q_RES_0402LF-33.2,1%,1/16W,CHIA',
 WATTAGE='1/16W',
 TOLERANCE='1%',
 MATERIAL='CHIP',
 VALUE='33.2',
 PRIM_FILE='W:/<user>/logical/q_res/chips/chips.prt';

PART_NAME
 R719 'Q_RES_0402LF-0,5%,1/16W,EMPTY,A':;

SECTION_NUMBER 1
 '@SCM_LIB.SCM(SCH_1):PAGE28_I128@PURE_QUANTA.Q_RES(CHIPS)':
 C_PATH='@scm_lib.scm(sch_1):page28_i128@pure_quanta.q_res(chips)',
 P_PATH='@scm_lib.scm(sch_1):page28_i128@pure_quanta.q_res(chips)',
 PATH='I128',
 DRAWING='@SCM_LIB.SCM(SCH_1):PAGE28',
 PHYS_PAGE='28',
 XY='(2000,-1300)',
 ROT='2',
 VER='1',
 PACK_TYPE='0402LF',
 LOCATION='R719',
 CDS_LIB='pure_quanta',
 CDS_PART_NAME='Q_RES_0402LF-0,5%,1/16W,EMPTY,A',
 WATTAGE='1/16W',
 TOLERANCE='5%',
 MATERIAL='EMPTY',
 VALUE='0',
 PRIM_FILE='W:/<user>/logical/q_res/chips/chips.prt';

PART_NAME
 R720 'Q_RES_0402LF-0,5%,1/16W,CHIP,CA':;

SECTION_NUMBER 1
 '@SCM_LIB.SCM(SCH_1):PAGE28_I144@PURE_QUANTA.Q_RES(CHIPS)':
 C_PATH='@scm_lib.scm(sch_1):page28_i144@pure_quanta.q_res(chips)',
 P_PATH='@scm_lib.scm(sch_1):page28_i144@pure_quanta.q_res(chips)',
 PATH='I144',
 DRAWING='@SCM_LIB.SCM(SCH_1):PAGE28',
 PHYS_PAGE='28',
 XY='(2000,-1625)',
 ROT='2',
 VER='1',
 PACK_TYPE='0402LF',
 LOCATION='R720',
 CDS_LIB='pure_quanta',
 CDS_PART_NAME='Q_RES_0402LF-0,5%,1/16W,CHIP,CA',
 WATTAGE='1/16W',
 TOLERANCE='5%',
 MATERIAL='CHIP',
 VALUE='0',
 PRIM_FILE='W:/<user>/logical/q_res/chips/chips.prt';

PART_NAME
 R721 'Q_RES_0402LF-0,5%,1/16W,CHIP,CA':;

SECTION_NUMBER 1
 '@SCM_LIB.SCM(SCH_1):PAGE28_I145@PURE_QUANTA.Q_RES(CHIPS)':
 C_PATH='@scm_lib.scm(sch_1):page28_i145@pure_quanta.q_res(chips)',
 P_PATH='@scm_lib.scm(sch_1):page28_i145@pure_quanta.q_res(chips)',
 PATH='I145',
 DRAWING='@SCM_LIB.SCM(SCH_1):PAGE28',
 PHYS_PAGE='28',
 XY='(2025,-1825)',
 ROT='2',
 VER='1',
 PACK_TYPE='0402LF',
 LOCATION='R721',
 CDS_LIB='pure_quanta',
 CDS_PART_NAME='Q_RES_0402LF-0,5%,1/16W,CHIP,CA',
 WATTAGE='1/16W',
 TOLERANCE='5%',
 MATERIAL='CHIP',
 VALUE='0',
 PRIM_FILE='W:/<user>/logical/q_res/chips/chips.prt';

PART_NAME
 R722 'Q_RES_0402LF-0,5%,1/16W,CHIP,CA':;

SECTION_NUMBER 1
 '@SCM_LIB.SCM(SCH_1):PAGE13_I350@PURE_QUANTA.Q_RES(CHIPS)':
 C_PATH='@scm_lib.scm(sch_1):page13_i350@pure_quanta.q_res(chips)',
 P_PATH='@scm_lib.scm(sch_1):page13_i350@pure_quanta.q_res(chips)',
 PATH='I350',
 DRAWING='@SCM_LIB.SCM(SCH_1):PAGE13',
 PHYS_PAGE='13',
 XY='(-2175,2875)',
 ROT='2',
 VER='1',
 PACK_TYPE='0402LF',
 LOCATION='R722',
 CDS_LIB='pure_quanta',
 CDS_PART_NAME='Q_RES_0402LF-0,5%,1/16W,CHIP,CA',
 WATTAGE='1/16W',
 TOLERANCE='5%',
 MATERIAL='CHIP',
 VALUE='0',
 PRIM_FILE='W:/<user>/logical/q_res/chips/chips.prt';

PART_NAME
 R724 'Q_RES_0402LF-33.2,1%,1/16W,CHIA':;

SECTION_NUMBER 1
 '@SCM_LIB.SCM(SCH_1):PAGE44_I333@PURE_QUANTA.Q_RES(CHIPS)':
 C_PATH='@scm_lib.scm(sch_1):page44_i333@pure_quanta.q_res(chips)',
 P_PATH='@scm_lib.scm(sch_1):page44_i333@pure_quanta.q_res(chips)',
 PATH='I333',
 DRAWING='@SCM_LIB.SCM(SCH_1):PAGE44',
 PHYS_PAGE='44',
 XY='(-2625,2525)',
 ROT='0',
 VER='1',
 PACK_TYPE='0402LF',
 LOCATION='R724',
 CDS_LIB='pure_quanta',
 CDS_PART_NAME='Q_RES_0402LF-33.2,1%,1/16W,CHIA',
 WATTAGE='1/16W',
 TOLERANCE='1%',
 MATERIAL='CHIP',
 VALUE='33.2',
 PRIM_FILE='W:/<user>/logical/q_res/chips/chips.prt';

PART_NAME
 R725 'Q_RES_0402LF-33.2,1%,1/16W,CHIA':;

SECTION_NUMBER 1
 '@SCM_LIB.SCM(SCH_1):PAGE44_I334@PURE_QUANTA.Q_RES(CHIPS)':
 C_PATH='@scm_lib.scm(sch_1):page44_i334@pure_quanta.q_res(chips)',
 P_PATH='@scm_lib.scm(sch_1):page44_i334@pure_quanta.q_res(chips)',
 PATH='I334',
 DRAWING='@SCM_LIB.SCM(SCH_1):PAGE44',
 PHYS_PAGE='44',
 XY='(-2625,2475)',
 ROT='0',
 VER='1',
 PACK_TYPE='0402LF',
 LOCATION='R725',
 CDS_LIB='pure_quanta',
 CDS_PART_NAME='Q_RES_0402LF-33.2,1%,1/16W,CHIA',
 WATTAGE='1/16W',
 TOLERANCE='1%',
 MATERIAL='CHIP',
 VALUE='33.2',
 PRIM_FILE='W:/<user>/logical/q_res/chips/chips.prt';

PART_NAME
 R726 'Q_RES_0402LF-0,5%,1/16W,CHIP,CA':;

SECTION_NUMBER 1
 '@SCM_LIB.SCM(SCH_1):PAGE30_I266@PURE_QUANTA.Q_RES(CHIPS)':
 C_PATH='@scm_lib.scm(sch_1):page30_i266@pure_quanta.q_res(chips)',
 P_PATH='@scm_lib.scm(sch_1):page30_i266@pure_quanta.q_res(chips)',
 PATH='I266',
 DRAWING='@SCM_LIB.SCM(SCH_1):PAGE30',
 PHYS_PAGE='30',
 XY='(350,3200)',
 ROT='0',
 VER='1',
 PACK_TYPE='0402LF',
 LOCATION='R726',
 CDS_LIB='pure_quanta',
 CDS_PART_NAME='Q_RES_0402LF-0,5%,1/16W,CHIP,CA',
 WATTAGE='1/16W',
 TOLERANCE='5%',
 MATERIAL='CHIP',
 VALUE='0',
 PRIM_FILE='W:/<user>/logical/q_res/chips/chips.prt';

PART_NAME
 R728 'Q_RES_0402LF-0,5%,1/16W,CHIP,CA':;

SECTION_NUMBER 1
 '@SCM_LIB.SCM(SCH_1):PAGE44_I336@PURE_QUANTA.Q_RES(CHIPS)':
 C_PATH='@scm_lib.scm(sch_1):page44_i336@pure_quanta.q_res(chips)',
 P_PATH='@scm_lib.scm(sch_1):page44_i336@pure_quanta.q_res(chips)',
 PATH='I336',
 DRAWING='@SCM_LIB.SCM(SCH_1):PAGE44',
 PHYS_PAGE='44',
 XY='(-2625,2300)',
 ROT='0',
 VER='1',
 PACK_TYPE='0402LF',
 LOCATION='R728',
 CDS_LIB='pure_quanta',
 CDS_PART_NAME='Q_RES_0402LF-0,5%,1/16W,CHIP,CA',
 WATTAGE='1/16W',
 TOLERANCE='5%',
 MATERIAL='CHIP',
 VALUE='0',
 PRIM_FILE='W:/<user>/logical/q_res/chips/chips.prt';

PART_NAME
 R730 'Q_RES_0402LF-4.7K,1%,1/16W,CHIA':;

SECTION_NUMBER 1
 '@SCM_LIB.SCM(SCH_1):PAGE29_I204@PURE_QUANTA.Q_RES(CHIPS)':
 C_PATH='@scm_lib.scm(sch_1):page29_i204@pure_quanta.q_res(chips)',
 P_PATH='@scm_lib.scm(sch_1):page29_i204@pure_quanta.q_res(chips)',
 PATH='I204',
 DRAWING='@SCM_LIB.SCM(SCH_1):PAGE29',
 PHYS_PAGE='29',
 XY='(4650,-175)',
 ROT='2',
 VER='2',
 PACK_TYPE='0402LF',
 LOCATION='R730',
 CDS_LIB='pure_quanta',
 CDS_PART_NAME='Q_RES_0402LF-4.7K,1%,1/16W,CHIA',
 WATTAGE='1/16W',
 TOLERANCE='1%',
 MATERIAL='CHIP',
 VALUE='4.7K',
 PRIM_FILE='W:/<user>/logical/q_res/chips/chips.prt';

PART_NAME
 R731 'Q_RES_0402LF-0,5%,1/16W,CHIP,CA':;

SECTION_NUMBER 1
 '@SCM_LIB.SCM(SCH_1):PAGE29_I135@PURE_QUANTA.Q_RES(CHIPS)':
 C_PATH='@scm_lib.scm(sch_1):page29_i135@pure_quanta.q_res(chips)',
 P_PATH='@scm_lib.scm(sch_1):page29_i135@pure_quanta.q_res(chips)',
 PATH='I135',
 DRAWING='@SCM_LIB.SCM(SCH_1):PAGE29',
 PHYS_PAGE='29',
 XY='(350,-775)',
 ROT='2',
 VER='1',
 PACK_TYPE='0402LF',
 LOCATION='R731',
 CDS_LIB='pure_quanta',
 CDS_PART_NAME='Q_RES_0402LF-0,5%,1/16W,CHIP,CA',
 WATTAGE='1/16W',
 TOLERANCE='5%',
 MATERIAL='CHIP',
 VALUE='0',
 PRIM_FILE='W:/<user>/logical/q_res/chips/chips.prt';

PART_NAME
 R732 'Q_RES_0402LF-0,5%,1/16W,CHIP,CA':;

SECTION_NUMBER 1
 '@SCM_LIB.SCM(SCH_1):PAGE29_I136@PURE_QUANTA.Q_RES(CHIPS)':
 C_PATH='@scm_lib.scm(sch_1):page29_i136@pure_quanta.q_res(chips)',
 P_PATH='@scm_lib.scm(sch_1):page29_i136@pure_quanta.q_res(chips)',
 PATH='I136',
 DRAWING='@SCM_LIB.SCM(SCH_1):PAGE29',
 PHYS_PAGE='29',
 XY='(350,-825)',
 ROT='2',
 VER='1',
 PACK_TYPE='0402LF',
 LOCATION='R732',
 CDS_LIB='pure_quanta',
 CDS_PART_NAME='Q_RES_0402LF-0,5%,1/16W,CHIP,CA',
 WATTAGE='1/16W',
 TOLERANCE='5%',
 MATERIAL='CHIP',
 VALUE='0',
 PRIM_FILE='W:/<user>/logical/q_res/chips/chips.prt';

PART_NAME
 R733 'Q_RES_0402LF-0,5%,1/16W,CHIP,CA':;

SECTION_NUMBER 1
 '@SCM_LIB.SCM(SCH_1):PAGE50_I154@PURE_QUANTA.Q_RES(CHIPS)':
 C_PATH='@scm_lib.scm(sch_1):page50_i154@pure_quanta.q_res(chips)',
 P_PATH='@scm_lib.scm(sch_1):page50_i154@pure_quanta.q_res(chips)',
 PATH='I154',
 DRAWING='@SCM_LIB.SCM(SCH_1):PAGE50',
 PHYS_PAGE='50',
 XY='(-2200,3775)',
 ROT='2',
 VER='1',
 PACK_TYPE='0402LF',
 LOCATION='R733',
 CDS_LIB='pure_quanta',
 CDS_PART_NAME='Q_RES_0402LF-0,5%,1/16W,CHIP,CA',
 WATTAGE='1/16W',
 TOLERANCE='5%',
 MATERIAL='CHIP',
 VALUE='0',
 PRIM_FILE='W:/<user>/logical/q_res/chips/chips.prt';

PART_NAME
 R734 'Q_RES_0402LF-0,5%,1/16W,CHIP,CA':;

SECTION_NUMBER 1
 '@SCM_LIB.SCM(SCH_1):PAGE50_I152@PURE_QUANTA.Q_RES(CHIPS)':
 C_PATH='@scm_lib.scm(sch_1):page50_i152@pure_quanta.q_res(chips)',
 P_PATH='@scm_lib.scm(sch_1):page50_i152@pure_quanta.q_res(chips)',
 PATH='I152',
 DRAWING='@SCM_LIB.SCM(SCH_1):PAGE50',
 PHYS_PAGE='50',
 XY='(-2000,5175)',
 ROT='2',
 VER='1',
 PACK_TYPE='0402LF',
 LOCATION='R734',
 CDS_LIB='pure_quanta',
 CDS_PART_NAME='Q_RES_0402LF-0,5%,1/16W,CHIP,CA',
 WATTAGE='1/16W',
 TOLERANCE='5%',
 MATERIAL='CHIP',
 VALUE='0',
 PRIM_FILE='W:/<user>/logical/q_res/chips/chips.prt';

PART_NAME
 R735 'Q_RES_0402LF-1K,1%,1/16W,CHIP,A':;

SECTION_NUMBER 1
 '@SCM_LIB.SCM(SCH_1):PAGE28_I166@PURE_QUANTA.Q_RES(CHIPS)':
 C_PATH='@scm_lib.scm(sch_1):page28_i166@pure_quanta.q_res(chips)',
 P_PATH='@scm_lib.scm(sch_1):page28_i166@pure_quanta.q_res(chips)',
 PATH='I166',
 DRAWING='@SCM_LIB.SCM(SCH_1):PAGE28',
 PHYS_PAGE='28',
 XY='(2475,-150)',
 ROT='2',
 VER='2',
 PACK_TYPE='0402LF',
 LOCATION='R735',
 CDS_LIB='pure_quanta',
 CDS_PART_NAME='Q_RES_0402LF-1K,1%,1/16W,CHIP,A',
 WATTAGE='1/16W',
 TOLERANCE='1%',
 MATERIAL='CHIP',
 VALUE='1K',
 PRIM_FILE='W:/<user>/logical/q_res/chips/chips.prt';

PART_NAME
 R736 'Q_RES_0402LF-1K,1%,1/16W,CHIP,A':;

SECTION_NUMBER 1
 '@SCM_LIB.SCM(SCH_1):PAGE28_I162@PURE_QUANTA.Q_RES(CHIPS)':
 C_PATH='@scm_lib.scm(sch_1):page28_i162@pure_quanta.q_res(chips)',
 P_PATH='@scm_lib.scm(sch_1):page28_i162@pure_quanta.q_res(chips)',
 PATH='I162',
 DRAWING='@SCM_LIB.SCM(SCH_1):PAGE28',
 PHYS_PAGE='28',
 XY='(2725,700)',
 ROT='0',
 VER='2',
 PACK_TYPE='0402LF',
 LOCATION='R736',
 CDS_LIB='pure_quanta',
 CDS_PART_NAME='Q_RES_0402LF-1K,1%,1/16W,CHIP,A',
 WATTAGE='1/16W',
 TOLERANCE='1%',
 MATERIAL='CHIP',
 VALUE='1K',
 PRIM_FILE='W:/<user>/logical/q_res/chips/chips.prt';

PART_NAME
 R737 'Q_RES_0402LF-4.7K,1%,1/16W,EMPA':;

SECTION_NUMBER 1
 '@SCM_LIB.SCM(SCH_1):PAGE30_I192@PURE_QUANTA.Q_RES(CHIPS)':
 C_PATH='@scm_lib.scm(sch_1):page30_i192@pure_quanta.q_res(chips)',
 P_PATH='@scm_lib.scm(sch_1):page30_i192@pure_quanta.q_res(chips)',
 PATH='I192',
 DRAWING='@SCM_LIB.SCM(SCH_1):PAGE30',
 SEC_TYPE='0402LF',
 PHYS_PAGE='30',
 XY='(1525,3700)',
 ROT='2',
 VER='2',
 PACK_TYPE='0402LF',
 LOCATION='R737',
 SEC='1',
 CDS_LIB='pure_quanta',
 CDS_PART_NAME='Q_RES_0402LF-4.7K,1%,1/16W,EMPA',
 WATTAGE='1/16W',
 TOLERANCE='1%',
 MATERIAL='EMPTY',
 VALUE='4.7K',
 PRIM_FILE='W:/<user>/logical/q_res/chips/chips.prt';

PART_NAME
 R738 'Q_RES_0402LF-4.7K,1%,1/16W,CHIA':;

SECTION_NUMBER 1
 '@SCM_LIB.SCM(SCH_1):PAGE28_I171@PURE_QUANTA.Q_RES(CHIPS)':
 C_PATH='@scm_lib.scm(sch_1):page28_i171@pure_quanta.q_res(chips)',
 P_PATH='@scm_lib.scm(sch_1):page28_i171@pure_quanta.q_res(chips)',
 PATH='I171',
 DRAWING='@SCM_LIB.SCM(SCH_1):PAGE28',
 SEC_TYPE='0402LF',
 PHYS_PAGE='28',
 XY='(-3950,875)',
 ROT='0',
 VER='2',
 PACK_TYPE='0402LF',
 LOCATION='R738',
 SEC='1',
 CDS_LIB='pure_quanta',
 CDS_PART_NAME='Q_RES_0402LF-4.7K,1%,1/16W,CHIA',
 WATTAGE='1/16W',
 TOLERANCE='1%',
 MATERIAL='CHIP',
 VALUE='4.7K',
 PRIM_FILE='W:/<user>/logical/q_res/chips/chips.prt';

PART_NAME
 R739 'Q_RES_0402LF-4.7K,1%,1/16W,CHIA':;

SECTION_NUMBER 1
 '@SCM_LIB.SCM(SCH_1):PAGE28_I169@PURE_QUANTA.Q_RES(CHIPS)':
 C_PATH='@scm_lib.scm(sch_1):page28_i169@pure_quanta.q_res(chips)',
 P_PATH='@scm_lib.scm(sch_1):page28_i169@pure_quanta.q_res(chips)',
 PATH='I169',
 DRAWING='@SCM_LIB.SCM(SCH_1):PAGE28',
 SEC_TYPE='0402LF',
 PHYS_PAGE='28',
 XY='(-3600,875)',
 ROT='0',
 VER='2',
 PACK_TYPE='0402LF',
 LOCATION='R739',
 SEC='1',
 CDS_LIB='pure_quanta',
 CDS_PART_NAME='Q_RES_0402LF-4.7K,1%,1/16W,CHIA',
 WATTAGE='1/16W',
 TOLERANCE='1%',
 MATERIAL='CHIP',
 VALUE='4.7K',
 PRIM_FILE='W:/<user>/logical/q_res/chips/chips.prt';

PART_NAME
 R740 'Q_RES_0402LF-4.7K,1%,1/16W,CHIA':;

SECTION_NUMBER 1
 '@SCM_LIB.SCM(SCH_1):PAGE28_I168@PURE_QUANTA.Q_RES(CHIPS)':
 C_PATH='@scm_lib.scm(sch_1):page28_i168@pure_quanta.q_res(chips)',
 P_PATH='@scm_lib.scm(sch_1):page28_i168@pure_quanta.q_res(chips)',
 PATH='I168',
 DRAWING='@SCM_LIB.SCM(SCH_1):PAGE28',
 SEC_TYPE='0402LF',
 PHYS_PAGE='28',
 XY='(-3250,875)',
 ROT='0',
 VER='2',
 PACK_TYPE='0402LF',
 LOCATION='R740',
 SEC='1',
 CDS_LIB='pure_quanta',
 CDS_PART_NAME='Q_RES_0402LF-4.7K,1%,1/16W,CHIA',
 WATTAGE='1/16W',
 TOLERANCE='1%',
 MATERIAL='CHIP',
 VALUE='4.7K',
 PRIM_FILE='W:/<user>/logical/q_res/chips/chips.prt';

PART_NAME
 R741 'Q_RES_0402LF-4.7K,1%,1/16W,CHIA':;

SECTION_NUMBER 1
 '@SCM_LIB.SCM(SCH_1):PAGE30_I197@PURE_QUANTA.Q_RES(CHIPS)':
 C_PATH='@scm_lib.scm(sch_1):page30_i197@pure_quanta.q_res(chips)',
 P_PATH='@scm_lib.scm(sch_1):page30_i197@pure_quanta.q_res(chips)',
 PATH='I197',
 DRAWING='@SCM_LIB.SCM(SCH_1):PAGE30',
 SEC_TYPE='0402LF',
 PHYS_PAGE='30',
 XY='(850,1275)',
 ROT='2',
 VER='2',
 PACK_TYPE='0402LF',
 LOCATION='R741',
 SEC='1',
 CDS_LIB='pure_quanta',
 CDS_PART_NAME='Q_RES_0402LF-4.7K,1%,1/16W,CHIA',
 WATTAGE='1/16W',
 TOLERANCE='1%',
 MATERIAL='CHIP',
 VALUE='4.7K',
 PRIM_FILE='W:/<user>/logical/q_res/chips/chips.prt';

PART_NAME
 R742 'Q_RES_0402LF-4.7K,1%,1/16W,EMPA':;

SECTION_NUMBER 1
 '@SCM_LIB.SCM(SCH_1):PAGE30_I195@PURE_QUANTA.Q_RES(CHIPS)':
 C_PATH='@scm_lib.scm(sch_1):page30_i195@pure_quanta.q_res(chips)',
 P_PATH='@scm_lib.scm(sch_1):page30_i195@pure_quanta.q_res(chips)',
 PATH='I195',
 DRAWING='@SCM_LIB.SCM(SCH_1):PAGE30',
 SEC_TYPE='0402LF',
 PHYS_PAGE='30',
 XY='(1675,4725)',
 ROT='2',
 VER='2',
 PACK_TYPE='0402LF',
 LOCATION='R742',
 SEC='1',
 CDS_LIB='pure_quanta',
 CDS_PART_NAME='Q_RES_0402LF-4.7K,1%,1/16W,EMPA',
 WATTAGE='1/16W',
 TOLERANCE='1%',
 MATERIAL='EMPTY',
 VALUE='4.7K',
 PRIM_FILE='W:/<user>/logical/q_res/chips/chips.prt';

PART_NAME
 R743 'Q_RES_0402LF-100,1%,1/16W,EMPTA':;

SECTION_NUMBER 1
 '@SCM_LIB.SCM(SCH_1):PAGE28_I175@PURE_QUANTA.Q_RES(CHIPS)':
 C_PATH='@scm_lib.scm(sch_1):page28_i175@pure_quanta.q_res(chips)',
 P_PATH='@scm_lib.scm(sch_1):page28_i175@pure_quanta.q_res(chips)',
 PATH='I175',
 DRAWING='@SCM_LIB.SCM(SCH_1):PAGE28',
 PHYS_PAGE='28',
 XY='(-3950,200)',
 ROT='0',
 VER='2',
 PACK_TYPE='0402LF',
 LOCATION='R743',
 CDS_LIB='pure_quanta',
 CDS_PART_NAME='Q_RES_0402LF-100,1%,1/16W,EMPTA',
 WATTAGE='1/16W',
 TOLERANCE='1%',
 MATERIAL='EMPTY',
 VALUE='100',
 PRIM_FILE='W:/<user>/logical/q_res/chips/chips.prt';

PART_NAME
 R744 'Q_RES_0402LF-100,1%,1/16W,EMPTA':;

SECTION_NUMBER 1
 '@SCM_LIB.SCM(SCH_1):PAGE28_I173@PURE_QUANTA.Q_RES(CHIPS)':
 C_PATH='@scm_lib.scm(sch_1):page28_i173@pure_quanta.q_res(chips)',
 P_PATH='@scm_lib.scm(sch_1):page28_i173@pure_quanta.q_res(chips)',
 PATH='I173',
 DRAWING='@SCM_LIB.SCM(SCH_1):PAGE28',
 PHYS_PAGE='28',
 XY='(-3600,200)',
 ROT='0',
 VER='2',
 PACK_TYPE='0402LF',
 LOCATION='R744',
 CDS_LIB='pure_quanta',
 CDS_PART_NAME='Q_RES_0402LF-100,1%,1/16W,EMPTA',
 WATTAGE='1/16W',
 TOLERANCE='1%',
 MATERIAL='EMPTY',
 VALUE='100',
 PRIM_FILE='W:/<user>/logical/q_res/chips/chips.prt';

PART_NAME
 R745 'Q_RES_0402LF-100,1%,1/16W,EMPTA':;

SECTION_NUMBER 1
 '@SCM_LIB.SCM(SCH_1):PAGE28_I172@PURE_QUANTA.Q_RES(CHIPS)':
 C_PATH='@scm_lib.scm(sch_1):page28_i172@pure_quanta.q_res(chips)',
 P_PATH='@scm_lib.scm(sch_1):page28_i172@pure_quanta.q_res(chips)',
 PATH='I172',
 DRAWING='@SCM_LIB.SCM(SCH_1):PAGE28',
 PHYS_PAGE='28',
 XY='(-3250,200)',
 ROT='0',
 VER='2',
 PACK_TYPE='0402LF',
 LOCATION='R745',
 CDS_LIB='pure_quanta',
 CDS_PART_NAME='Q_RES_0402LF-100,1%,1/16W,EMPTA',
 WATTAGE='1/16W',
 TOLERANCE='1%',
 MATERIAL='EMPTY',
 VALUE='100',
 PRIM_FILE='W:/<user>/logical/q_res/chips/chips.prt';

PART_NAME
 R746 'Q_RES_0402LF-0,5%,1/16W,CHIP,CA':;

SECTION_NUMBER 1
 '@SCM_LIB.SCM(SCH_1):PAGE36_I10@PURE_QUANTA.Q_RES(CHIPS)':
 C_PATH='@scm_lib.scm(sch_1):page36_i10@pure_quanta.q_res(chips)',
 P_PATH='@scm_lib.scm(sch_1):page36_i10@pure_quanta.q_res(chips)',
 PATH='I10',
 DRAWING='@SCM_LIB.SCM(SCH_1):PAGE36',
 SEC_TYPE='0402LF',
 PHYS_PAGE='36',
 XY='(-7250,4675)',
 ROT='0',
 VER='1',
 PACK_TYPE='0402LF',
 LOCATION='R746',
 SEC='1',
 CDS_LIB='pure_quanta',
 CDS_PART_NAME='Q_RES_0402LF-0,5%,1/16W,CHIP,CA',
 WATTAGE='1/16W',
 TOLERANCE='5%',
 MATERIAL='CHIP',
 VALUE='0',
 PRIM_FILE='W:/<user>/logical/q_res/chips/chips.prt';

PART_NAME
 R747 'Q_RES_0402LF-0,5%,1/16W,CHIP,CA':;

SECTION_NUMBER 1
 '@SCM_LIB.SCM(SCH_1):PAGE36_I9@PURE_QUANTA.Q_RES(CHIPS)':
 C_PATH='@scm_lib.scm(sch_1):page36_i9@pure_quanta.q_res(chips)',
 P_PATH='@scm_lib.scm(sch_1):page36_i9@pure_quanta.q_res(chips)',
 PATH='I9',
 DRAWING='@SCM_LIB.SCM(SCH_1):PAGE36',
 SEC_TYPE='0402LF',
 PHYS_PAGE='36',
 XY='(-7250,4625)',
 ROT='0',
 VER='1',
 PACK_TYPE='0402LF',
 LOCATION='R747',
 SEC='1',
 CDS_LIB='pure_quanta',
 CDS_PART_NAME='Q_RES_0402LF-0,5%,1/16W,CHIP,CA',
 WATTAGE='1/16W',
 TOLERANCE='5%',
 MATERIAL='CHIP',
 VALUE='0',
 PRIM_FILE='W:/<user>/logical/q_res/chips/chips.prt';

PART_NAME
 R748 'Q_RES_0402LF-0,5%,1/16W,CHIP,CA':;

SECTION_NUMBER 1
 '@SCM_LIB.SCM(SCH_1):PAGE36_I78@PURE_QUANTA.Q_RES(CHIPS)':
 C_PATH='@scm_lib.scm(sch_1):page36_i78@pure_quanta.q_res(chips)',
 P_PATH='@scm_lib.scm(sch_1):page36_i78@pure_quanta.q_res(chips)',
 PATH='I78',
 DRAWING='@SCM_LIB.SCM(SCH_1):PAGE36',
 PHYS_PAGE='36',
 XY='(-1900,4225)',
 ROT='0',
 VER='1',
 PACK_TYPE='0402LF',
 LOCATION='R748',
 CDS_LIB='pure_quanta',
 CDS_PART_NAME='Q_RES_0402LF-0,5%,1/16W,CHIP,CA',
 WATTAGE='1/16W',
 TOLERANCE='5%',
 MATERIAL='CHIP',
 VALUE='0',
 PRIM_FILE='W:/<user>/logical/q_res/chips/chips.prt';

PART_NAME
 R749 'Q_RES_0402LF-4.7K,1%,1/16W,CHIA':;

SECTION_NUMBER 1
 '@SCM_LIB.SCM(SCH_1):PAGE42_I61@PURE_QUANTA.Q_RES(CHIPS)':
 C_PATH='@scm_lib.scm(sch_1):page42_i61@pure_quanta.q_res(chips)',
 P_PATH='@scm_lib.scm(sch_1):page42_i61@pure_quanta.q_res(chips)',
 PATH='I61',
 DRAWING='@SCM_LIB.SCM(SCH_1):PAGE42',
 PHYS_PAGE='42',
 XY='(8500,950)',
 ROT='0',
 VER='1',
 PACK_TYPE='0402LF',
 LOCATION='R749',
 CDS_LIB='pure_quanta',
 CDS_PART_NAME='Q_RES_0402LF-4.7K,1%,1/16W,CHIA',
 WATTAGE='1/16W',
 TOLERANCE='1%',
 MATERIAL='CHIP',
 VALUE='4.7K',
 PRIM_FILE='W:/<user>/logical/q_res/chips/chips.prt';

PART_NAME
 R750 'Q_RES_0402LF-33.2,1%,1/16W,CHIA':;

SECTION_NUMBER 1
 '@SCM_LIB.SCM(SCH_1):PAGE36_I82@PURE_QUANTA.Q_RES(CHIPS)':
 C_PATH='@scm_lib.scm(sch_1):page36_i82@pure_quanta.q_res(chips)',
 P_PATH='@scm_lib.scm(sch_1):page36_i82@pure_quanta.q_res(chips)',
 PATH='I82',
 DRAWING='@SCM_LIB.SCM(SCH_1):PAGE36',
 PHYS_PAGE='36',
 XY='(-7250,4525)',
 ROT='0',
 VER='1',
 PACK_TYPE='0402LF',
 LOCATION='R750',
 CDS_LIB='pure_quanta',
 CDS_PART_NAME='Q_RES_0402LF-33.2,1%,1/16W,CHIA',
 WATTAGE='1/16W',
 TOLERANCE='1%',
 MATERIAL='CHIP',
 VALUE='33.2',
 PRIM_FILE='W:/<user>/logical/q_res/chips/chips.prt';

PART_NAME
 R751 'Q_RES_0402LF-2K,1%,1/16W,CHIP,A':;

SECTION_NUMBER 1
 '@SCM_LIB.SCM(SCH_1):PAGE22_I83@PURE_QUANTA.Q_RES(CHIPS)':
 C_PATH='@scm_lib.scm(sch_1):page22_i83@pure_quanta.q_res(chips)',
 P_PATH='@scm_lib.scm(sch_1):page22_i83@pure_quanta.q_res(chips)',
 PATH='I83',
 DRAWING='@SCM_LIB.SCM(SCH_1):PAGE22',
 PHYS_PAGE='22',
 XY='(-2600,200)',
 ROT='0',
 VER='2',
 PACK_TYPE='0402LF',
 LOCATION='R751',
 CDS_LIB='pure_quanta',
 CDS_PART_NAME='Q_RES_0402LF-2K,1%,1/16W,CHIP,A',
 WATTAGE='1/16W',
 TOLERANCE='1%',
 MATERIAL='CHIP',
 VALUE='2K',
 PRIM_FILE='W:/<user>/logical/q_res/chips/chips.prt';

PART_NAME
 R752 'Q_RES_0402LF-33.2,1%,1/16W,CHIA':;

SECTION_NUMBER 1
 '@SCM_LIB.SCM(SCH_1):PAGE25_I67@PURE_QUANTA.Q_RES(CHIPS)':
 C_PATH='@scm_lib.scm(sch_1):page25_i67@pure_quanta.q_res(chips)',
 P_PATH='@scm_lib.scm(sch_1):page25_i67@pure_quanta.q_res(chips)',
 PATH='I67',
 DRAWING='@SCM_LIB.SCM(SCH_1):PAGE25',
 PHYS_PAGE='25',
 XY='(-925,-950)',
 ROT='0',
 VER='1',
 PACK_TYPE='0402LF',
 LOCATION='R752',
 CDS_LIB='pure_quanta',
 CDS_PART_NAME='Q_RES_0402LF-33.2,1%,1/16W,CHIA',
 WATTAGE='1/16W',
 TOLERANCE='1%',
 MATERIAL='CHIP',
 VALUE='33.2',
 PRIM_FILE='W:/<user>/logical/q_res/chips/chips.prt';

PART_NAME
 R753 'Q_RES_0402LF-4.7K,1%,1/16W,EMPA':;

SECTION_NUMBER 1
 '@SCM_LIB.SCM(SCH_1):PAGE27_I233@PURE_QUANTA.Q_RES(CHIPS)':
 C_PATH='@scm_lib.scm(sch_1):page27_i233@pure_quanta.q_res(chips)',
 P_PATH='@scm_lib.scm(sch_1):page27_i233@pure_quanta.q_res(chips)',
 PATH='I233',
 DRAWING='@SCM_LIB.SCM(SCH_1):PAGE27',
 PHYS_PAGE='27',
 XY='(-2825,-150)',
 ROT='0',
 VER='2',
 PACK_TYPE='0402LF',
 LOCATION='R753',
 CDS_LIB='pure_quanta',
 CDS_PART_NAME='Q_RES_0402LF-4.7K,1%,1/16W,EMPA',
 WATTAGE='1/16W',
 TOLERANCE='1%',
 MATERIAL='EMPTY',
 VALUE='4.7K',
 PRIM_FILE='W:/<user>/logical/q_res/chips/chips.prt';

PART_NAME
 R754 'Q_RES_0402LF-4.7K,1%,1/16W,EMPA':;

SECTION_NUMBER 1
 '@SCM_LIB.SCM(SCH_1):PAGE27_I213@PURE_QUANTA.Q_RES(CHIPS)':
 C_PATH='@scm_lib.scm(sch_1):page27_i213@pure_quanta.q_res(chips)',
 P_PATH='@scm_lib.scm(sch_1):page27_i213@pure_quanta.q_res(chips)',
 PATH='I213',
 DRAWING='@SCM_LIB.SCM(SCH_1):PAGE27',
 PHYS_PAGE='27',
 XY='(-675,2725)',
 ROT='0',
 VER='1',
 PACK_TYPE='0402LF',
 LOCATION='R754',
 CDS_LIB='pure_quanta',
 CDS_PART_NAME='Q_RES_0402LF-4.7K,1%,1/16W,EMPA',
 WATTAGE='1/16W',
 TOLERANCE='1%',
 MATERIAL='EMPTY',
 VALUE='4.7K',
 PRIM_FILE='W:/<user>/logical/q_res/chips/chips.prt';

PART_NAME
 R757 'Q_RES_0402LF-33.2,1%,1/16W,CHIA':;

SECTION_NUMBER 1
 '@SCM_LIB.SCM(SCH_1):PAGE30_I226@PURE_QUANTA.Q_RES(CHIPS)':
 C_PATH='@scm_lib.scm(sch_1):page30_i226@pure_quanta.q_res(chips)',
 P_PATH='@scm_lib.scm(sch_1):page30_i226@pure_quanta.q_res(chips)',
 PATH='I226',
 DRAWING='@SCM_LIB.SCM(SCH_1):PAGE30',
 SEC_TYPE='0402LF',
 PHYS_PAGE='30',
 XY='(1275,2050)',
 ROT='0',
 VER='1',
 PACK_TYPE='0402LF',
 LOCATION='R757',
 SEC='1',
 CDS_LIB='pure_quanta',
 CDS_PART_NAME='Q_RES_0402LF-33.2,1%,1/16W,CHIA',
 WATTAGE='1/16W',
 TOLERANCE='1%',
 MATERIAL='CHIP',
 VALUE='33.2',
 PRIM_FILE='W:/<user>/logical/q_res/chips/chips.prt';

PART_NAME
 R758 'Q_RES_0402LF-4.7K,1%,1/16W,CHIA':;

SECTION_NUMBER 1
 '@SCM_LIB.SCM(SCH_1):PAGE30_I221@PURE_QUANTA.Q_RES(CHIPS)':
 C_PATH='@scm_lib.scm(sch_1):page30_i221@pure_quanta.q_res(chips)',
 P_PATH='@scm_lib.scm(sch_1):page30_i221@pure_quanta.q_res(chips)',
 PATH='I221',
 DRAWING='@SCM_LIB.SCM(SCH_1):PAGE30',
 SEC_TYPE='0402LF',
 PHYS_PAGE='30',
 XY='(2200,2375)',
 ROT='2',
 VER='2',
 PACK_TYPE='0402LF',
 LOCATION='R758',
 SEC='1',
 CDS_LIB='pure_quanta',
 CDS_PART_NAME='Q_RES_0402LF-4.7K,1%,1/16W,CHIA',
 WATTAGE='1/16W',
 TOLERANCE='1%',
 MATERIAL='CHIP',
 VALUE='4.7K',
 PRIM_FILE='W:/<user>/logical/q_res/chips/chips.prt';

PART_NAME
 R759 'Q_RES_0402LF-33.2,1%,1/16W,CHIA':;

SECTION_NUMBER 1
 '@SCM_LIB.SCM(SCH_1):PAGE13_I208@PURE_QUANTA.Q_RES(CHIPS)':
 C_PATH='@scm_lib.scm(sch_1):page13_i208@pure_quanta.q_res(chips)',
 P_PATH='@scm_lib.scm(sch_1):page13_i208@pure_quanta.q_res(chips)',
 PATH='I208',
 DRAWING='@SCM_LIB.SCM(SCH_1):PAGE13',
 PHYS_PAGE='13',
 XY='(2875,1975)',
 ROT='0',
 VER='1',
 PACK_TYPE='0402LF',
 LOCATION='R759',
 CDS_LIB='pure_quanta',
 CDS_PART_NAME='Q_RES_0402LF-33.2,1%,1/16W,CHIA',
 WATTAGE='1/16W',
 TOLERANCE='1%',
 MATERIAL='CHIP',
 VALUE='33.2',
 PRIM_FILE='W:/<user>/logical/q_res/chips/chips.prt';

PART_NAME
 R760 'Q_RES_0402LF-33.2,1%,1/16W,CHIA':;

SECTION_NUMBER 1
 '@SCM_LIB.SCM(SCH_1):PAGE13_I400@PURE_QUANTA.Q_RES(CHIPS)':
 C_PATH='@scm_lib.scm(sch_1):page13_i400@pure_quanta.q_res(chips)',
 P_PATH='@scm_lib.scm(sch_1):page13_i400@pure_quanta.q_res(chips)',
 PATH='I400',
 DRAWING='@SCM_LIB.SCM(SCH_1):PAGE13',
 PHYS_PAGE='13',
 XY='(-2200,1175)',
 ROT='0',
 VER='1',
 PACK_TYPE='0402LF',
 LOCATION='R760',
 CDS_LIB='pure_quanta',
 CDS_PART_NAME='Q_RES_0402LF-33.2,1%,1/16W,CHIA',
 WATTAGE='1/16W',
 TOLERANCE='1%',
 MATERIAL='CHIP',
 VALUE='33.2',
 PRIM_FILE='W:/<user>/logical/q_res/chips/chips.prt';

PART_NAME
 R761 'Q_RES_0402LF-33.2,1%,1/16W,CHIA':;

SECTION_NUMBER 1
 '@SCM_LIB.SCM(SCH_1):PAGE12_I473@PURE_QUANTA.Q_RES(CHIPS)':
 C_PATH='@scm_lib.scm(sch_1):page12_i473@pure_quanta.q_res(chips)',
 P_PATH='@scm_lib.scm(sch_1):page12_i473@pure_quanta.q_res(chips)',
 PATH='I473',
 DRAWING='@SCM_LIB.SCM(SCH_1):PAGE12',
 PHYS_PAGE='12',
 XY='(-850,1100)',
 ROT='0',
 VER='1',
 PACK_TYPE='0402LF',
 LOCATION='R761',
 CDS_LIB='pure_quanta',
 CDS_PART_NAME='Q_RES_0402LF-33.2,1%,1/16W,CHIA',
 WATTAGE='1/16W',
 TOLERANCE='1%',
 MATERIAL='CHIP',
 VALUE='33.2',
 PRIM_FILE='W:/<user>/logical/q_res/chips/chips.prt';

PART_NAME
 R762 'Q_RES_0402LF-33.2,1%,1/16W,CHIA':;

SECTION_NUMBER 1
 '@SCM_LIB.SCM(SCH_1):PAGE12_I474@PURE_QUANTA.Q_RES(CHIPS)':
 C_PATH='@scm_lib.scm(sch_1):page12_i474@pure_quanta.q_res(chips)',
 P_PATH='@scm_lib.scm(sch_1):page12_i474@pure_quanta.q_res(chips)',
 PATH='I474',
 DRAWING='@SCM_LIB.SCM(SCH_1):PAGE12',
 PHYS_PAGE='12',
 XY='(-850,1050)',
 ROT='0',
 VER='1',
 PACK_TYPE='0402LF',
 LOCATION='R762',
 CDS_LIB='pure_quanta',
 CDS_PART_NAME='Q_RES_0402LF-33.2,1%,1/16W,CHIA',
 WATTAGE='1/16W',
 TOLERANCE='1%',
 MATERIAL='CHIP',
 VALUE='33.2',
 PRIM_FILE='W:/<user>/logical/q_res/chips/chips.prt';

PART_NAME
 R763 'Q_RES_0402LF-33.2,1%,1/16W,CHIA':;

SECTION_NUMBER 1
 '@SCM_LIB.SCM(SCH_1):PAGE13_I402@PURE_QUANTA.Q_RES(CHIPS)':
 C_PATH='@scm_lib.scm(sch_1):page13_i402@pure_quanta.q_res(chips)',
 P_PATH='@scm_lib.scm(sch_1):page13_i402@pure_quanta.q_res(chips)',
 PATH='I402',
 DRAWING='@SCM_LIB.SCM(SCH_1):PAGE13',
 PHYS_PAGE='13',
 XY='(-2200,1775)',
 ROT='0',
 VER='1',
 PACK_TYPE='0402LF',
 LOCATION='R763',
 CDS_LIB='pure_quanta',
 CDS_PART_NAME='Q_RES_0402LF-33.2,1%,1/16W,CHIA',
 WATTAGE='1/16W',
 TOLERANCE='1%',
 MATERIAL='CHIP',
 VALUE='33.2',
 PRIM_FILE='W:/<user>/logical/q_res/chips/chips.prt';

PART_NAME
 R764 'Q_RES_0402LF-0,5%,1/16W,EMPTY,A':;

SECTION_NUMBER 1
 '@SCM_LIB.SCM(SCH_1):PAGE55_I41@PURE_QUANTA.Q_RES(CHIPS)':
 C_PATH='@scm_lib.scm(sch_1):page55_i41@pure_quanta.q_res(chips)',
 P_PATH='@scm_lib.scm(sch_1):page55_i41@pure_quanta.q_res(chips)',
 PATH='I41',
 DRAWING='@SCM_LIB.SCM(SCH_1):PAGE55',
 PHYS_PAGE='55',
 XY='(-1700,575)',
 ROT='0',
 VER='1',
 PACK_TYPE='0402LF',
 LOCATION='R764',
 CDS_LIB='pure_quanta',
 CDS_PART_NAME='Q_RES_0402LF-0,5%,1/16W,EMPTY,A',
 WATTAGE='1/16W',
 TOLERANCE='5%',
 MATERIAL='EMPTY',
 VALUE='0',
 PRIM_FILE='W:/<user>/logical/q_res/chips/chips.prt';

PART_NAME
 R765 'Q_RES_0402LF-4.7K,1%,1/16W,CHIA':;

SECTION_NUMBER 1
 '@SCM_LIB.SCM(SCH_1):PAGE30_I239@PURE_QUANTA.Q_RES(CHIPS)':
 C_PATH='@scm_lib.scm(sch_1):page30_i239@pure_quanta.q_res(chips)',
 P_PATH='@scm_lib.scm(sch_1):page30_i239@pure_quanta.q_res(chips)',
 PATH='I239',
 DRAWING='@SCM_LIB.SCM(SCH_1):PAGE30',
 SEC_TYPE='0402LF',
 PHYS_PAGE='30',
 XY='(3675,1250)',
 ROT='2',
 VER='2',
 PACK_TYPE='0402LF',
 LOCATION='R765',
 SEC='1',
 CDS_LIB='pure_quanta',
 CDS_PART_NAME='Q_RES_0402LF-4.7K,1%,1/16W,CHIA',
 WATTAGE='1/16W',
 TOLERANCE='1%',
 MATERIAL='CHIP',
 VALUE='4.7K',
 PRIM_FILE='W:/<user>/logical/q_res/chips/chips.prt';

PART_NAME
 R766 'Q_RES_0402LF-33.2,1%,1/16W,CHIA':;

SECTION_NUMBER 1
 '@SCM_LIB.SCM(SCH_1):PAGE30_I237@PURE_QUANTA.Q_RES(CHIPS)':
 C_PATH='@scm_lib.scm(sch_1):page30_i237@pure_quanta.q_res(chips)',
 P_PATH='@scm_lib.scm(sch_1):page30_i237@pure_quanta.q_res(chips)',
 PATH='I237',
 DRAWING='@SCM_LIB.SCM(SCH_1):PAGE30',
 SEC_TYPE='0402LF',
 PHYS_PAGE='30',
 XY='(4900,2675)',
 ROT='0',
 VER='1',
 PACK_TYPE='0402LF',
 LOCATION='R766',
 SEC='1',
 CDS_LIB='pure_quanta',
 CDS_PART_NAME='Q_RES_0402LF-33.2,1%,1/16W,CHIA',
 WATTAGE='1/16W',
 TOLERANCE='1%',
 MATERIAL='CHIP',
 VALUE='33.2',
 PRIM_FILE='W:/<user>/logical/q_res/chips/chips.prt';

PART_NAME
 R767 'Q_RES_0402LF-33.2,1%,1/16W,CHIA':;

SECTION_NUMBER 1
 '@SCM_LIB.SCM(SCH_1):PAGE34_I150@PURE_QUANTA.Q_RES(CHIPS)':
 C_PATH='@scm_lib.scm(sch_1):page34_i150@pure_quanta.q_res(chips)',
 P_PATH='@scm_lib.scm(sch_1):page34_i150@pure_quanta.q_res(chips)',
 PATH='I150',
 DRAWING='@SCM_LIB.SCM(SCH_1):PAGE34',
 PHYS_PAGE='34',
 XY='(-7000,5200)',
 ROT='0',
 VER='1',
 PACK_TYPE='0402LF',
 LOCATION='R767',
 CDS_LIB='pure_quanta',
 CDS_PART_NAME='Q_RES_0402LF-33.2,1%,1/16W,CHIA',
 WATTAGE='1/16W',
 TOLERANCE='1%',
 MATERIAL='CHIP',
 VALUE='33.2',
 PRIM_FILE='W:/<user>/logical/q_res/chips/chips.prt';

PART_NAME
 R768 'Q_RES_0402LF-8.2K,5%,1/16W,CHIA':;

SECTION_NUMBER 1
 '@SCM_LIB.SCM(SCH_1):PAGE50_I89@PURE_QUANTA.Q_RES(CHIPS)':
 C_PATH='@scm_lib.scm(sch_1):page50_i89@pure_quanta.q_res(chips)',
 P_PATH='@scm_lib.scm(sch_1):page50_i89@pure_quanta.q_res(chips)',
 PATH='I89',
 DRAWING='@SCM_LIB.SCM(SCH_1):PAGE50',
 PHYS_PAGE='50',
 XY='(-1175,5050)',
 ROT='0',
 VER='2',
 PACK_TYPE='0402LF',
 LOCATION='R768',
 CDS_LIB='pure_quanta',
 CDS_PART_NAME='Q_RES_0402LF-8.2K,5%,1/16W,CHIA',
 WATTAGE='1/16W',
 TOLERANCE='5%',
 MATERIAL='CHIP',
 VALUE='8.2K',
 PRIM_FILE='W:/<user>/logical/q_res/chips/chips.prt';

PART_NAME
 R769 'Q_RES_0402LF-33.2,1%,1/16W,CHIA':;

SECTION_NUMBER 1
 '@SCM_LIB.SCM(SCH_1):PAGE35_I140@PURE_QUANTA.Q_RES(CHIPS)':
 C_PATH='@scm_lib.scm(sch_1):page35_i140@pure_quanta.q_res(chips)',
 P_PATH='@scm_lib.scm(sch_1):page35_i140@pure_quanta.q_res(chips)',
 PATH='I140',
 DRAWING='@SCM_LIB.SCM(SCH_1):PAGE35',
 PHYS_PAGE='35',
 XY='(-7300,4300)',
 ROT='0',
 VER='1',
 PACK_TYPE='0402LF',
 LOCATION='R769',
 CDS_LIB='pure_quanta',
 CDS_PART_NAME='Q_RES_0402LF-33.2,1%,1/16W,CHIA',
 WATTAGE='1/16W',
 TOLERANCE='1%',
 MATERIAL='CHIP',
 VALUE='33.2',
 PRIM_FILE='W:/<user>/logical/q_res/chips/chips.prt';

PART_NAME
 R770 'Q_RES_0402LF-4.7K,1%,1/16W,EMPA':;

SECTION_NUMBER 1
 '@SCM_LIB.SCM(SCH_1):PAGE27_I217@PURE_QUANTA.Q_RES(CHIPS)':
 C_PATH='@scm_lib.scm(sch_1):page27_i217@pure_quanta.q_res(chips)',
 P_PATH='@scm_lib.scm(sch_1):page27_i217@pure_quanta.q_res(chips)',
 PATH='I217',
 DRAWING='@SCM_LIB.SCM(SCH_1):PAGE27',
 PHYS_PAGE='27',
 XY='(-675,2525)',
 ROT='0',
 VER='1',
 PACK_TYPE='0402LF',
 LOCATION='R770',
 CDS_LIB='pure_quanta',
 CDS_PART_NAME='Q_RES_0402LF-4.7K,1%,1/16W,EMPA',
 WATTAGE='1/16W',
 TOLERANCE='1%',
 MATERIAL='EMPTY',
 VALUE='4.7K',
 PRIM_FILE='W:/<user>/logical/q_res/chips/chips.prt';

PART_NAME
 R773 'Q_RES_0402LF-33.2,1%,1/16W,CHIA':;

SECTION_NUMBER 1
 '@SCM_LIB.SCM(SCH_1):PAGE35_I137@PURE_QUANTA.Q_RES(CHIPS)':
 C_PATH='@scm_lib.scm(sch_1):page35_i137@pure_quanta.q_res(chips)',
 P_PATH='@scm_lib.scm(sch_1):page35_i137@pure_quanta.q_res(chips)',
 PATH='I137',
 DRAWING='@SCM_LIB.SCM(SCH_1):PAGE35',
 PHYS_PAGE='35',
 XY='(-7300,4500)',
 ROT='0',
 VER='1',
 PACK_TYPE='0402LF',
 LOCATION='R773',
 CDS_LIB='pure_quanta',
 CDS_PART_NAME='Q_RES_0402LF-33.2,1%,1/16W,CHIA',
 WATTAGE='1/16W',
 TOLERANCE='1%',
 MATERIAL='CHIP',
 VALUE='33.2',
 PRIM_FILE='W:/<user>/logical/q_res/chips/chips.prt';

PART_NAME
 R774 'Q_RES_0402LF-4.7K,1%,1/16W,CHIA':;

SECTION_NUMBER 1
 '@SCM_LIB.SCM(SCH_1):PAGE13_I213@PURE_QUANTA.Q_RES(CHIPS)':
 C_PATH='@scm_lib.scm(sch_1):page13_i213@pure_quanta.q_res(chips)',
 P_PATH='@scm_lib.scm(sch_1):page13_i213@pure_quanta.q_res(chips)',
 PATH='I213',
 DRAWING='@SCM_LIB.SCM(SCH_1):PAGE13',
 PHYS_PAGE='13',
 XY='(2750,-25)',
 ROT='0',
 VER='1',
 PACK_TYPE='0402LF',
 LOCATION='R774',
 CDS_LIB='pure_quanta',
 CDS_PART_NAME='Q_RES_0402LF-4.7K,1%,1/16W,CHIA',
 WATTAGE='1/16W',
 TOLERANCE='1%',
 MATERIAL='CHIP',
 VALUE='4.7K',
 PRIM_FILE='W:/<user>/logical/q_res/chips/chips.prt';

PART_NAME
 R775 'Q_RES_0402LF-1K,1%,1/16W,CHIP,A':;

SECTION_NUMBER 1
 '@SCM_LIB.SCM(SCH_1):PAGE15_I183@PURE_QUANTA.Q_RES(CHIPS)':
 C_PATH='@scm_lib.scm(sch_1):page15_i183@pure_quanta.q_res(chips)',
 P_PATH='@scm_lib.scm(sch_1):page15_i183@pure_quanta.q_res(chips)',
 PATH='I183',
 DRAWING='@SCM_LIB.SCM(SCH_1):PAGE15',
 PHYS_PAGE='15',
 XY='(-400,-750)',
 ROT='0',
 VER='1',
 PACK_TYPE='0402LF',
 LOCATION='R775',
 CDS_LIB='pure_quanta',
 CDS_PART_NAME='Q_RES_0402LF-1K,1%,1/16W,CHIP,A',
 WATTAGE='1/16W',
 TOLERANCE='1%',
 MATERIAL='CHIP',
 VALUE='1K',
 PRIM_FILE='W:/<user>/logical/q_res/chips/chips.prt';

PART_NAME
 R776 'Q_RES_0402LF-47K,1%,1/16W,CHIPA':;

SECTION_NUMBER 1
 '@SCM_LIB.SCM(SCH_1):PAGE15_I184@PURE_QUANTA.Q_RES(CHIPS)':
 C_PATH='@scm_lib.scm(sch_1):page15_i184@pure_quanta.q_res(chips)',
 P_PATH='@scm_lib.scm(sch_1):page15_i184@pure_quanta.q_res(chips)',
 PATH='I184',
 DRAWING='@SCM_LIB.SCM(SCH_1):PAGE15',
 SEC_TYPE='0402LF',
 PHYS_PAGE='15',
 XY='(250,-1100)',
 ROT='0',
 VER='2',
 PACK_TYPE='0402LF',
 LOCATION='R776',
 SEC='1',
 CDS_LIB='pure_quanta',
 CDS_PART_NAME='Q_RES_0402LF-47K,1%,1/16W,CHIPA',
 WATTAGE='1/16W',
 TOLERANCE='1%',
 MATERIAL='CHIP',
 VALUE='47K',
 PRIM_FILE='W:/<user>/logical/q_res/chips/chips.prt';

PART_NAME
 R777 'Q_RES_0402LF-200K,1%,1/16W,CHIA':;

SECTION_NUMBER 1
 '@SCM_LIB.SCM(SCH_1):PAGE15_I289@PURE_QUANTA.Q_RES(CHIPS)':
 C_PATH='@scm_lib.scm(sch_1):page15_i289@pure_quanta.q_res(chips)',
 P_PATH='@scm_lib.scm(sch_1):page15_i289@pure_quanta.q_res(chips)',
 PATH='I289',
 DRAWING='@SCM_LIB.SCM(SCH_1):PAGE15',
 PHYS_PAGE='15',
 XY='(650,-175)',
 ROT='0',
 VER='2',
 PACK_TYPE='0402LF',
 LOCATION='R777',
 CDS_LIB='pure_quanta',
 CDS_PART_NAME='Q_RES_0402LF-200K,1%,1/16W,CHIA',
 WATTAGE='1/16W',
 TOLERANCE='1%',
 MATERIAL='CHIP',
 VALUE='200K',
 PRIM_FILE='W:/<user>/logical/q_res/chips/chips.prt';

PART_NAME
 R778 'Q_RES_0402LF-100K,1%,1/16W,CHIA':;

SECTION_NUMBER 1
 '@SCM_LIB.SCM(SCH_1):PAGE15_I181@PURE_QUANTA.Q_RES(CHIPS)':
 C_PATH='@scm_lib.scm(sch_1):page15_i181@pure_quanta.q_res(chips)',
 P_PATH='@scm_lib.scm(sch_1):page15_i181@pure_quanta.q_res(chips)',
 PATH='I181',
 DRAWING='@SCM_LIB.SCM(SCH_1):PAGE15',
 PHYS_PAGE='15',
 XY='(650,-1250)',
 ROT='0',
 VER='2',
 PACK_TYPE='0402LF',
 LOCATION='R778',
 CDS_LIB='pure_quanta',
 CDS_PART_NAME='Q_RES_0402LF-100K,1%,1/16W,CHIA',
 WATTAGE='1/16W',
 TOLERANCE='1%',
 MATERIAL='CHIP',
 VALUE='100K',
 PRIM_FILE='W:/<user>/logical/q_res/chips/chips.prt';

PART_NAME
 R779 'Q_RES_0402LF-0,5%,1/16W,CHIP,CA':;

SECTION_NUMBER 1
 '@SCM_LIB.SCM(SCH_1):PAGE17_I259@PURE_QUANTA.Q_RES(CHIPS)':
 C_PATH='@scm_lib.scm(sch_1):page17_i259@pure_quanta.q_res(chips)',
 P_PATH='@scm_lib.scm(sch_1):page17_i259@pure_quanta.q_res(chips)',
 PATH='I259',
 DRAWING='@SCM_LIB.SCM(SCH_1):PAGE17',
 PHYS_PAGE='17',
 XY='(-3425,-1050)',
 ROT='0',
 VER='1',
 PACK_TYPE='0402LF',
 LOCATION='R779',
 CDS_LIB='pure_quanta',
 CDS_PART_NAME='Q_RES_0402LF-0,5%,1/16W,CHIP,CA',
 WATTAGE='1/16W',
 TOLERANCE='5%',
 MATERIAL='CHIP',
 VALUE='0',
 PRIM_FILE='W:/<user>/logical/q_res/chips/chips.prt';

PART_NAME
 R780 'Q_RES_0402LF-0,5%,1/16W,EMPTY,A':;

SECTION_NUMBER 1
 '@SCM_LIB.SCM(SCH_1):PAGE17_I256@PURE_QUANTA.Q_RES(CHIPS)':
 C_PATH='@scm_lib.scm(sch_1):page17_i256@pure_quanta.q_res(chips)',
 P_PATH='@scm_lib.scm(sch_1):page17_i256@pure_quanta.q_res(chips)',
 PATH='I256',
 DRAWING='@SCM_LIB.SCM(SCH_1):PAGE17',
 PHYS_PAGE='17',
 XY='(-1125,-1050)',
 ROT='0',
 VER='1',
 PACK_TYPE='0402LF',
 LOCATION='R780',
 CDS_LIB='pure_quanta',
 CDS_PART_NAME='Q_RES_0402LF-0,5%,1/16W,EMPTY,A',
 WATTAGE='1/16W',
 TOLERANCE='5%',
 MATERIAL='EMPTY',
 VALUE='0',
 PRIM_FILE='W:/<user>/logical/q_res/chips/chips.prt';

PART_NAME
 R781 'Q_RES_0402LF-0,5%,1/16W,EMPTY,A':;

SECTION_NUMBER 1
 '@SCM_LIB.SCM(SCH_1):PAGE17_I263@PURE_QUANTA.Q_RES(CHIPS)':
 C_PATH='@scm_lib.scm(sch_1):page17_i263@pure_quanta.q_res(chips)',
 P_PATH='@scm_lib.scm(sch_1):page17_i263@pure_quanta.q_res(chips)',
 PATH='I263',
 DRAWING='@SCM_LIB.SCM(SCH_1):PAGE17',
 PHYS_PAGE='17',
 XY='(-3525,-1325)',
 ROT='0',
 VER='1',
 PACK_TYPE='0402LF',
 LOCATION='R781',
 CDS_LIB='pure_quanta',
 CDS_PART_NAME='Q_RES_0402LF-0,5%,1/16W,EMPTY,A',
 WATTAGE='1/16W',
 TOLERANCE='5%',
 MATERIAL='EMPTY',
 VALUE='0',
 PRIM_FILE='W:/<user>/logical/q_res/chips/chips.prt';

PART_NAME
 R782 'Q_RES_0402LF-0,5%,1/16W,EMPTY,A':;

SECTION_NUMBER 1
 '@SCM_LIB.SCM(SCH_1):PAGE17_I264@PURE_QUANTA.Q_RES(CHIPS)':
 C_PATH='@scm_lib.scm(sch_1):page17_i264@pure_quanta.q_res(chips)',
 P_PATH='@scm_lib.scm(sch_1):page17_i264@pure_quanta.q_res(chips)',
 PATH='I264',
 DRAWING='@SCM_LIB.SCM(SCH_1):PAGE17',
 PHYS_PAGE='17',
 XY='(-3525,-1600)',
 ROT='0',
 VER='1',
 PACK_TYPE='0402LF',
 LOCATION='R782',
 CDS_LIB='pure_quanta',
 CDS_PART_NAME='Q_RES_0402LF-0,5%,1/16W,EMPTY,A',
 WATTAGE='1/16W',
 TOLERANCE='5%',
 MATERIAL='EMPTY',
 VALUE='0',
 PRIM_FILE='W:/<user>/logical/q_res/chips/chips.prt';

PART_NAME
 R783 'Q_RES_0402LF-0,5%,1/16W,CHIP,CA':;

SECTION_NUMBER 1
 '@SCM_LIB.SCM(SCH_1):PAGE17_I260@PURE_QUANTA.Q_RES(CHIPS)':
 C_PATH='@scm_lib.scm(sch_1):page17_i260@pure_quanta.q_res(chips)',
 P_PATH='@scm_lib.scm(sch_1):page17_i260@pure_quanta.q_res(chips)',
 PATH='I260',
 DRAWING='@SCM_LIB.SCM(SCH_1):PAGE17',
 PHYS_PAGE='17',
 XY='(-1225,-1325)',
 ROT='0',
 VER='1',
 PACK_TYPE='0402LF',
 LOCATION='R783',
 CDS_LIB='pure_quanta',
 CDS_PART_NAME='Q_RES_0402LF-0,5%,1/16W,CHIP,CA',
 WATTAGE='1/16W',
 TOLERANCE='5%',
 MATERIAL='CHIP',
 VALUE='0',
 PRIM_FILE='W:/<user>/logical/q_res/chips/chips.prt';

PART_NAME
 R784 'Q_RES_0402LF-0,5%,1/16W,EMPTY,A':;

SECTION_NUMBER 1
 '@SCM_LIB.SCM(SCH_1):PAGE17_I267@PURE_QUANTA.Q_RES(CHIPS)':
 C_PATH='@scm_lib.scm(sch_1):page17_i267@pure_quanta.q_res(chips)',
 P_PATH='@scm_lib.scm(sch_1):page17_i267@pure_quanta.q_res(chips)',
 PATH='I267',
 DRAWING='@SCM_LIB.SCM(SCH_1):PAGE17',
 PHYS_PAGE='17',
 XY='(-1225,-1600)',
 ROT='0',
 VER='1',
 PACK_TYPE='0402LF',
 LOCATION='R784',
 CDS_LIB='pure_quanta',
 CDS_PART_NAME='Q_RES_0402LF-0,5%,1/16W,EMPTY,A',
 WATTAGE='1/16W',
 TOLERANCE='5%',
 MATERIAL='EMPTY',
 VALUE='0',
 PRIM_FILE='W:/<user>/logical/q_res/chips/chips.prt';

PART_NAME
 R785 'Q_RES_0402LF-15.8K,1%,1/16W,CHA':;

SECTION_NUMBER 1
 '@SCM_LIB.SCM(SCH_1):PAGE15_I202@PURE_QUANTA.Q_RES(CHIPS)':
 C_PATH='@scm_lib.scm(sch_1):page15_i202@pure_quanta.q_res(chips)',
 P_PATH='@scm_lib.scm(sch_1):page15_i202@pure_quanta.q_res(chips)',
 PATH='I202',
 DRAWING='@SCM_LIB.SCM(SCH_1):PAGE15',
 PHYS_PAGE='15',
 XY='(-2625,3475)',
 ROT='2',
 VER='2',
 PACK_TYPE='0402LF',
 LOCATION='R785',
 CDS_LIB='pure_quanta',
 CDS_PART_NAME='Q_RES_0402LF-15.8K,1%,1/16W,CHA',
 WATTAGE='1/16W',
 TOLERANCE='1%',
 MATERIAL='CHIP',
 VALUE='15.8K',
 PRIM_FILE='W:/<user>/logical/q_res/chips/chips.prt';

PART_NAME
 R786 'Q_RES_0402LF-2K,1%,1/16W,CHIP,A':;

SECTION_NUMBER 1
 '@SCM_LIB.SCM(SCH_1):PAGE15_I203@PURE_QUANTA.Q_RES(CHIPS)':
 C_PATH='@scm_lib.scm(sch_1):page15_i203@pure_quanta.q_res(chips)',
 P_PATH='@scm_lib.scm(sch_1):page15_i203@pure_quanta.q_res(chips)',
 PATH='I203',
 DRAWING='@SCM_LIB.SCM(SCH_1):PAGE15',
 PHYS_PAGE='15',
 XY='(-2625,3100)',
 ROT='2',
 VER='2',
 PACK_TYPE='0402LF',
 LOCATION='R786',
 CDS_LIB='pure_quanta',
 CDS_PART_NAME='Q_RES_0402LF-2K,1%,1/16W,CHIP,A',
 WATTAGE='1/16W',
 TOLERANCE='1%',
 MATERIAL='CHIP',
 VALUE='2K',
 PRIM_FILE='W:/<user>/logical/q_res/chips/chips.prt';

PART_NAME
 R787 'Q_RES_0402LF-5.36K,1%,1/16W,CHA':;

SECTION_NUMBER 1
 '@SCM_LIB.SCM(SCH_1):PAGE15_I223@PURE_QUANTA.Q_RES(CHIPS)':
 C_PATH='@scm_lib.scm(sch_1):page15_i223@pure_quanta.q_res(chips)',
 P_PATH='@scm_lib.scm(sch_1):page15_i223@pure_quanta.q_res(chips)',
 PATH='I223',
 DRAWING='@SCM_LIB.SCM(SCH_1):PAGE15',
 PHYS_PAGE='15',
 XY='(-2625,2525)',
 ROT='2',
 VER='2',
 PACK_TYPE='0402LF',
 LOCATION='R787',
 CDS_LIB='pure_quanta',
 CDS_PART_NAME='Q_RES_0402LF-5.36K,1%,1/16W,CHA',
 WATTAGE='1/16W',
 TOLERANCE='1%',
 MATERIAL='CHIP',
 VALUE='5.36K',
 PRIM_FILE='W:/<user>/logical/q_res/chips/chips.prt';

PART_NAME
 R788 'Q_RES_0402LF-2K,1%,1/16W,CHIP,A':;

SECTION_NUMBER 1
 '@SCM_LIB.SCM(SCH_1):PAGE15_I211@PURE_QUANTA.Q_RES(CHIPS)':
 C_PATH='@scm_lib.scm(sch_1):page15_i211@pure_quanta.q_res(chips)',
 P_PATH='@scm_lib.scm(sch_1):page15_i211@pure_quanta.q_res(chips)',
 PATH='I211',
 DRAWING='@SCM_LIB.SCM(SCH_1):PAGE15',
 PHYS_PAGE='15',
 XY='(-2625,2150)',
 ROT='2',
 VER='2',
 PACK_TYPE='0402LF',
 LOCATION='R788',
 CDS_LIB='pure_quanta',
 CDS_PART_NAME='Q_RES_0402LF-2K,1%,1/16W,CHIP,A',
 WATTAGE='1/16W',
 TOLERANCE='1%',
 MATERIAL='CHIP',
 VALUE='2K',
 PRIM_FILE='W:/<user>/logical/q_res/chips/chips.prt';

PART_NAME
 R789 'Q_RES_0402LF-2.87K,1%,1/16W,CHA':;

SECTION_NUMBER 1
 '@SCM_LIB.SCM(SCH_1):PAGE15_I219@PURE_QUANTA.Q_RES(CHIPS)':
 C_PATH='@scm_lib.scm(sch_1):page15_i219@pure_quanta.q_res(chips)',
 P_PATH='@scm_lib.scm(sch_1):page15_i219@pure_quanta.q_res(chips)',
 PATH='I219',
 DRAWING='@SCM_LIB.SCM(SCH_1):PAGE15',
 PHYS_PAGE='15',
 XY='(-2625,1525)',
 ROT='2',
 VER='2',
 PACK_TYPE='0402LF',
 LOCATION='R789',
 CDS_LIB='pure_quanta',
 CDS_PART_NAME='Q_RES_0402LF-2.87K,1%,1/16W,CHA',
 WATTAGE='1/16W',
 TOLERANCE='1%',
 MATERIAL='CHIP',
 VALUE='2.87K',
 PRIM_FILE='W:/<user>/logical/q_res/chips/chips.prt';

PART_NAME
 R790 'Q_RES_0402LF-2K,1%,1/16W,CHIP,A':;

SECTION_NUMBER 1
 '@SCM_LIB.SCM(SCH_1):PAGE15_I220@PURE_QUANTA.Q_RES(CHIPS)':
 C_PATH='@scm_lib.scm(sch_1):page15_i220@pure_quanta.q_res(chips)',
 P_PATH='@scm_lib.scm(sch_1):page15_i220@pure_quanta.q_res(chips)',
 PATH='I220',
 DRAWING='@SCM_LIB.SCM(SCH_1):PAGE15',
 PHYS_PAGE='15',
 XY='(-2625,1150)',
 ROT='2',
 VER='2',
 PACK_TYPE='0402LF',
 LOCATION='R790',
 CDS_LIB='pure_quanta',
 CDS_PART_NAME='Q_RES_0402LF-2K,1%,1/16W,CHIP,A',
 WATTAGE='1/16W',
 TOLERANCE='1%',
 MATERIAL='CHIP',
 VALUE='2K',
 PRIM_FILE='W:/<user>/logical/q_res/chips/chips.prt';

PART_NAME
 R791 'Q_RES_0402LF-1.69K,1%,1/16W,CHA':;

SECTION_NUMBER 1
 '@SCM_LIB.SCM(SCH_1):PAGE15_I245@PURE_QUANTA.Q_RES(CHIPS)':
 C_PATH='@scm_lib.scm(sch_1):page15_i245@pure_quanta.q_res(chips)',
 P_PATH='@scm_lib.scm(sch_1):page15_i245@pure_quanta.q_res(chips)',
 PATH='I245',
 DRAWING='@SCM_LIB.SCM(SCH_1):PAGE15',
 PHYS_PAGE='15',
 XY='(-2625,400)',
 ROT='2',
 VER='2',
 PACK_TYPE='0402LF',
 LOCATION='R791',
 CDS_LIB='pure_quanta',
 CDS_PART_NAME='Q_RES_0402LF-1.69K,1%,1/16W,CHA',
 WATTAGE='1/16W',
 TOLERANCE='1%',
 MATERIAL='CHIP',
 VALUE='1.69K',
 PRIM_FILE='W:/<user>/logical/q_res/chips/chips.prt';

PART_NAME
 R792 'Q_RES_0402LF-2K,1%,1/16W,CHIP,A':;

SECTION_NUMBER 1
 '@SCM_LIB.SCM(SCH_1):PAGE15_I236@PURE_QUANTA.Q_RES(CHIPS)':
 C_PATH='@scm_lib.scm(sch_1):page15_i236@pure_quanta.q_res(chips)',
 P_PATH='@scm_lib.scm(sch_1):page15_i236@pure_quanta.q_res(chips)',
 PATH='I236',
 DRAWING='@SCM_LIB.SCM(SCH_1):PAGE15',
 PHYS_PAGE='15',
 XY='(-2625,25)',
 ROT='2',
 VER='2',
 PACK_TYPE='0402LF',
 LOCATION='R792',
 CDS_LIB='pure_quanta',
 CDS_PART_NAME='Q_RES_0402LF-2K,1%,1/16W,CHIP,A',
 WATTAGE='1/16W',
 TOLERANCE='1%',
 MATERIAL='CHIP',
 VALUE='2K',
 PRIM_FILE='W:/<user>/logical/q_res/chips/chips.prt';

PART_NAME
 R793 'Q_RES_0402LF-665,1%,1/16W,CHIPA':;

SECTION_NUMBER 1
 '@SCM_LIB.SCM(SCH_1):PAGE15_I244@PURE_QUANTA.Q_RES(CHIPS)':
 C_PATH='@scm_lib.scm(sch_1):page15_i244@pure_quanta.q_res(chips)',
 P_PATH='@scm_lib.scm(sch_1):page15_i244@pure_quanta.q_res(chips)',
 PATH='I244',
 DRAWING='@SCM_LIB.SCM(SCH_1):PAGE15',
 PHYS_PAGE='15',
 XY='(-2625,-700)',
 ROT='2',
 VER='2',
 PACK_TYPE='0402LF',
 LOCATION='R793',
 CDS_LIB='pure_quanta',
 CDS_PART_NAME='Q_RES_0402LF-665,1%,1/16W,CHIPA',
 WATTAGE='1/16W',
 TOLERANCE='1%',
 MATERIAL='CHIP',
 VALUE='665',
 PRIM_FILE='W:/<user>/logical/q_res/chips/chips.prt';

PART_NAME
 R794 'Q_RES_0402LF-2K,1%,1/16W,CHIP,A':;

SECTION_NUMBER 1
 '@SCM_LIB.SCM(SCH_1):PAGE15_I242@PURE_QUANTA.Q_RES(CHIPS)':
 C_PATH='@scm_lib.scm(sch_1):page15_i242@pure_quanta.q_res(chips)',
 P_PATH='@scm_lib.scm(sch_1):page15_i242@pure_quanta.q_res(chips)',
 PATH='I242',
 DRAWING='@SCM_LIB.SCM(SCH_1):PAGE15',
 PHYS_PAGE='15',
 XY='(-2625,-1075)',
 ROT='2',
 VER='2',
 PACK_TYPE='0402LF',
 LOCATION='R794',
 CDS_LIB='pure_quanta',
 CDS_PART_NAME='Q_RES_0402LF-2K,1%,1/16W,CHIP,A',
 WATTAGE='1/16W',
 TOLERANCE='1%',
 MATERIAL='CHIP',
 VALUE='2K',
 PRIM_FILE='W:/<user>/logical/q_res/chips/chips.prt';

PART_NAME
 R795 'Q_RES_0402LF-1K,1%,1/16W,CHIP,A':;

SECTION_NUMBER 1
 '@SCM_LIB.SCM(SCH_1):PAGE15_I252@PURE_QUANTA.Q_RES(CHIPS)':
 C_PATH='@scm_lib.scm(sch_1):page15_i252@pure_quanta.q_res(chips)',
 P_PATH='@scm_lib.scm(sch_1):page15_i252@pure_quanta.q_res(chips)',
 PATH='I252',
 DRAWING='@SCM_LIB.SCM(SCH_1):PAGE15',
 PHYS_PAGE='15',
 XY='(-1650,1425)',
 ROT='0',
 VER='2',
 PACK_TYPE='0402LF',
 LOCATION='R795',
 CDS_LIB='pure_quanta',
 CDS_PART_NAME='Q_RES_0402LF-1K,1%,1/16W,CHIP,A',
 WATTAGE='1/16W',
 TOLERANCE='1%',
 MATERIAL='CHIP',
 VALUE='1K',
 PRIM_FILE='W:/<user>/logical/q_res/chips/chips.prt';

PART_NAME
 R796 'Q_RES_0402LF-1K,1%,1/16W,CHIP,A':;

SECTION_NUMBER 1
 '@SCM_LIB.SCM(SCH_1):PAGE15_I255@PURE_QUANTA.Q_RES(CHIPS)':
 C_PATH='@scm_lib.scm(sch_1):page15_i255@pure_quanta.q_res(chips)',
 P_PATH='@scm_lib.scm(sch_1):page15_i255@pure_quanta.q_res(chips)',
 PATH='I255',
 DRAWING='@SCM_LIB.SCM(SCH_1):PAGE15',
 PHYS_PAGE='15',
 XY='(-1625,325)',
 ROT='0',
 VER='2',
 PACK_TYPE='0402LF',
 LOCATION='R796',
 CDS_LIB='pure_quanta',
 CDS_PART_NAME='Q_RES_0402LF-1K,1%,1/16W,CHIP,A',
 WATTAGE='1/16W',
 TOLERANCE='1%',
 MATERIAL='CHIP',
 VALUE='1K',
 PRIM_FILE='W:/<user>/logical/q_res/chips/chips.prt';

PART_NAME
 R797 'Q_RES_0402LF-2.87K,1%,1/16W,CHA':;

SECTION_NUMBER 1
 '@SCM_LIB.SCM(SCH_1):PAGE15_I261@PURE_QUANTA.Q_RES(CHIPS)':
 C_PATH='@scm_lib.scm(sch_1):page15_i261@pure_quanta.q_res(chips)',
 P_PATH='@scm_lib.scm(sch_1):page15_i261@pure_quanta.q_res(chips)',
 PATH='I261',
 DRAWING='@SCM_LIB.SCM(SCH_1):PAGE15',
 PHYS_PAGE='15',
 XY='(-1500,-1175)',
 ROT='2',
 VER='2',
 PACK_TYPE='0402LF',
 LOCATION='R797',
 CDS_LIB='pure_quanta',
 CDS_PART_NAME='Q_RES_0402LF-2.87K,1%,1/16W,CHA',
 WATTAGE='1/16W',
 TOLERANCE='1%',
 MATERIAL='CHIP',
 VALUE='2.87K',
 PRIM_FILE='W:/<user>/logical/q_res/chips/chips.prt';

PART_NAME
 R798 'Q_RES_0402LF-2K,1%,1/16W,CHIP,A':;

SECTION_NUMBER 1
 '@SCM_LIB.SCM(SCH_1):PAGE15_I262@PURE_QUANTA.Q_RES(CHIPS)':
 C_PATH='@scm_lib.scm(sch_1):page15_i262@pure_quanta.q_res(chips)',
 P_PATH='@scm_lib.scm(sch_1):page15_i262@pure_quanta.q_res(chips)',
 PATH='I262',
 DRAWING='@SCM_LIB.SCM(SCH_1):PAGE15',
 PHYS_PAGE='15',
 XY='(-1500,-1550)',
 ROT='2',
 VER='2',
 PACK_TYPE='0402LF',
 LOCATION='R798',
 CDS_LIB='pure_quanta',
 CDS_PART_NAME='Q_RES_0402LF-2K,1%,1/16W,CHIP,A',
 WATTAGE='1/16W',
 TOLERANCE='1%',
 MATERIAL='CHIP',
 VALUE='2K',
 PRIM_FILE='W:/<user>/logical/q_res/chips/chips.prt';

PART_NAME
 R799 'Q_RES_0402LF-33.2,1%,1/16W,CHIA':;

SECTION_NUMBER 1
 '@SCM_LIB.SCM(SCH_1):PAGE13_I215@PURE_QUANTA.Q_RES(CHIPS)':
 C_PATH='@scm_lib.scm(sch_1):page13_i215@pure_quanta.q_res(chips)',
 P_PATH='@scm_lib.scm(sch_1):page13_i215@pure_quanta.q_res(chips)',
 PATH='I215',
 DRAWING='@SCM_LIB.SCM(SCH_1):PAGE13',
 PHYS_PAGE='13',
 XY='(-1825,3725)',
 ROT='0',
 VER='1',
 PACK_TYPE='0402LF',
 LOCATION='R799',
 CDS_LIB='pure_quanta',
 CDS_PART_NAME='Q_RES_0402LF-33.2,1%,1/16W,CHIA',
 WATTAGE='1/16W',
 TOLERANCE='1%',
 MATERIAL='CHIP',
 VALUE='33.2',
 PRIM_FILE='W:/<user>/logical/q_res/chips/chips.prt';

PART_NAME
 R801 'Q_RES_0402LF-33.2,1%,1/16W,CHIA':;

SECTION_NUMBER 1
 '@SCM_LIB.SCM(SCH_1):PAGE13_I217@PURE_QUANTA.Q_RES(CHIPS)':
 C_PATH='@scm_lib.scm(sch_1):page13_i217@pure_quanta.q_res(chips)',
 P_PATH='@scm_lib.scm(sch_1):page13_i217@pure_quanta.q_res(chips)',
 PATH='I217',
 DRAWING='@SCM_LIB.SCM(SCH_1):PAGE13',
 PHYS_PAGE='13',
 XY='(-1775,4325)',
 ROT='0',
 VER='1',
 PACK_TYPE='0402LF',
 LOCATION='R801',
 CDS_LIB='pure_quanta',
 CDS_PART_NAME='Q_RES_0402LF-33.2,1%,1/16W,CHIA',
 WATTAGE='1/16W',
 TOLERANCE='1%',
 MATERIAL='CHIP',
 VALUE='33.2',
 PRIM_FILE='W:/<user>/logical/q_res/chips/chips.prt';

PART_NAME
 R802 'Q_RES_0402LF-33.2,1%,1/16W,CHIA':;

SECTION_NUMBER 1
 '@SCM_LIB.SCM(SCH_1):PAGE13_I218@PURE_QUANTA.Q_RES(CHIPS)':
 C_PATH='@scm_lib.scm(sch_1):page13_i218@pure_quanta.q_res(chips)',
 P_PATH='@scm_lib.scm(sch_1):page13_i218@pure_quanta.q_res(chips)',
 PATH='I218',
 DRAWING='@SCM_LIB.SCM(SCH_1):PAGE13',
 PHYS_PAGE='13',
 XY='(-1775,4275)',
 ROT='0',
 VER='1',
 PACK_TYPE='0402LF',
 LOCATION='R802',
 CDS_LIB='pure_quanta',
 CDS_PART_NAME='Q_RES_0402LF-33.2,1%,1/16W,CHIA',
 WATTAGE='1/16W',
 TOLERANCE='1%',
 MATERIAL='CHIP',
 VALUE='33.2',
 PRIM_FILE='W:/<user>/logical/q_res/chips/chips.prt';

PART_NAME
 R804 'Q_RES_0402LF-0,5%,1/16W,CHIP,CA':;

SECTION_NUMBER 1
 '@SCM_LIB.SCM(SCH_1):PAGE15_I367@PURE_QUANTA.Q_RES(CHIPS)':
 C_PATH='@scm_lib.scm(sch_1):page15_i367@pure_quanta.q_res(chips)',
 P_PATH='@scm_lib.scm(sch_1):page15_i367@pure_quanta.q_res(chips)',
 PATH='I367',
 DRAWING='@SCM_LIB.SCM(SCH_1):PAGE15',
 PHYS_PAGE='15',
 XY='(4125,3425)',
 ROT='0',
 VER='1',
 PACK_TYPE='0402LF',
 CDS_LIB='pure_quanta',
 CDS_PART_NAME='Q_RES_0402LF-0,5%,1/16W,CHIP,CA',
 WATTAGE='1/16W',
 TOLERANCE='5%',
 MATERIAL='CHIP',
 VALUE='0',
 PRIM_FILE='W:/<user>/logical/q_res/chips/chips.prt';

PART_NAME
 R805 'Q_RES_0402LF-4.7K,1%,1/16W,CHIA':;

SECTION_NUMBER 1
 '@SCM_LIB.SCM(SCH_1):PAGE13_I356@PURE_QUANTA.Q_RES(CHIPS)':
 C_PATH='@scm_lib.scm(sch_1):page13_i356@pure_quanta.q_res(chips)',
 P_PATH='@scm_lib.scm(sch_1):page13_i356@pure_quanta.q_res(chips)',
 PATH='I356',
 DRAWING='@SCM_LIB.SCM(SCH_1):PAGE13',
 SEC_TYPE='0402LF',
 PHYS_PAGE='13',
 XY='(1300,-50)',
 ROT='0',
 VER='1',
 PACK_TYPE='0402LF',
 LOCATION='R805',
 SEC='1',
 CDS_LIB='pure_quanta',
 CDS_PART_NAME='Q_RES_0402LF-4.7K,1%,1/16W,CHIA',
 WATTAGE='1/16W',
 TOLERANCE='1%',
 MATERIAL='CHIP',
 VALUE='4.7K',
 PRIM_FILE='W:/<user>/logical/q_res/chips/chips.prt';

PART_NAME
 R806 'Q_RES_0402LF-4.7K,1%,1/16W,CHIA':;

SECTION_NUMBER 1
 '@SCM_LIB.SCM(SCH_1):PAGE34_I119@PURE_QUANTA.Q_RES(CHIPS)':
 C_PATH='@scm_lib.scm(sch_1):page34_i119@pure_quanta.q_res(chips)',
 P_PATH='@scm_lib.scm(sch_1):page34_i119@pure_quanta.q_res(chips)',
 PATH='I119',
 DRAWING='@SCM_LIB.SCM(SCH_1):PAGE34',
 PHYS_PAGE='34',
 XY='(-4375,950)',
 ROT='0',
 VER='2',
 PACK_TYPE='0402LF',
 LOCATION='R806',
 CDS_LIB='pure_quanta',
 CDS_PART_NAME='Q_RES_0402LF-4.7K,1%,1/16W,CHIA',
 WATTAGE='1/16W',
 TOLERANCE='1%',
 MATERIAL='CHIP',
 VALUE='4.7K',
 PRIM_FILE='W:/<user>/logical/q_res/chips/chips.prt';

PART_NAME
 R807 'Q_RES_0402LF-33.2,1%,1/16W,CHIA':;

SECTION_NUMBER 1
 '@SCM_LIB.SCM(SCH_1):PAGE34_I126@PURE_QUANTA.Q_RES(CHIPS)':
 C_PATH='@scm_lib.scm(sch_1):page34_i126@pure_quanta.q_res(chips)',
 P_PATH='@scm_lib.scm(sch_1):page34_i126@pure_quanta.q_res(chips)',
 PATH='I126',
 DRAWING='@SCM_LIB.SCM(SCH_1):PAGE34',
 PHYS_PAGE='34',
 XY='(-1800,850)',
 ROT='0',
 VER='1',
 PACK_TYPE='0402LF',
 LOCATION='R807',
 CDS_LIB='pure_quanta',
 CDS_PART_NAME='Q_RES_0402LF-33.2,1%,1/16W,CHIA',
 WATTAGE='1/16W',
 TOLERANCE='1%',
 MATERIAL='CHIP',
 VALUE='33.2',
 PRIM_FILE='W:/<user>/logical/q_res/chips/chips.prt';

PART_NAME
 R808 'Q_RES_0402LF-10K,1%,1/16W,CHIPA':;

SECTION_NUMBER 1
 '@SCM_LIB.SCM(SCH_1):PAGE34_I117@PURE_QUANTA.Q_RES(CHIPS)':
 C_PATH='@scm_lib.scm(sch_1):page34_i117@pure_quanta.q_res(chips)',
 P_PATH='@scm_lib.scm(sch_1):page34_i117@pure_quanta.q_res(chips)',
 PATH='I117',
 DRAWING='@SCM_LIB.SCM(SCH_1):PAGE34',
 PHYS_PAGE='34',
 XY='(-6950,750)',
 ROT='0',
 VER='1',
 PACK_TYPE='0402LF',
 LOCATION='R808',
 CDS_LIB='pure_quanta',
 CDS_PART_NAME='Q_RES_0402LF-10K,1%,1/16W,CHIPA',
 WATTAGE='1/16W',
 TOLERANCE='1%',
 MATERIAL='CHIP',
 VALUE='10K',
 PRIM_FILE='W:/<user>/logical/q_res/chips/chips.prt';

PART_NAME
 R809 'Q_RES_0402LF-10K,1%,1/16W,CHIPA':;

SECTION_NUMBER 1
 '@SCM_LIB.SCM(SCH_1):PAGE34_I115@PURE_QUANTA.Q_RES(CHIPS)':
 C_PATH='@scm_lib.scm(sch_1):page34_i115@pure_quanta.q_res(chips)',
 P_PATH='@scm_lib.scm(sch_1):page34_i115@pure_quanta.q_res(chips)',
 PATH='I115',
 DRAWING='@SCM_LIB.SCM(SCH_1):PAGE34',
 PHYS_PAGE='34',
 XY='(-6950,700)',
 ROT='0',
 VER='1',
 PACK_TYPE='0402LF',
 LOCATION='R809',
 CDS_LIB='pure_quanta',
 CDS_PART_NAME='Q_RES_0402LF-10K,1%,1/16W,CHIPA',
 WATTAGE='1/16W',
 TOLERANCE='1%',
 MATERIAL='CHIP',
 VALUE='10K',
 PRIM_FILE='W:/<user>/logical/q_res/chips/chips.prt';

PART_NAME
 R810 'Q_RES_0402LF-10K,1%,1/16W,CHIPA':;

SECTION_NUMBER 1
 '@SCM_LIB.SCM(SCH_1):PAGE34_I116@PURE_QUANTA.Q_RES(CHIPS)':
 C_PATH='@scm_lib.scm(sch_1):page34_i116@pure_quanta.q_res(chips)',
 P_PATH='@scm_lib.scm(sch_1):page34_i116@pure_quanta.q_res(chips)',
 PATH='I116',
 DRAWING='@SCM_LIB.SCM(SCH_1):PAGE34',
 PHYS_PAGE='34',
 XY='(-6950,650)',
 ROT='0',
 VER='1',
 PACK_TYPE='0402LF',
 LOCATION='R810',
 CDS_LIB='pure_quanta',
 CDS_PART_NAME='Q_RES_0402LF-10K,1%,1/16W,CHIPA',
 WATTAGE='1/16W',
 TOLERANCE='1%',
 MATERIAL='CHIP',
 VALUE='10K',
 PRIM_FILE='W:/<user>/logical/q_res/chips/chips.prt';

PART_NAME
 R811 'Q_RES_0402LF-0,5%,1/16W,EMPTY,A':;

SECTION_NUMBER 1
 '@SCM_LIB.SCM(SCH_1):PAGE10_I565@PURE_QUANTA.Q_RES(CHIPS)':
 C_PATH='@scm_lib.scm(sch_1):page10_i565@pure_quanta.q_res(chips)',
 P_PATH='@scm_lib.scm(sch_1):page10_i565@pure_quanta.q_res(chips)',
 PATH='I565',
 DRAWING='@SCM_LIB.SCM(SCH_1):PAGE10',
 PHYS_PAGE='10',
 XY='(-6450,-1300)',
 ROT='2',
 VER='1',
 PACK_TYPE='0402LF',
 CDS_LIB='pure_quanta',
 CDS_PART_NAME='Q_RES_0402LF-0,5%,1/16W,EMPTY,A',
 WATTAGE='1/16W',
 TOLERANCE='5%',
 MATERIAL='EMPTY',
 VALUE='0',
 PRIM_FILE='W:/<user>/logical/q_res/chips/chips.prt';

PART_NAME
 R812 'Q_RES_0402LF-33.2,1%,1/16W,CHIA':;

SECTION_NUMBER 1
 '@SCM_LIB.SCM(SCH_1):PAGE49_I34@PURE_QUANTA.Q_RES(CHIPS)':
 C_PATH='@scm_lib.scm(sch_1):page49_i34@pure_quanta.q_res(chips)',
 P_PATH='@scm_lib.scm(sch_1):page49_i34@pure_quanta.q_res(chips)',
 PATH='I34',
 DRAWING='@SCM_LIB.SCM(SCH_1):PAGE49',
 PHYS_PAGE='49',
 XY='(-8075,2900)',
 ROT='0',
 VER='1',
 PACK_TYPE='0402LF',
 LOCATION='R812',
 CDS_LIB='pure_quanta',
 CDS_PART_NAME='Q_RES_0402LF-33.2,1%,1/16W,CHIA',
 WATTAGE='1/16W',
 TOLERANCE='1%',
 MATERIAL='CHIP',
 VALUE='33.2',
 PRIM_FILE='W:/<user>/logical/q_res/chips/chips.prt';

PART_NAME
 R813 'Q_RES_0402LF-33.2,1%,1/16W,CHIA':;

SECTION_NUMBER 1
 '@SCM_LIB.SCM(SCH_1):PAGE49_I35@PURE_QUANTA.Q_RES(CHIPS)':
 C_PATH='@scm_lib.scm(sch_1):page49_i35@pure_quanta.q_res(chips)',
 P_PATH='@scm_lib.scm(sch_1):page49_i35@pure_quanta.q_res(chips)',
 PATH='I35',
 DRAWING='@SCM_LIB.SCM(SCH_1):PAGE49',
 PHYS_PAGE='49',
 XY='(-7875,2450)',
 ROT='0',
 VER='1',
 PACK_TYPE='0402LF',
 LOCATION='R813',
 CDS_LIB='pure_quanta',
 CDS_PART_NAME='Q_RES_0402LF-33.2,1%,1/16W,CHIA',
 WATTAGE='1/16W',
 TOLERANCE='1%',
 MATERIAL='CHIP',
 VALUE='33.2',
 PRIM_FILE='W:/<user>/logical/q_res/chips/chips.prt';

PART_NAME
 R814 'Q_RES_0402LF-10K,1%,1/16W,CHIPA':;

SECTION_NUMBER 1
 '@SCM_LIB.SCM(SCH_1):PAGE49_I36@PURE_QUANTA.Q_RES(CHIPS)':
 C_PATH='@scm_lib.scm(sch_1):page49_i36@pure_quanta.q_res(chips)',
 P_PATH='@scm_lib.scm(sch_1):page49_i36@pure_quanta.q_res(chips)',
 PATH='I36',
 DRAWING='@SCM_LIB.SCM(SCH_1):PAGE49',
 PHYS_PAGE='49',
 XY='(-7100,3175)',
 ROT='0',
 VER='2',
 PACK_TYPE='0402LF',
 LOCATION='R814',
 CDS_LIB='pure_quanta',
 CDS_PART_NAME='Q_RES_0402LF-10K,1%,1/16W,CHIPA',
 WATTAGE='1/16W',
 TOLERANCE='1%',
 MATERIAL='CHIP',
 VALUE='10K',
 PRIM_FILE='W:/<user>/logical/q_res/chips/chips.prt';

PART_NAME
 R815 'Q_RES_0402LF-10K,1%,1/16W,CHIPA':;

SECTION_NUMBER 1
 '@SCM_LIB.SCM(SCH_1):PAGE49_I40@PURE_QUANTA.Q_RES(CHIPS)':
 C_PATH='@scm_lib.scm(sch_1):page49_i40@pure_quanta.q_res(chips)',
 P_PATH='@scm_lib.scm(sch_1):page49_i40@pure_quanta.q_res(chips)',
 PATH='I40',
 DRAWING='@SCM_LIB.SCM(SCH_1):PAGE49',
 PHYS_PAGE='49',
 XY='(-6800,3175)',
 ROT='0',
 VER='2',
 PACK_TYPE='0402LF',
 LOCATION='R815',
 CDS_LIB='pure_quanta',
 CDS_PART_NAME='Q_RES_0402LF-10K,1%,1/16W,CHIPA',
 WATTAGE='1/16W',
 TOLERANCE='1%',
 MATERIAL='CHIP',
 VALUE='10K',
 PRIM_FILE='W:/<user>/logical/q_res/chips/chips.prt';

PART_NAME
 R816 'Q_RES_0402LF-4.7K,1%,1/16W,CHIA':;

SECTION_NUMBER 1
 '@SCM_LIB.SCM(SCH_1):PAGE13_I353@PURE_QUANTA.Q_RES(CHIPS)':
 C_PATH='@scm_lib.scm(sch_1):page13_i353@pure_quanta.q_res(chips)',
 P_PATH='@scm_lib.scm(sch_1):page13_i353@pure_quanta.q_res(chips)',
 PATH='I353',
 DRAWING='@SCM_LIB.SCM(SCH_1):PAGE13',
 PHYS_PAGE='13',
 XY='(2750,450)',
 ROT='0',
 VER='1',
 PACK_TYPE='0402LF',
 LOCATION='R816',
 CDS_LIB='pure_quanta',
 CDS_PART_NAME='Q_RES_0402LF-4.7K,1%,1/16W,CHIA',
 WATTAGE='1/16W',
 TOLERANCE='1%',
 MATERIAL='CHIP',
 VALUE='4.7K',
 PRIM_FILE='W:/<user>/logical/q_res/chips/chips.prt';

PART_NAME
 R817 'Q_RES_0402LF-100K,1%,1/16W,EMPA':;

SECTION_NUMBER 1
 '@SCM_LIB.SCM(SCH_1):PAGE12_I393@PURE_QUANTA.Q_RES(CHIPS)':
 C_PATH='@scm_lib.scm(sch_1):page12_i393@pure_quanta.q_res(chips)',
 P_PATH='@scm_lib.scm(sch_1):page12_i393@pure_quanta.q_res(chips)',
 PATH='I393',
 DRAWING='@SCM_LIB.SCM(SCH_1):PAGE12',
 SEC_TYPE='0402LF',
 PHYS_PAGE='12',
 XY='(2550,-250)',
 ROT='2',
 VER='1',
 PACK_TYPE='0402LF',
 LOCATION='R817',
 SEC='1',
 CDS_LIB='pure_quanta',
 CDS_PART_NAME='Q_RES_0402LF-100K,1%,1/16W,EMPA',
 WATTAGE='1/16W',
 TOLERANCE='1%',
 MATERIAL='EMPTY',
 VALUE='100K',
 PRIM_FILE='W:/<user>/logical/q_res/chips/chips.prt';

PART_NAME
 R818 'Q_RES_0402LF-100K,1%,1/16W,EMPA':;

SECTION_NUMBER 1
 '@SCM_LIB.SCM(SCH_1):PAGE12_I392@PURE_QUANTA.Q_RES(CHIPS)':
 C_PATH='@scm_lib.scm(sch_1):page12_i392@pure_quanta.q_res(chips)',
 P_PATH='@scm_lib.scm(sch_1):page12_i392@pure_quanta.q_res(chips)',
 PATH='I392',
 DRAWING='@SCM_LIB.SCM(SCH_1):PAGE12',
 SEC_TYPE='0402LF',
 PHYS_PAGE='12',
 XY='(2550,-300)',
 ROT='2',
 VER='1',
 PACK_TYPE='0402LF',
 LOCATION='R818',
 SEC='1',
 CDS_LIB='pure_quanta',
 CDS_PART_NAME='Q_RES_0402LF-100K,1%,1/16W,EMPA',
 WATTAGE='1/16W',
 TOLERANCE='1%',
 MATERIAL='EMPTY',
 VALUE='100K',
 PRIM_FILE='W:/<user>/logical/q_res/chips/chips.prt';

PART_NAME
 R819 'Q_RES_0402LF-100K,1%,1/16W,EMPA':;

SECTION_NUMBER 1
 '@SCM_LIB.SCM(SCH_1):PAGE12_I391@PURE_QUANTA.Q_RES(CHIPS)':
 C_PATH='@scm_lib.scm(sch_1):page12_i391@pure_quanta.q_res(chips)',
 P_PATH='@scm_lib.scm(sch_1):page12_i391@pure_quanta.q_res(chips)',
 PATH='I391',
 DRAWING='@SCM_LIB.SCM(SCH_1):PAGE12',
 SEC_TYPE='0402LF',
 PHYS_PAGE='12',
 XY='(2550,-350)',
 ROT='2',
 VER='1',
 PACK_TYPE='0402LF',
 LOCATION='R819',
 SEC='1',
 CDS_LIB='pure_quanta',
 CDS_PART_NAME='Q_RES_0402LF-100K,1%,1/16W,EMPA',
 WATTAGE='1/16W',
 TOLERANCE='1%',
 MATERIAL='EMPTY',
 VALUE='100K',
 PRIM_FILE='W:/<user>/logical/q_res/chips/chips.prt';

PART_NAME
 R820 'Q_RES_0402LF-100K,1%,1/16W,EMPA':;

SECTION_NUMBER 1
 '@SCM_LIB.SCM(SCH_1):PAGE12_I390@PURE_QUANTA.Q_RES(CHIPS)':
 C_PATH='@scm_lib.scm(sch_1):page12_i390@pure_quanta.q_res(chips)',
 P_PATH='@scm_lib.scm(sch_1):page12_i390@pure_quanta.q_res(chips)',
 PATH='I390',
 DRAWING='@SCM_LIB.SCM(SCH_1):PAGE12',
 SEC_TYPE='0402LF',
 PHYS_PAGE='12',
 XY='(2550,-400)',
 ROT='2',
 VER='1',
 PACK_TYPE='0402LF',
 LOCATION='R820',
 SEC='1',
 CDS_LIB='pure_quanta',
 CDS_PART_NAME='Q_RES_0402LF-100K,1%,1/16W,EMPA',
 WATTAGE='1/16W',
 TOLERANCE='1%',
 MATERIAL='EMPTY',
 VALUE='100K',
 PRIM_FILE='W:/<user>/logical/q_res/chips/chips.prt';

PART_NAME
 R821 'Q_RES_0402LF-4.7K,1%,1/16W,EMPA':;

SECTION_NUMBER 1
 '@SCM_LIB.SCM(SCH_1):PAGE13_I220@PURE_QUANTA.Q_RES(CHIPS)':
 C_PATH='@scm_lib.scm(sch_1):page13_i220@pure_quanta.q_res(chips)',
 P_PATH='@scm_lib.scm(sch_1):page13_i220@pure_quanta.q_res(chips)',
 PATH='I220',
 DRAWING='@SCM_LIB.SCM(SCH_1):PAGE13',
 PHYS_PAGE='13',
 XY='(2750,-75)',
 ROT='0',
 VER='1',
 PACK_TYPE='0402LF',
 LOCATION='R821',
 CDS_LIB='pure_quanta',
 CDS_PART_NAME='Q_RES_0402LF-4.7K,1%,1/16W,EMPA',
 WATTAGE='1/16W',
 TOLERANCE='1%',
 MATERIAL='EMPTY',
 VALUE='4.7K',
 PRIM_FILE='W:/<user>/logical/q_res/chips/chips.prt';

PART_NAME
 R822 'Q_RES_0402LF-0,5%,1/16W,CHIP,CA':;

SECTION_NUMBER 1
 '@SCM_LIB.SCM(SCH_1):PAGE10_I456@PURE_QUANTA.Q_RES(CHIPS)':
 C_PATH='@scm_lib.scm(sch_1):page10_i456@pure_quanta.q_res(chips)',
 P_PATH='@scm_lib.scm(sch_1):page10_i456@pure_quanta.q_res(chips)',
 PATH='I456',
 DRAWING='@SCM_LIB.SCM(SCH_1):PAGE10',
 PHYS_PAGE='10',
 XY='(-6425,2850)',
 ROT='2',
 VER='1',
 PACK_TYPE='0402LF',
 LOCATION='R822',
 CDS_LIB='pure_quanta',
 CDS_PART_NAME='Q_RES_0402LF-0,5%,1/16W,CHIP,CA',
 WATTAGE='1/16W',
 TOLERANCE='5%',
 MATERIAL='CHIP',
 VALUE='0',
 PRIM_FILE='W:/<user>/logical/q_res/chips/chips.prt';

PART_NAME
 R823 'Q_RES_0402LF-100K,1%,1/16W,CHIA':;

SECTION_NUMBER 1
 '@SCM_LIB.SCM(SCH_1):PAGE11_I234@PURE_QUANTA.Q_RES(CHIPS)':
 C_PATH='@scm_lib.scm(sch_1):page11_i234@pure_quanta.q_res(chips)',
 P_PATH='@scm_lib.scm(sch_1):page11_i234@pure_quanta.q_res(chips)',
 PATH='I234',
 DRAWING='@SCM_LIB.SCM(SCH_1):PAGE11',
 PHYS_PAGE='11',
 XY='(-200,3300)',
 ROT='0',
 VER='1',
 PACK_TYPE='0402LF',
 LOCATION='R823',
 CDS_LIB='pure_quanta',
 CDS_PART_NAME='Q_RES_0402LF-100K,1%,1/16W,CHIA',
 WATTAGE='1/16W',
 TOLERANCE='1%',
 MATERIAL='CHIP',
 VALUE='100K',
 PRIM_FILE='W:/<user>/logical/q_res/chips/chips.prt';

PART_NAME
 R824 'Q_RES_0402LF-33.2,1%,1/16W,CHIA':;

SECTION_NUMBER 1
 '@SCM_LIB.SCM(SCH_1):PAGE13_I223@PURE_QUANTA.Q_RES(CHIPS)':
 C_PATH='@scm_lib.scm(sch_1):page13_i223@pure_quanta.q_res(chips)',
 P_PATH='@scm_lib.scm(sch_1):page13_i223@pure_quanta.q_res(chips)',
 PATH='I223',
 DRAWING='@SCM_LIB.SCM(SCH_1):PAGE13',
 PHYS_PAGE='13',
 XY='(-2300,2425)',
 ROT='0',
 VER='1',
 PACK_TYPE='0402LF',
 LOCATION='R824',
 CDS_LIB='pure_quanta',
 CDS_PART_NAME='Q_RES_0402LF-33.2,1%,1/16W,CHIA',
 WATTAGE='1/16W',
 TOLERANCE='1%',
 MATERIAL='CHIP',
 VALUE='33.2',
 PRIM_FILE='W:/<user>/logical/q_res/chips/chips.prt';

PART_NAME
 R825 'Q_RES_0402LF-33.2,1%,1/16W,CHIA':;

SECTION_NUMBER 1
 '@SCM_LIB.SCM(SCH_1):PAGE35_I138@PURE_QUANTA.Q_RES(CHIPS)':
 C_PATH='@scm_lib.scm(sch_1):page35_i138@pure_quanta.q_res(chips)',
 P_PATH='@scm_lib.scm(sch_1):page35_i138@pure_quanta.q_res(chips)',
 PATH='I138',
 DRAWING='@SCM_LIB.SCM(SCH_1):PAGE35',
 PHYS_PAGE='35',
 XY='(-7300,4450)',
 ROT='0',
 VER='1',
 PACK_TYPE='0402LF',
 LOCATION='R825',
 CDS_LIB='pure_quanta',
 CDS_PART_NAME='Q_RES_0402LF-33.2,1%,1/16W,CHIA',
 WATTAGE='1/16W',
 TOLERANCE='1%',
 MATERIAL='CHIP',
 VALUE='33.2',
 PRIM_FILE='W:/<user>/logical/q_res/chips/chips.prt';

PART_NAME
 R826 'Q_RES_0402LF-33.2,1%,1/16W,CHIA':;

SECTION_NUMBER 1
 '@SCM_LIB.SCM(SCH_1):PAGE13_I351@PURE_QUANTA.Q_RES(CHIPS)':
 C_PATH='@scm_lib.scm(sch_1):page13_i351@pure_quanta.q_res(chips)',
 P_PATH='@scm_lib.scm(sch_1):page13_i351@pure_quanta.q_res(chips)',
 PATH='I351',
 DRAWING='@SCM_LIB.SCM(SCH_1):PAGE13',
 PHYS_PAGE='13',
 XY='(3800,2575)',
 ROT='0',
 VER='1',
 PACK_TYPE='0402LF',
 LOCATION='R826',
 CDS_LIB='pure_quanta',
 CDS_PART_NAME='Q_RES_0402LF-33.2,1%,1/16W,CHIA',
 WATTAGE='1/16W',
 TOLERANCE='1%',
 MATERIAL='CHIP',
 VALUE='33.2',
 PRIM_FILE='W:/<user>/logical/q_res/chips/chips.prt';

PART_NAME
 R827 'Q_RES_0402LF-33.2,1%,1/16W,CHIA':;

SECTION_NUMBER 1
 '@SCM_LIB.SCM(SCH_1):PAGE25_I73@PURE_QUANTA.Q_RES(CHIPS)':
 C_PATH='@scm_lib.scm(sch_1):page25_i73@pure_quanta.q_res(chips)',
 P_PATH='@scm_lib.scm(sch_1):page25_i73@pure_quanta.q_res(chips)',
 PATH='I73',
 DRAWING='@SCM_LIB.SCM(SCH_1):PAGE25',
 PHYS_PAGE='25',
 XY='(1825,-950)',
 ROT='0',
 VER='1',
 PACK_TYPE='0402LF',
 LOCATION='R827',
 CDS_LIB='pure_quanta',
 CDS_PART_NAME='Q_RES_0402LF-33.2,1%,1/16W,CHIA',
 WATTAGE='1/16W',
 TOLERANCE='1%',
 MATERIAL='CHIP',
 VALUE='33.2',
 PRIM_FILE='W:/<user>/logical/q_res/chips/chips.prt';

PART_NAME
 R828 'Q_RES_0402LF-4.7K,1%,1/16W,EMPA':;

SECTION_NUMBER 1
 '@SCM_LIB.SCM(SCH_1):PAGE11_I241@PURE_QUANTA.Q_RES(CHIPS)':
 C_PATH='@scm_lib.scm(sch_1):page11_i241@pure_quanta.q_res(chips)',
 P_PATH='@scm_lib.scm(sch_1):page11_i241@pure_quanta.q_res(chips)',
 PATH='I241',
 DRAWING='@SCM_LIB.SCM(SCH_1):PAGE11',
 PHYS_PAGE='11',
 XY='(-3325,2975)',
 ROT='0',
 VER='1',
 PACK_TYPE='0402LF',
 LOCATION='R828',
 CDS_LIB='pure_quanta',
 CDS_PART_NAME='Q_RES_0402LF-4.7K,1%,1/16W,EMPA',
 WATTAGE='1/16W',
 TOLERANCE='1%',
 MATERIAL='EMPTY',
 VALUE='4.7K',
 PRIM_FILE='W:/<user>/logical/q_res/chips/chips.prt';

PART_NAME
 R829 'Q_RES_0402LF-25.5K,1%,1/16W,CHA':;

SECTION_NUMBER 1
 '@SCM_LIB.SCM(SCH_1):PAGE53_I62@PURE_QUANTA.Q_RES(CHIPS)':
 C_PATH='@scm_lib.scm(sch_1):page53_i62@pure_quanta.q_res(chips)',
 P_PATH='@scm_lib.scm(sch_1):page53_i62@pure_quanta.q_res(chips)',
 PATH='I62',
 DRAWING='@SCM_LIB.SCM(SCH_1):PAGE53',
 PHYS_PAGE='53',
 XY='(325,250)',
 ROT='0',
 VER='2',
 PACK_TYPE='0402LF',
 LOCATION='R829',
 CDS_LIB='pure_quanta',
 CDS_PART_NAME='Q_RES_0402LF-25.5K,1%,1/16W,CHA',
 WATTAGE='1/16W',
 TOLERANCE='1%',
 MATERIAL='CHIP',
 VALUE='25.5K',
 PRIM_FILE='W:/<user>/logical/q_res/chips/chips.prt';

PART_NAME
 R830 'Q_RES_0402LF-12K,1%,1/16W,CHIPA':;

SECTION_NUMBER 1
 '@SCM_LIB.SCM(SCH_1):PAGE53_I61@PURE_QUANTA.Q_RES(CHIPS)':
 C_PATH='@scm_lib.scm(sch_1):page53_i61@pure_quanta.q_res(chips)',
 P_PATH='@scm_lib.scm(sch_1):page53_i61@pure_quanta.q_res(chips)',
 PATH='I61',
 DRAWING='@SCM_LIB.SCM(SCH_1):PAGE53',
 PHYS_PAGE='53',
 XY='(325,-175)',
 ROT='0',
 VER='2',
 PACK_TYPE='0402LF',
 LOCATION='R830',
 CDS_LIB='pure_quanta',
 CDS_PART_NAME='Q_RES_0402LF-12K,1%,1/16W,CHIPA',
 WATTAGE='1/16W',
 TOLERANCE='1%',
 MATERIAL='CHIP',
 VALUE='12K',
 PRIM_FILE='W:/<user>/logical/q_res/chips/chips.prt';

PART_NAME
 R831 'Q_RES_0402LF-15K,1%,1/16W,CHIPA':;

SECTION_NUMBER 1
 '@SCM_LIB.SCM(SCH_1):PAGE54_I98@PURE_QUANTA.Q_RES(CHIPS)':
 C_PATH='@scm_lib.scm(sch_1):page54_i98@pure_quanta.q_res(chips)',
 P_PATH='@scm_lib.scm(sch_1):page54_i98@pure_quanta.q_res(chips)',
 PATH='I98',
 DRAWING='@SCM_LIB.SCM(SCH_1):PAGE54',
 PHYS_PAGE='54',
 XY='(975,2000)',
 ROT='0',
 VER='2',
 PACK_TYPE='0402LF',
 LOCATION='R831',
 CDS_LIB='pure_quanta',
 CDS_PART_NAME='Q_RES_0402LF-15K,1%,1/16W,CHIPA',
 WATTAGE='1/16W',
 TOLERANCE='1%',
 MATERIAL='CHIP',
 VALUE='15K',
 PRIM_FILE='W:/<user>/logical/q_res/chips/chips.prt';

PART_NAME
 R832 'Q_RES_0402LF-12K,1%,1/16W,CHIPA':;

SECTION_NUMBER 1
 '@SCM_LIB.SCM(SCH_1):PAGE54_I97@PURE_QUANTA.Q_RES(CHIPS)':
 C_PATH='@scm_lib.scm(sch_1):page54_i97@pure_quanta.q_res(chips)',
 P_PATH='@scm_lib.scm(sch_1):page54_i97@pure_quanta.q_res(chips)',
 PATH='I97',
 DRAWING='@SCM_LIB.SCM(SCH_1):PAGE54',
 PHYS_PAGE='54',
 XY='(975,1575)',
 ROT='0',
 VER='2',
 PACK_TYPE='0402LF',
 LOCATION='R832',
 CDS_LIB='pure_quanta',
 CDS_PART_NAME='Q_RES_0402LF-12K,1%,1/16W,CHIPA',
 WATTAGE='1/16W',
 TOLERANCE='1%',
 MATERIAL='CHIP',
 VALUE='12K',
 PRIM_FILE='W:/<user>/logical/q_res/chips/chips.prt';

PART_NAME
 R833 'Q_RES_0402LF-33.2,1%,1/16W,CHIA':;

SECTION_NUMBER 1
 '@SCM_LIB.SCM(SCH_1):PAGE35_I139@PURE_QUANTA.Q_RES(CHIPS)':
 C_PATH='@scm_lib.scm(sch_1):page35_i139@pure_quanta.q_res(chips)',
 P_PATH='@scm_lib.scm(sch_1):page35_i139@pure_quanta.q_res(chips)',
 PATH='I139',
 DRAWING='@SCM_LIB.SCM(SCH_1):PAGE35',
 PHYS_PAGE='35',
 XY='(-7300,4350)',
 ROT='0',
 VER='1',
 PACK_TYPE='0402LF',
 LOCATION='R833',
 CDS_LIB='pure_quanta',
 CDS_PART_NAME='Q_RES_0402LF-33.2,1%,1/16W,CHIA',
 WATTAGE='1/16W',
 TOLERANCE='1%',
 MATERIAL='CHIP',
 VALUE='33.2',
 PRIM_FILE='W:/<user>/logical/q_res/chips/chips.prt';

PART_NAME
 R834 'Q_RES_0402LF-10K,1%,1/16W,EMPTA':;

SECTION_NUMBER 1
 '@SCM_LIB.SCM(SCH_1):PAGE32_I131@PURE_QUANTA.Q_RES(CHIPS)':
 C_PATH='@scm_lib.scm(sch_1):page32_i131@pure_quanta.q_res(chips)',
 P_PATH='@scm_lib.scm(sch_1):page32_i131@pure_quanta.q_res(chips)',
 PATH='I131',
 DRAWING='@SCM_LIB.SCM(SCH_1):PAGE32',
 PHYS_PAGE='32',
 XY='(-2425,50)',
 ROT='0',
 VER='1',
 PACK_TYPE='0402LF',
 LOCATION='R834',
 CDS_LIB='pure_quanta',
 CDS_PART_NAME='Q_RES_0402LF-10K,1%,1/16W,EMPTA',
 WATTAGE='1/16W',
 TOLERANCE='1%',
 MATERIAL='EMPTY',
 VALUE='10K',
 PRIM_FILE='W:/<user>/logical/q_res/chips/chips.prt';

PART_NAME
 R835 'Q_RES_0402LF-4.7K,1%,1/16W,CHIA':;

SECTION_NUMBER 1
 '@SCM_LIB.SCM(SCH_1):PAGE42_I63@PURE_QUANTA.Q_RES(CHIPS)':
 C_PATH='@scm_lib.scm(sch_1):page42_i63@pure_quanta.q_res(chips)',
 P_PATH='@scm_lib.scm(sch_1):page42_i63@pure_quanta.q_res(chips)',
 PATH='I63',
 DRAWING='@SCM_LIB.SCM(SCH_1):PAGE42',
 PHYS_PAGE='42',
 XY='(11950,4050)',
 ROT='0',
 VER='1',
 PACK_TYPE='0402LF',
 LOCATION='R835',
 CDS_LIB='pure_quanta',
 CDS_PART_NAME='Q_RES_0402LF-4.7K,1%,1/16W,CHIA',
 WATTAGE='1/16W',
 TOLERANCE='1%',
 MATERIAL='CHIP',
 VALUE='4.7K',
 PRIM_FILE='W:/<user>/logical/q_res/chips/chips.prt';

PART_NAME
 R836 'Q_RES_0402LF-33.2,1%,1/16W,CHIA':;

SECTION_NUMBER 1
 '@SCM_LIB.SCM(SCH_1):PAGE13_I225@PURE_QUANTA.Q_RES(CHIPS)':
 C_PATH='@scm_lib.scm(sch_1):page13_i225@pure_quanta.q_res(chips)',
 P_PATH='@scm_lib.scm(sch_1):page13_i225@pure_quanta.q_res(chips)',
 PATH='I225',
 DRAWING='@SCM_LIB.SCM(SCH_1):PAGE13',
 PHYS_PAGE='13',
 XY='(-2300,2375)',
 ROT='0',
 VER='1',
 PACK_TYPE='0402LF',
 LOCATION='R836',
 CDS_LIB='pure_quanta',
 CDS_PART_NAME='Q_RES_0402LF-33.2,1%,1/16W,CHIA',
 WATTAGE='1/16W',
 TOLERANCE='1%',
 MATERIAL='CHIP',
 VALUE='33.2',
 PRIM_FILE='W:/<user>/logical/q_res/chips/chips.prt';

PART_NAME
 R837 'Q_RES_0402LF-33.2,1%,1/16W,CHIA':;

SECTION_NUMBER 1
 '@SCM_LIB.SCM(SCH_1):PAGE34_I158@PURE_QUANTA.Q_RES(CHIPS)':
 C_PATH='@scm_lib.scm(sch_1):page34_i158@pure_quanta.q_res(chips)',
 P_PATH='@scm_lib.scm(sch_1):page34_i158@pure_quanta.q_res(chips)',
 PATH='I158',
 DRAWING='@SCM_LIB.SCM(SCH_1):PAGE34',
 PHYS_PAGE='34',
 XY='(-7000,4900)',
 ROT='0',
 VER='1',
 PACK_TYPE='0402LF',
 LOCATION='R837',
 CDS_LIB='pure_quanta',
 CDS_PART_NAME='Q_RES_0402LF-33.2,1%,1/16W,CHIA',
 WATTAGE='1/16W',
 TOLERANCE='1%',
 MATERIAL='CHIP',
 VALUE='33.2',
 PRIM_FILE='W:/<user>/logical/q_res/chips/chips.prt';

PART_NAME
 R838 'Q_RES_0402LF-0,5%,1/16W,CHIP,CA':;

SECTION_NUMBER 1
 '@SCM_LIB.SCM(SCH_1):PAGE10_I568@PURE_QUANTA.Q_RES(CHIPS)':
 C_PATH='@scm_lib.scm(sch_1):page10_i568@pure_quanta.q_res(chips)',
 P_PATH='@scm_lib.scm(sch_1):page10_i568@pure_quanta.q_res(chips)',
 PATH='I568',
 DRAWING='@SCM_LIB.SCM(SCH_1):PAGE10',
 PHYS_PAGE='10',
 XY='(-6175,-1475)',
 ROT='2',
 VER='1',
 PACK_TYPE='0402LF',
 CDS_LIB='pure_quanta',
 CDS_PART_NAME='Q_RES_0402LF-0,5%,1/16W,CHIP,CA',
 WATTAGE='1/16W',
 TOLERANCE='5%',
 MATERIAL='CHIP',
 VALUE='0',
 PRIM_FILE='W:/<user>/logical/q_res/chips/chips.prt';

PART_NAME
 R839 'Q_RES_0402LF-8.2K,5%,1/16W,CHIA':;

SECTION_NUMBER 1
 '@SCM_LIB.SCM(SCH_1):PAGE49_I22@PURE_QUANTA.Q_RES(CHIPS)':
 C_PATH='@scm_lib.scm(sch_1):page49_i22@pure_quanta.q_res(chips)',
 P_PATH='@scm_lib.scm(sch_1):page49_i22@pure_quanta.q_res(chips)',
 PATH='I22',
 DRAWING='@SCM_LIB.SCM(SCH_1):PAGE49',
 PHYS_PAGE='49',
 XY='(-7950,1075)',
 ROT='0',
 VER='2',
 PACK_TYPE='0402LF',
 LOCATION='R839',
 CDS_LIB='pure_quanta',
 CDS_PART_NAME='Q_RES_0402LF-8.2K,5%,1/16W,CHIA',
 WATTAGE='1/16W',
 TOLERANCE='5%',
 MATERIAL='CHIP',
 VALUE='8.2K',
 PRIM_FILE='W:/<user>/logical/q_res/chips/chips.prt';

PART_NAME
 R840 'Q_RES_0402LF-33.2,1%,1/16W,CHIA':;

SECTION_NUMBER 1
 '@SCM_LIB.SCM(SCH_1):PAGE13_I295@PURE_QUANTA.Q_RES(CHIPS)':
 C_PATH='@scm_lib.scm(sch_1):page13_i295@pure_quanta.q_res(chips)',
 P_PATH='@scm_lib.scm(sch_1):page13_i295@pure_quanta.q_res(chips)',
 PATH='I295',
 DRAWING='@SCM_LIB.SCM(SCH_1):PAGE13',
 PHYS_PAGE='13',
 XY='(-2300,2275)',
 ROT='0',
 VER='1',
 PACK_TYPE='0402LF',
 LOCATION='R840',
 CDS_LIB='pure_quanta',
 CDS_PART_NAME='Q_RES_0402LF-33.2,1%,1/16W,CHIA',
 WATTAGE='1/16W',
 TOLERANCE='1%',
 MATERIAL='CHIP',
 VALUE='33.2',
 PRIM_FILE='W:/<user>/logical/q_res/chips/chips.prt';

PART_NAME
 R841 'Q_RES_0402LF-33.2,1%,1/16W,CHIA':;

SECTION_NUMBER 1
 '@SCM_LIB.SCM(SCH_1):PAGE35_I142@PURE_QUANTA.Q_RES(CHIPS)':
 C_PATH='@scm_lib.scm(sch_1):page35_i142@pure_quanta.q_res(chips)',
 P_PATH='@scm_lib.scm(sch_1):page35_i142@pure_quanta.q_res(chips)',
 PATH='I142',
 DRAWING='@SCM_LIB.SCM(SCH_1):PAGE35',
 PHYS_PAGE='35',
 XY='(-1800,3800)',
 ROT='0',
 VER='1',
 PACK_TYPE='0402LF',
 LOCATION='R841',
 CDS_LIB='pure_quanta',
 CDS_PART_NAME='Q_RES_0402LF-33.2,1%,1/16W,CHIA',
 WATTAGE='1/16W',
 TOLERANCE='1%',
 MATERIAL='CHIP',
 VALUE='33.2',
 PRIM_FILE='W:/<user>/logical/q_res/chips/chips.prt';

PART_NAME
 R842 'Q_RES_0402LF-4.7K,1%,1/16W,CHIA':;

SECTION_NUMBER 1
 '@SCM_LIB.SCM(SCH_1):PAGE27_I168@PURE_QUANTA.Q_RES(CHIPS)':
 C_PATH='@scm_lib.scm(sch_1):page27_i168@pure_quanta.q_res(chips)',
 P_PATH='@scm_lib.scm(sch_1):page27_i168@pure_quanta.q_res(chips)',
 PATH='I168',
 DRAWING='@SCM_LIB.SCM(SCH_1):PAGE27',
 PHYS_PAGE='27',
 XY='(-3625,1050)',
 ROT='0',
 VER='1',
 PACK_TYPE='0402LF',
 LOCATION='R842',
 CDS_LIB='pure_quanta',
 CDS_PART_NAME='Q_RES_0402LF-4.7K,1%,1/16W,CHIA',
 WATTAGE='1/16W',
 TOLERANCE='1%',
 MATERIAL='CHIP',
 VALUE='4.7K',
 PRIM_FILE='W:/<user>/logical/q_res/chips/chips.prt';

PART_NAME
 R843 'Q_RES_0402LF-4.7K,1%,1/16W,CHIA':;

SECTION_NUMBER 1
 '@SCM_LIB.SCM(SCH_1):PAGE27_I177@PURE_QUANTA.Q_RES(CHIPS)':
 C_PATH='@scm_lib.scm(sch_1):page27_i177@pure_quanta.q_res(chips)',
 P_PATH='@scm_lib.scm(sch_1):page27_i177@pure_quanta.q_res(chips)',
 PATH='I177',
 DRAWING='@SCM_LIB.SCM(SCH_1):PAGE27',
 PHYS_PAGE='27',
 XY='(-3625,975)',
 ROT='0',
 VER='1',
 PACK_TYPE='0402LF',
 LOCATION='R843',
 CDS_LIB='pure_quanta',
 CDS_PART_NAME='Q_RES_0402LF-4.7K,1%,1/16W,CHIA',
 WATTAGE='1/16W',
 TOLERANCE='1%',
 MATERIAL='CHIP',
 VALUE='4.7K',
 PRIM_FILE='W:/<user>/logical/q_res/chips/chips.prt';

PART_NAME
 R844 'Q_RES_0402LF-4.7K,1%,1/16W,CHIA':;

SECTION_NUMBER 1
 '@SCM_LIB.SCM(SCH_1):PAGE27_I179@PURE_QUANTA.Q_RES(CHIPS)':
 C_PATH='@scm_lib.scm(sch_1):page27_i179@pure_quanta.q_res(chips)',
 P_PATH='@scm_lib.scm(sch_1):page27_i179@pure_quanta.q_res(chips)',
 PATH='I179',
 DRAWING='@SCM_LIB.SCM(SCH_1):PAGE27',
 PHYS_PAGE='27',
 XY='(-3625,825)',
 ROT='0',
 VER='1',
 PACK_TYPE='0402LF',
 LOCATION='R844',
 CDS_LIB='pure_quanta',
 CDS_PART_NAME='Q_RES_0402LF-4.7K,1%,1/16W,CHIA',
 WATTAGE='1/16W',
 TOLERANCE='1%',
 MATERIAL='CHIP',
 VALUE='4.7K',
 PRIM_FILE='W:/<user>/logical/q_res/chips/chips.prt';

PART_NAME
 R846 'Q_RES_0402LF-4.7K,1%,1/16W,EMPA':;

SECTION_NUMBER 1
 '@SCM_LIB.SCM(SCH_1):PAGE27_I181@PURE_QUANTA.Q_RES(CHIPS)':
 C_PATH='@scm_lib.scm(sch_1):page27_i181@pure_quanta.q_res(chips)',
 P_PATH='@scm_lib.scm(sch_1):page27_i181@pure_quanta.q_res(chips)',
 PATH='I181',
 DRAWING='@SCM_LIB.SCM(SCH_1):PAGE27',
 PHYS_PAGE='27',
 XY='(-3625,675)',
 ROT='0',
 VER='1',
 PACK_TYPE='0402LF',
 LOCATION='R846',
 CDS_LIB='pure_quanta',
 CDS_PART_NAME='Q_RES_0402LF-4.7K,1%,1/16W,EMPA',
 WATTAGE='1/16W',
 TOLERANCE='1%',
 MATERIAL='EMPTY',
 VALUE='4.7K',
 PRIM_FILE='W:/<user>/logical/q_res/chips/chips.prt';

PART_NAME
 R847 'Q_RES_0402LF-0,5%,1/16W,CHIP,CA':;

SECTION_NUMBER 1
 '@SCM_LIB.SCM(SCH_1):PAGE10_I569@PURE_QUANTA.Q_RES(CHIPS)':
 C_PATH='@scm_lib.scm(sch_1):page10_i569@pure_quanta.q_res(chips)',
 P_PATH='@scm_lib.scm(sch_1):page10_i569@pure_quanta.q_res(chips)',
 PATH='I569',
 DRAWING='@SCM_LIB.SCM(SCH_1):PAGE10',
 PHYS_PAGE='10',
 XY='(-6175,-1525)',
 ROT='2',
 VER='1',
 PACK_TYPE='0402LF',
 CDS_LIB='pure_quanta',
 CDS_PART_NAME='Q_RES_0402LF-0,5%,1/16W,CHIP,CA',
 WATTAGE='1/16W',
 TOLERANCE='5%',
 MATERIAL='CHIP',
 VALUE='0',
 PRIM_FILE='W:/<user>/logical/q_res/chips/chips.prt';

PART_NAME
 R848 'Q_RES_0402LF-4.7K,1%,1/16W,CHIA':;

SECTION_NUMBER 1
 '@SCM_LIB.SCM(SCH_1):PAGE27_I182@PURE_QUANTA.Q_RES(CHIPS)':
 C_PATH='@scm_lib.scm(sch_1):page27_i182@pure_quanta.q_res(chips)',
 P_PATH='@scm_lib.scm(sch_1):page27_i182@pure_quanta.q_res(chips)',
 PATH='I182',
 DRAWING='@SCM_LIB.SCM(SCH_1):PAGE27',
 PHYS_PAGE='27',
 XY='(-3625,525)',
 ROT='0',
 VER='1',
 PACK_TYPE='0402LF',
 LOCATION='R848',
 CDS_LIB='pure_quanta',
 CDS_PART_NAME='Q_RES_0402LF-4.7K,1%,1/16W,CHIA',
 WATTAGE='1/16W',
 TOLERANCE='1%',
 MATERIAL='CHIP',
 VALUE='4.7K',
 PRIM_FILE='W:/<user>/logical/q_res/chips/chips.prt';

PART_NAME
 R849 'Q_RES_0402LF-33.2,1%,1/16W,CHIA':;

SECTION_NUMBER 1
 '@SCM_LIB.SCM(SCH_1):PAGE21_I157@PURE_QUANTA.Q_RES(CHIPS)':
 C_PATH='@scm_lib.scm(sch_1):page21_i157@pure_quanta.q_res(chips)',
 P_PATH='@scm_lib.scm(sch_1):page21_i157@pure_quanta.q_res(chips)',
 PATH='I157',
 DRAWING='@SCM_LIB.SCM(SCH_1):PAGE21',
 SEC_TYPE='0402LF',
 PHYS_PAGE='21',
 XY='(100,2600)',
 ROT='0',
 VER='1',
 PACK_TYPE='0402LF',
 SEC='1',
 CDS_LIB='pure_quanta',
 CDS_PART_NAME='Q_RES_0402LF-33.2,1%,1/16W,CHIA',
 WATTAGE='1/16W',
 TOLERANCE='1%',
 MATERIAL='CHIP',
 VALUE='33.2',
 PRIM_FILE='W:/<user>/logical/q_res/chips/chips.prt';

PART_NAME
 R850 'Q_RES_0402LF-33.2,1%,1/16W,CHIA':;

SECTION_NUMBER 1
 '@SCM_LIB.SCM(SCH_1):PAGE21_I156@PURE_QUANTA.Q_RES(CHIPS)':
 C_PATH='@scm_lib.scm(sch_1):page21_i156@pure_quanta.q_res(chips)',
 P_PATH='@scm_lib.scm(sch_1):page21_i156@pure_quanta.q_res(chips)',
 PATH='I156',
 DRAWING='@SCM_LIB.SCM(SCH_1):PAGE21',
 SEC_TYPE='0402LF',
 PHYS_PAGE='21',
 XY='(100,2550)',
 ROT='0',
 VER='1',
 PACK_TYPE='0402LF',
 SEC='1',
 CDS_LIB='pure_quanta',
 CDS_PART_NAME='Q_RES_0402LF-33.2,1%,1/16W,CHIA',
 WATTAGE='1/16W',
 TOLERANCE='1%',
 MATERIAL='CHIP',
 VALUE='33.2',
 PRIM_FILE='W:/<user>/logical/q_res/chips/chips.prt';

PART_NAME
 R851 'Q_RES_0402LF-4.7K,1%,1/16W,CHIA':;

SECTION_NUMBER 1
 '@SCM_LIB.SCM(SCH_1):PAGE27_I184@PURE_QUANTA.Q_RES(CHIPS)':
 C_PATH='@scm_lib.scm(sch_1):page27_i184@pure_quanta.q_res(chips)',
 P_PATH='@scm_lib.scm(sch_1):page27_i184@pure_quanta.q_res(chips)',
 PATH='I184',
 DRAWING='@SCM_LIB.SCM(SCH_1):PAGE27',
 PHYS_PAGE='27',
 XY='(-3625,600)',
 ROT='0',
 VER='1',
 PACK_TYPE='0402LF',
 LOCATION='R851',
 CDS_LIB='pure_quanta',
 CDS_PART_NAME='Q_RES_0402LF-4.7K,1%,1/16W,CHIA',
 WATTAGE='1/16W',
 TOLERANCE='1%',
 MATERIAL='CHIP',
 VALUE='4.7K',
 PRIM_FILE='W:/<user>/logical/q_res/chips/chips.prt';

PART_NAME
 R852 'Q_RES_0402LF-68.1,1%,1/16W,CHIA':;

SECTION_NUMBER 1
 '@SCM_LIB.SCM(SCH_1):PAGE44_I366@PURE_QUANTA.Q_RES(CHIPS)':
 C_PATH='@scm_lib.scm(sch_1):page44_i366@pure_quanta.q_res(chips)',
 P_PATH='@scm_lib.scm(sch_1):page44_i366@pure_quanta.q_res(chips)',
 PATH='I366',
 DRAWING='@SCM_LIB.SCM(SCH_1):PAGE44',
 PHYS_PAGE='44',
 XY='(-2425,225)',
 ROT='0',
 VER='1',
 PACK_TYPE='0402LF',
 LOCATION='R852',
 CDS_LIB='pure_quanta',
 CDS_PART_NAME='Q_RES_0402LF-68.1,1%,1/16W,CHIA',
 WATTAGE='1/16W',
 TOLERANCE='1%',
 MATERIAL='CHIP',
 VALUE='68.1',
 PRIM_FILE='W:/<user>/logical/q_res/chips/chips.prt';

PART_NAME
 R853 'Q_RES_0402LF-0,5%,1/16W,CHIP,CA':;

SECTION_NUMBER 1
 '@SCM_LIB.SCM(SCH_1):PAGE15_I387@PURE_QUANTA.Q_RES(CHIPS)':
 C_PATH='@scm_lib.scm(sch_1):page15_i387@pure_quanta.q_res(chips)',
 P_PATH='@scm_lib.scm(sch_1):page15_i387@pure_quanta.q_res(chips)',
 PATH='I387',
 DRAWING='@SCM_LIB.SCM(SCH_1):PAGE15',
 PHYS_PAGE='15',
 XY='(3200,1525)',
 ROT='0',
 VER='1',
 PACK_TYPE='0402LF',
 CDS_LIB='pure_quanta',
 CDS_PART_NAME='Q_RES_0402LF-0,5%,1/16W,CHIP,CA',
 WATTAGE='1/16W',
 TOLERANCE='5%',
 MATERIAL='CHIP',
 VALUE='0',
 PRIM_FILE='W:/<user>/logical/q_res/chips/chips.prt';

PART_NAME
 R854 'Q_RES_0402LF-4.7K,1%,1/16W,EMPA':;

SECTION_NUMBER 1
 '@SCM_LIB.SCM(SCH_1):PAGE14_I221@PURE_QUANTA.Q_RES(CHIPS)':
 C_PATH='@scm_lib.scm(sch_1):page14_i221@pure_quanta.q_res(chips)',
 P_PATH='@scm_lib.scm(sch_1):page14_i221@pure_quanta.q_res(chips)',
 PATH='I221',
 DRAWING='@SCM_LIB.SCM(SCH_1):PAGE14',
 PHYS_PAGE='14',
 XY='(4400,4350)',
 ROT='0',
 VER='2',
 PACK_TYPE='0402LF',
 LOCATION='R854',
 CDS_LIB='pure_quanta',
 CDS_PART_NAME='Q_RES_0402LF-4.7K,1%,1/16W,EMPA',
 WATTAGE='1/16W',
 TOLERANCE='1%',
 MATERIAL='EMPTY',
 VALUE='4.7K',
 PRIM_FILE='W:/<user>/logical/q_res/chips/chips.prt';

PART_NAME
 R855 'Q_RES_0402LF-1K,1%,1/16W,CHIP,A':;

SECTION_NUMBER 1
 '@SCM_LIB.SCM(SCH_1):PAGE14_I223@PURE_QUANTA.Q_RES(CHIPS)':
 C_PATH='@scm_lib.scm(sch_1):page14_i223@pure_quanta.q_res(chips)',
 P_PATH='@scm_lib.scm(sch_1):page14_i223@pure_quanta.q_res(chips)',
 PATH='I223',
 DRAWING='@SCM_LIB.SCM(SCH_1):PAGE14',
 PHYS_PAGE='14',
 XY='(4400,3800)',
 ROT='0',
 VER='2',
 PACK_TYPE='0402LF',
 LOCATION='R855',
 CDS_LIB='pure_quanta',
 CDS_PART_NAME='Q_RES_0402LF-1K,1%,1/16W,CHIP,A',
 WATTAGE='1/16W',
 TOLERANCE='1%',
 MATERIAL='CHIP',
 VALUE='1K',
 PRIM_FILE='W:/<user>/logical/q_res/chips/chips.prt';

PART_NAME
 R856 'Q_RES_0402LF-4.7K,1%,1/16W,CHIA':;

SECTION_NUMBER 1
 '@SCM_LIB.SCM(SCH_1):PAGE14_I220@PURE_QUANTA.Q_RES(CHIPS)':
 C_PATH='@scm_lib.scm(sch_1):page14_i220@pure_quanta.q_res(chips)',
 P_PATH='@scm_lib.scm(sch_1):page14_i220@pure_quanta.q_res(chips)',
 PATH='I220',
 DRAWING='@SCM_LIB.SCM(SCH_1):PAGE14',
 PHYS_PAGE='14',
 XY='(4625,4350)',
 ROT='0',
 VER='2',
 PACK_TYPE='0402LF',
 LOCATION='R856',
 CDS_LIB='pure_quanta',
 CDS_PART_NAME='Q_RES_0402LF-4.7K,1%,1/16W,CHIA',
 WATTAGE='1/16W',
 TOLERANCE='1%',
 MATERIAL='CHIP',
 VALUE='4.7K',
 PRIM_FILE='W:/<user>/logical/q_res/chips/chips.prt';

PART_NAME
 R857 'Q_RES_0402LF-1K,1%,1/16W,EMPTYA':;

SECTION_NUMBER 1
 '@SCM_LIB.SCM(SCH_1):PAGE14_I224@PURE_QUANTA.Q_RES(CHIPS)':
 C_PATH='@scm_lib.scm(sch_1):page14_i224@pure_quanta.q_res(chips)',
 P_PATH='@scm_lib.scm(sch_1):page14_i224@pure_quanta.q_res(chips)',
 PATH='I224',
 DRAWING='@SCM_LIB.SCM(SCH_1):PAGE14',
 PHYS_PAGE='14',
 XY='(4625,3800)',
 ROT='0',
 VER='2',
 PACK_TYPE='0402LF',
 LOCATION='R857',
 CDS_LIB='pure_quanta',
 CDS_PART_NAME='Q_RES_0402LF-1K,1%,1/16W,EMPTYA',
 WATTAGE='1/16W',
 TOLERANCE='1%',
 MATERIAL='EMPTY',
 VALUE='1K',
 PRIM_FILE='W:/<user>/logical/q_res/chips/chips.prt';

PART_NAME
 R858 'Q_RES_0402LF-4.7K,1%,1/16W,CHIA':;

SECTION_NUMBER 1
 '@SCM_LIB.SCM(SCH_1):PAGE14_I222@PURE_QUANTA.Q_RES(CHIPS)':
 C_PATH='@scm_lib.scm(sch_1):page14_i222@pure_quanta.q_res(chips)',
 P_PATH='@scm_lib.scm(sch_1):page14_i222@pure_quanta.q_res(chips)',
 PATH='I222',
 DRAWING='@SCM_LIB.SCM(SCH_1):PAGE14',
 PHYS_PAGE='14',
 XY='(4850,4350)',
 ROT='0',
 VER='2',
 PACK_TYPE='0402LF',
 LOCATION='R858',
 CDS_LIB='pure_quanta',
 CDS_PART_NAME='Q_RES_0402LF-4.7K,1%,1/16W,CHIA',
 WATTAGE='1/16W',
 TOLERANCE='1%',
 MATERIAL='CHIP',
 VALUE='4.7K',
 PRIM_FILE='W:/<user>/logical/q_res/chips/chips.prt';

PART_NAME
 R859 'Q_RES_0402LF-33.2,1%,1/16W,CHIA':;

SECTION_NUMBER 1
 '@SCM_LIB.SCM(SCH_1):PAGE44_I339@PURE_QUANTA.Q_RES(CHIPS)':
 C_PATH='@scm_lib.scm(sch_1):page44_i339@pure_quanta.q_res(chips)',
 P_PATH='@scm_lib.scm(sch_1):page44_i339@pure_quanta.q_res(chips)',
 PATH='I339',
 DRAWING='@SCM_LIB.SCM(SCH_1):PAGE44',
 PHYS_PAGE='44',
 XY='(-2600,1700)',
 ROT='0',
 VER='1',
 PACK_TYPE='0402LF',
 LOCATION='R859',
 CDS_LIB='pure_quanta',
 CDS_PART_NAME='Q_RES_0402LF-33.2,1%,1/16W,CHIA',
 WATTAGE='1/16W',
 TOLERANCE='1%',
 MATERIAL='CHIP',
 VALUE='33.2',
 PRIM_FILE='W:/<user>/logical/q_res/chips/chips.prt';

PART_NAME
 R860 'Q_RES_0402LF-22,1%,1/16W,CHIP,A':;

SECTION_NUMBER 1
 '@SCM_LIB.SCM(SCH_1):PAGE44_I362@PURE_QUANTA.Q_RES(CHIPS)':
 C_PATH='@scm_lib.scm(sch_1):page44_i362@pure_quanta.q_res(chips)',
 P_PATH='@scm_lib.scm(sch_1):page44_i362@pure_quanta.q_res(chips)',
 PATH='I362',
 DRAWING='@SCM_LIB.SCM(SCH_1):PAGE44',
 PHYS_PAGE='44',
 XY='(-2600,1650)',
 ROT='0',
 VER='1',
 PACK_TYPE='0402LF',
 LOCATION='R860',
 CDS_LIB='pure_quanta',
 CDS_PART_NAME='Q_RES_0402LF-22,1%,1/16W,CHIP,A',
 WATTAGE='1/16W',
 TOLERANCE='1%',
 MATERIAL='CHIP',
 VALUE='22',
 PRIM_FILE='W:/<user>/logical/q_res/chips/chips.prt';

PART_NAME
 R861 'Q_RES_0402LF-22,1%,1/16W,CHIP,A':;

SECTION_NUMBER 1
 '@SCM_LIB.SCM(SCH_1):PAGE44_I363@PURE_QUANTA.Q_RES(CHIPS)':
 C_PATH='@scm_lib.scm(sch_1):page44_i363@pure_quanta.q_res(chips)',
 P_PATH='@scm_lib.scm(sch_1):page44_i363@pure_quanta.q_res(chips)',
 PATH='I363',
 DRAWING='@SCM_LIB.SCM(SCH_1):PAGE44',
 PHYS_PAGE='44',
 XY='(-2600,1600)',
 ROT='0',
 VER='1',
 PACK_TYPE='0402LF',
 LOCATION='R861',
 CDS_LIB='pure_quanta',
 CDS_PART_NAME='Q_RES_0402LF-22,1%,1/16W,CHIP,A',
 WATTAGE='1/16W',
 TOLERANCE='1%',
 MATERIAL='CHIP',
 VALUE='22',
 PRIM_FILE='W:/<user>/logical/q_res/chips/chips.prt';

PART_NAME
 R862 'Q_RES_0402LF-22,1%,1/16W,CHIP,A':;

SECTION_NUMBER 1
 '@SCM_LIB.SCM(SCH_1):PAGE44_I364@PURE_QUANTA.Q_RES(CHIPS)':
 C_PATH='@scm_lib.scm(sch_1):page44_i364@pure_quanta.q_res(chips)',
 P_PATH='@scm_lib.scm(sch_1):page44_i364@pure_quanta.q_res(chips)',
 PATH='I364',
 DRAWING='@SCM_LIB.SCM(SCH_1):PAGE44',
 PHYS_PAGE='44',
 XY='(-2600,1550)',
 ROT='0',
 VER='1',
 PACK_TYPE='0402LF',
 LOCATION='R862',
 CDS_LIB='pure_quanta',
 CDS_PART_NAME='Q_RES_0402LF-22,1%,1/16W,CHIP,A',
 WATTAGE='1/16W',
 TOLERANCE='1%',
 MATERIAL='CHIP',
 VALUE='22',
 PRIM_FILE='W:/<user>/logical/q_res/chips/chips.prt';

PART_NAME
 R863 'Q_RES_0402LF-22,1%,1/16W,CHIP,A':;

SECTION_NUMBER 1
 '@SCM_LIB.SCM(SCH_1):PAGE44_I365@PURE_QUANTA.Q_RES(CHIPS)':
 C_PATH='@scm_lib.scm(sch_1):page44_i365@pure_quanta.q_res(chips)',
 P_PATH='@scm_lib.scm(sch_1):page44_i365@pure_quanta.q_res(chips)',
 PATH='I365',
 DRAWING='@SCM_LIB.SCM(SCH_1):PAGE44',
 PHYS_PAGE='44',
 XY='(-2600,1500)',
 ROT='0',
 VER='1',
 PACK_TYPE='0402LF',
 LOCATION='R863',
 CDS_LIB='pure_quanta',
 CDS_PART_NAME='Q_RES_0402LF-22,1%,1/16W,CHIP,A',
 WATTAGE='1/16W',
 TOLERANCE='1%',
 MATERIAL='CHIP',
 VALUE='22',
 PRIM_FILE='W:/<user>/logical/q_res/chips/chips.prt';

PART_NAME
 R864 'Q_RES_0402LF-33.2,1%,1/16W,CHIA':;

SECTION_NUMBER 1
 '@SCM_LIB.SCM(SCH_1):PAGE44_I342@PURE_QUANTA.Q_RES(CHIPS)':
 C_PATH='@scm_lib.scm(sch_1):page44_i342@pure_quanta.q_res(chips)',
 P_PATH='@scm_lib.scm(sch_1):page44_i342@pure_quanta.q_res(chips)',
 PATH='I342',
 DRAWING='@SCM_LIB.SCM(SCH_1):PAGE44',
 PHYS_PAGE='44',
 XY='(-2600,1450)',
 ROT='0',
 VER='1',
 PACK_TYPE='0402LF',
 LOCATION='R864',
 CDS_LIB='pure_quanta',
 CDS_PART_NAME='Q_RES_0402LF-33.2,1%,1/16W,CHIA',
 WATTAGE='1/16W',
 TOLERANCE='1%',
 MATERIAL='CHIP',
 VALUE='33.2',
 PRIM_FILE='W:/<user>/logical/q_res/chips/chips.prt';

PART_NAME
 R865 'Q_RES_0402LF-1K,1%,1/16W,EMPTYA':;

SECTION_NUMBER 1
 '@SCM_LIB.SCM(SCH_1):PAGE14_I225@PURE_QUANTA.Q_RES(CHIPS)':
 C_PATH='@scm_lib.scm(sch_1):page14_i225@pure_quanta.q_res(chips)',
 P_PATH='@scm_lib.scm(sch_1):page14_i225@pure_quanta.q_res(chips)',
 PATH='I225',
 DRAWING='@SCM_LIB.SCM(SCH_1):PAGE14',
 PHYS_PAGE='14',
 XY='(4850,3800)',
 ROT='0',
 VER='2',
 PACK_TYPE='0402LF',
 LOCATION='R865',
 CDS_LIB='pure_quanta',
 CDS_PART_NAME='Q_RES_0402LF-1K,1%,1/16W,EMPTYA',
 WATTAGE='1/16W',
 TOLERANCE='1%',
 MATERIAL='EMPTY',
 VALUE='1K',
 PRIM_FILE='W:/<user>/logical/q_res/chips/chips.prt';

PART_NAME
 R866 'Q_RES_0402LF-10K,1%,1/16W,CHIPA':;

SECTION_NUMBER 1
 '@SCM_LIB.SCM(SCH_1):PAGE44_I311@PURE_QUANTA.Q_RES(CHIPS)':
 C_PATH='@scm_lib.scm(sch_1):page44_i311@pure_quanta.q_res(chips)',
 P_PATH='@scm_lib.scm(sch_1):page44_i311@pure_quanta.q_res(chips)',
 PATH='I311',
 DRAWING='@SCM_LIB.SCM(SCH_1):PAGE44',
 PHYS_PAGE='44',
 XY='(1775,-1450)',
 ROT='2',
 VER='2',
 PACK_TYPE='0402LF',
 LOCATION='R866',
 CDS_LIB='pure_quanta',
 CDS_PART_NAME='Q_RES_0402LF-10K,1%,1/16W,CHIPA',
 WATTAGE='1/16W',
 TOLERANCE='1%',
 MATERIAL='CHIP',
 VALUE='10K',
 PRIM_FILE='W:/<user>/logical/q_res/chips/chips.prt';

PART_NAME
 R867 'Q_RES_0402LF-1K,1%,1/16W,EMPTYA':;

SECTION_NUMBER 1
 '@SCM_LIB.SCM(SCH_1):PAGE21_I161@PURE_QUANTA.Q_RES(CHIPS)':
 C_PATH='@scm_lib.scm(sch_1):page21_i161@pure_quanta.q_res(chips)',
 P_PATH='@scm_lib.scm(sch_1):page21_i161@pure_quanta.q_res(chips)',
 PATH='I161',
 DRAWING='@SCM_LIB.SCM(SCH_1):PAGE21',
 PHYS_PAGE='21',
 XY='(100,2450)',
 ROT='0',
 VER='1',
 PACK_TYPE='0402LF',
 CDS_LIB='pure_quanta',
 CDS_PART_NAME='Q_RES_0402LF-1K,1%,1/16W,EMPTYA',
 WATTAGE='1/16W',
 TOLERANCE='1%',
 MATERIAL='EMPTY',
 VALUE='1K',
 PRIM_FILE='W:/<user>/logical/q_res/chips/chips.prt';

PART_NAME
 R868 'Q_RES_0402LF-0,5%,1/16W,EMPTY,A':;

SECTION_NUMBER 1
 '@SCM_LIB.SCM(SCH_1):PAGE51_I54@PURE_QUANTA.Q_RES(CHIPS)':
 C_PATH='@scm_lib.scm(sch_1):page51_i54@pure_quanta.q_res(chips)',
 P_PATH='@scm_lib.scm(sch_1):page51_i54@pure_quanta.q_res(chips)',
 PATH='I54',
 DRAWING='@SCM_LIB.SCM(SCH_1):PAGE51',
 PHYS_PAGE='51',
 XY='(4275,1675)',
 ROT='0',
 VER='1',
 PACK_TYPE='0402LF',
 CDS_LIB='pure_quanta',
 CDS_PART_NAME='Q_RES_0402LF-0,5%,1/16W,EMPTY,A',
 WATTAGE='1/16W',
 TOLERANCE='5%',
 MATERIAL='EMPTY',
 VALUE='0',
 PRIM_FILE='W:/<user>/logical/q_res/chips/chips.prt';

PART_NAME
 R869 'Q_RES_0402LF-0,5%,1/16W,EMPTY,A':;

SECTION_NUMBER 1
 '@SCM_LIB.SCM(SCH_1):PAGE52_I139@PURE_QUANTA.Q_RES(CHIPS)':
 C_PATH='@scm_lib.scm(sch_1):page52_i139@pure_quanta.q_res(chips)',
 P_PATH='@scm_lib.scm(sch_1):page52_i139@pure_quanta.q_res(chips)',
 PATH='I139',
 DRAWING='@SCM_LIB.SCM(SCH_1):PAGE52',
 PHYS_PAGE='52',
 XY='(-2500,-1550)',
 ROT='0',
 VER='1',
 PACK_TYPE='0402LF',
 CDS_LIB='pure_quanta',
 CDS_PART_NAME='Q_RES_0402LF-0,5%,1/16W,EMPTY,A',
 WATTAGE='1/16W',
 TOLERANCE='5%',
 MATERIAL='EMPTY',
 VALUE='0',
 PRIM_FILE='W:/<user>/logical/q_res/chips/chips.prt';

PART_NAME
 R870 'Q_RES_0402LF-4.7K,1%,1/16W,EMPA':;

SECTION_NUMBER 1
 '@SCM_LIB.SCM(SCH_1):PAGE44_I315@PURE_QUANTA.Q_RES(CHIPS)':
 C_PATH='@scm_lib.scm(sch_1):page44_i315@pure_quanta.q_res(chips)',
 P_PATH='@scm_lib.scm(sch_1):page44_i315@pure_quanta.q_res(chips)',
 PATH='I315',
 DRAWING='@SCM_LIB.SCM(SCH_1):PAGE44',
 PHYS_PAGE='44',
 XY='(475,-1400)',
 ROT='2',
 VER='2',
 PACK_TYPE='0402LF',
 LOCATION='R870',
 CDS_LIB='pure_quanta',
 CDS_PART_NAME='Q_RES_0402LF-4.7K,1%,1/16W,EMPA',
 WATTAGE='1/16W',
 TOLERANCE='1%',
 MATERIAL='EMPTY',
 VALUE='4.7K',
 PRIM_FILE='W:/<user>/logical/q_res/chips/chips.prt';

PART_NAME
 R871 'Q_RES_0402LF-0,5%,1/16W,EMPTY,A':;

SECTION_NUMBER 1
 '@SCM_LIB.SCM(SCH_1):PAGE52_I137@PURE_QUANTA.Q_RES(CHIPS)':
 C_PATH='@scm_lib.scm(sch_1):page52_i137@pure_quanta.q_res(chips)',
 P_PATH='@scm_lib.scm(sch_1):page52_i137@pure_quanta.q_res(chips)',
 PATH='I137',
 DRAWING='@SCM_LIB.SCM(SCH_1):PAGE52',
 PHYS_PAGE='52',
 XY='(-1625,1550)',
 ROT='0',
 VER='1',
 PACK_TYPE='0402LF',
 CDS_LIB='pure_quanta',
 CDS_PART_NAME='Q_RES_0402LF-0,5%,1/16W,EMPTY,A',
 WATTAGE='1/16W',
 TOLERANCE='5%',
 MATERIAL='EMPTY',
 VALUE='0',
 PRIM_FILE='W:/<user>/logical/q_res/chips/chips.prt';

PART_NAME
 R872 'Q_RES_0402LF-0,5%,1/16W,EMPTY,A':;

SECTION_NUMBER 1
 '@SCM_LIB.SCM(SCH_1):PAGE52_I141@PURE_QUANTA.Q_RES(CHIPS)':
 C_PATH='@scm_lib.scm(sch_1):page52_i141@pure_quanta.q_res(chips)',
 P_PATH='@scm_lib.scm(sch_1):page52_i141@pure_quanta.q_res(chips)',
 PATH='I141',
 DRAWING='@SCM_LIB.SCM(SCH_1):PAGE52',
 PHYS_PAGE='52',
 XY='(400,-1525)',
 ROT='0',
 VER='1',
 PACK_TYPE='0402LF',
 CDS_LIB='pure_quanta',
 CDS_PART_NAME='Q_RES_0402LF-0,5%,1/16W,EMPTY,A',
 WATTAGE='1/16W',
 TOLERANCE='5%',
 MATERIAL='EMPTY',
 VALUE='0',
 PRIM_FILE='W:/<user>/logical/q_res/chips/chips.prt';

PART_NAME
 R873 'Q_RES_0402LF-0,5%,1/16W,EMPTY,A':;

SECTION_NUMBER 1
 '@SCM_LIB.SCM(SCH_1):PAGE53_I72@PURE_QUANTA.Q_RES(CHIPS)':
 C_PATH='@scm_lib.scm(sch_1):page53_i72@pure_quanta.q_res(chips)',
 P_PATH='@scm_lib.scm(sch_1):page53_i72@pure_quanta.q_res(chips)',
 PATH='I72',
 DRAWING='@SCM_LIB.SCM(SCH_1):PAGE53',
 PHYS_PAGE='53',
 XY='(-3050,75)',
 ROT='0',
 VER='1',
 PACK_TYPE='0402LF',
 CDS_LIB='pure_quanta',
 CDS_PART_NAME='Q_RES_0402LF-0,5%,1/16W,EMPTY,A',
 WATTAGE='1/16W',
 TOLERANCE='5%',
 MATERIAL='EMPTY',
 VALUE='0',
 PRIM_FILE='W:/<user>/logical/q_res/chips/chips.prt';

PART_NAME
 R874 'Q_RES_0402LF-0,5%,1/16W,EMPTY,A':;

SECTION_NUMBER 1
 '@SCM_LIB.SCM(SCH_1):PAGE54_I139@PURE_QUANTA.Q_RES(CHIPS)':
 C_PATH='@scm_lib.scm(sch_1):page54_i139@pure_quanta.q_res(chips)',
 P_PATH='@scm_lib.scm(sch_1):page54_i139@pure_quanta.q_res(chips)',
 PATH='I139',
 DRAWING='@SCM_LIB.SCM(SCH_1):PAGE54',
 PHYS_PAGE='54',
 XY='(-2025,1800)',
 ROT='0',
 VER='1',
 PACK_TYPE='0402LF',
 CDS_LIB='pure_quanta',
 CDS_PART_NAME='Q_RES_0402LF-0,5%,1/16W,EMPTY,A',
 WATTAGE='1/16W',
 TOLERANCE='5%',
 MATERIAL='EMPTY',
 VALUE='0',
 PRIM_FILE='W:/<user>/logical/q_res/chips/chips.prt';

PART_NAME
 R875 'Q_RES_0402LF-0,5%,1/16W,EMPTY,A':;

SECTION_NUMBER 1
 '@SCM_LIB.SCM(SCH_1):PAGE54_I137@PURE_QUANTA.Q_RES(CHIPS)':
 C_PATH='@scm_lib.scm(sch_1):page54_i137@pure_quanta.q_res(chips)',
 P_PATH='@scm_lib.scm(sch_1):page54_i137@pure_quanta.q_res(chips)',
 PATH='I137',
 DRAWING='@SCM_LIB.SCM(SCH_1):PAGE54',
 PHYS_PAGE='54',
 XY='(-1625,2450)',
 ROT='0',
 VER='1',
 PACK_TYPE='0402LF',
 CDS_LIB='pure_quanta',
 CDS_PART_NAME='Q_RES_0402LF-0,5%,1/16W,EMPTY,A',
 WATTAGE='1/16W',
 TOLERANCE='5%',
 MATERIAL='EMPTY',
 VALUE='0',
 PRIM_FILE='W:/<user>/logical/q_res/chips/chips.prt';

PART_NAME
 R876 'Q_RES_0402LF-0,5%,1/16W,EMPTY,A':;

SECTION_NUMBER 1
 '@SCM_LIB.SCM(SCH_1):PAGE55_I68@PURE_QUANTA.Q_RES(CHIPS)':
 C_PATH='@scm_lib.scm(sch_1):page55_i68@pure_quanta.q_res(chips)',
 P_PATH='@scm_lib.scm(sch_1):page55_i68@pure_quanta.q_res(chips)',
 PATH='I68',
 DRAWING='@SCM_LIB.SCM(SCH_1):PAGE55',
 PHYS_PAGE='55',
 XY='(-1700,475)',
 ROT='0',
 VER='1',
 PACK_TYPE='0402LF',
 CDS_LIB='pure_quanta',
 CDS_PART_NAME='Q_RES_0402LF-0,5%,1/16W,EMPTY,A',
 WATTAGE='1/16W',
 TOLERANCE='5%',
 MATERIAL='EMPTY',
 VALUE='0',
 PRIM_FILE='W:/<user>/logical/q_res/chips/chips.prt';

PART_NAME
 R877 'Q_RES_0402LF-0,5%,1/16W,EMPTY,A':;

SECTION_NUMBER 1
 '@SCM_LIB.SCM(SCH_1):PAGE55_I70@PURE_QUANTA.Q_RES(CHIPS)':
 C_PATH='@scm_lib.scm(sch_1):page55_i70@pure_quanta.q_res(chips)',
 P_PATH='@scm_lib.scm(sch_1):page55_i70@pure_quanta.q_res(chips)',
 PATH='I70',
 DRAWING='@SCM_LIB.SCM(SCH_1):PAGE55',
 PHYS_PAGE='55',
 XY='(1750,1325)',
 ROT='0',
 VER='1',
 PACK_TYPE='0402LF',
 CDS_LIB='pure_quanta',
 CDS_PART_NAME='Q_RES_0402LF-0,5%,1/16W,EMPTY,A',
 WATTAGE='1/16W',
 TOLERANCE='5%',
 MATERIAL='EMPTY',
 VALUE='0',
 PRIM_FILE='W:/<user>/logical/q_res/chips/chips.prt';

PART_NAME
 R878 'Q_RES_0402LF-0,5%,1/16W,EMPTY,A':;

SECTION_NUMBER 1
 '@SCM_LIB.SCM(SCH_1):PAGE56_I72@PURE_QUANTA.Q_RES(CHIPS)':
 C_PATH='@scm_lib.scm(sch_1):page56_i72@pure_quanta.q_res(chips)',
 P_PATH='@scm_lib.scm(sch_1):page56_i72@pure_quanta.q_res(chips)',
 PATH='I72',
 DRAWING='@SCM_LIB.SCM(SCH_1):PAGE56',
 PHYS_PAGE='56',
 XY='(-3650,550)',
 ROT='0',
 VER='1',
 PACK_TYPE='0402LF',
 CDS_LIB='pure_quanta',
 CDS_PART_NAME='Q_RES_0402LF-0,5%,1/16W,EMPTY,A',
 WATTAGE='1/16W',
 TOLERANCE='5%',
 MATERIAL='EMPTY',
 VALUE='0',
 PRIM_FILE='W:/<user>/logical/q_res/chips/chips.prt';

PART_NAME
 R879 'Q_RES_0402LF-200,1%,1/16W,CHIPA':;

SECTION_NUMBER 1
 '@SCM_LIB.SCM(SCH_1):PAGE12_I510@PURE_QUANTA.Q_RES(CHIPS)':
 C_PATH='@scm_lib.scm(sch_1):page12_i510@pure_quanta.q_res(chips)',
 P_PATH='@scm_lib.scm(sch_1):page12_i510@pure_quanta.q_res(chips)',
 PATH='I510',
 DRAWING='@SCM_LIB.SCM(SCH_1):PAGE12',
 PHYS_PAGE='12',
 XY='(-1400,75)',
 ROT='0',
 VER='1',
 PACK_TYPE='0402LF',
 LOCATION='R879',
 CDS_LIB='pure_quanta',
 CDS_PART_NAME='Q_RES_0402LF-200,1%,1/16W,CHIPA',
 WATTAGE='1/16W',
 TOLERANCE='1%',
 MATERIAL='CHIP',
 VALUE='200',
 PRIM_FILE='W:/<user>/logical/q_res/chips/chips.prt';

PART_NAME
 R880 'Q_RES_0402LF-33.2,1%,1/16W,CHIA':;

SECTION_NUMBER 1
 '@SCM_LIB.SCM(SCH_1):PAGE12_I458@PURE_QUANTA.Q_RES(CHIPS)':
 C_PATH='@scm_lib.scm(sch_1):page12_i458@pure_quanta.q_res(chips)',
 P_PATH='@scm_lib.scm(sch_1):page12_i458@pure_quanta.q_res(chips)',
 PATH='I458',
 DRAWING='@SCM_LIB.SCM(SCH_1):PAGE12',
 PHYS_PAGE='12',
 XY='(-1400,25)',
 ROT='0',
 VER='1',
 PACK_TYPE='0402LF',
 CDS_LIB='pure_quanta',
 CDS_PART_NAME='Q_RES_0402LF-33.2,1%,1/16W,CHIA',
 WATTAGE='1/16W',
 TOLERANCE='1%',
 MATERIAL='CHIP',
 VALUE='33.2',
 PRIM_FILE='W:/<user>/logical/q_res/chips/chips.prt';

PART_NAME
 R881 'Q_RES_0402LF-4.7K,1%,1/16W,EMPB':;

SECTION_NUMBER 1
 '@SCM_LIB.SCM(SCH_1):PAGE48_I42@PURE_QUANTA.Q_RES(CHIPS)':
 C_PATH='@scm_lib.scm(sch_1):page48_i42@pure_quanta.q_res(chips)',
 P_PATH='@scm_lib.scm(sch_1):page48_i42@pure_quanta.q_res(chips)',
 PATH='I42',
 DRAWING='@SCM_LIB.SCM(SCH_1):PAGE48',
 PHYS_PAGE='48',
 XY='(-2250,2300)',
 ROT='0',
 VER='2',
 PACK_TYPE='0402LF',
 CDS_LIB='pure_quanta',
 CDS_PART_NAME='Q_RES_0402LF-4.7K,1%,1/16W,EMPB',
 WATTAGE='1/16W',
 TOLERANCE='1%',
 MATERIAL='EMPTY',
 VALUE='4.7K',
 PRIM_FILE='W:/<user>/logical/q_res/chips/chips.prt';

PART_NAME
 R882 'Q_RES_0402LF-0,5%,1/16W,CHIP,CA':;

SECTION_NUMBER 1
 '@SCM_LIB.SCM(SCH_1):PAGE50_I286@PURE_QUANTA.Q_RES(CHIPS)':
 C_PATH='@scm_lib.scm(sch_1):page50_i286@pure_quanta.q_res(chips)',
 P_PATH='@scm_lib.scm(sch_1):page50_i286@pure_quanta.q_res(chips)',
 PATH='I286',
 DRAWING='@SCM_LIB.SCM(SCH_1):PAGE50',
 PHYS_PAGE='50',
 XY='(2650,1050)',
 ROT='0',
 VER='1',
 PACK_TYPE='0402LF',
 CDS_LIB='pure_quanta',
 CDS_PART_NAME='Q_RES_0402LF-0,5%,1/16W,CHIP,CA',
 WATTAGE='1/16W',
 TOLERANCE='5%',
 MATERIAL='CHIP',
 VALUE='0',
 PRIM_FILE='W:/<user>/logical/q_res/chips/chips.prt';

PART_NAME
 R883 'Q_RES_0402LF-8.2K,5%,1/16W,EMPA':;

SECTION_NUMBER 1
 '@SCM_LIB.SCM(SCH_1):PAGE50_I284@PURE_QUANTA.Q_RES(CHIPS)':
 C_PATH='@scm_lib.scm(sch_1):page50_i284@pure_quanta.q_res(chips)',
 P_PATH='@scm_lib.scm(sch_1):page50_i284@pure_quanta.q_res(chips)',
 PATH='I284',
 DRAWING='@SCM_LIB.SCM(SCH_1):PAGE50',
 PHYS_PAGE='50',
 XY='(2975,1450)',
 ROT='0',
 VER='2',
 PACK_TYPE='0402LF',
 CDS_LIB='pure_quanta',
 CDS_PART_NAME='Q_RES_0402LF-8.2K,5%,1/16W,EMPA',
 WATTAGE='1/16W',
 TOLERANCE='5%',
 MATERIAL='EMPTY',
 VALUE='8.2K',
 PRIM_FILE='W:/<user>/logical/q_res/chips/chips.prt';

PART_NAME
 R884 'Q_RES_0402LF-33.2,1%,1/16W,CHIA':;

SECTION_NUMBER 1
 '@SCM_LIB.SCM(SCH_1):PAGE14_I229@PURE_QUANTA.Q_RES(CHIPS)':
 C_PATH='@scm_lib.scm(sch_1):page14_i229@pure_quanta.q_res(chips)',
 P_PATH='@scm_lib.scm(sch_1):page14_i229@pure_quanta.q_res(chips)',
 PATH='I229',
 DRAWING='@SCM_LIB.SCM(SCH_1):PAGE14',
 PHYS_PAGE='14',
 XY='(2800,4675)',
 ROT='0',
 VER='1',
 PACK_TYPE='0402LF',
 CDS_LIB='pure_quanta',
 CDS_PART_NAME='Q_RES_0402LF-33.2,1%,1/16W,CHIA',
 WATTAGE='1/16W',
 TOLERANCE='1%',
 MATERIAL='CHIP',
 VALUE='33.2',
 PRIM_FILE='W:/<user>/logical/q_res/chips/chips.prt';

PART_NAME
 R885 'Q_RES_0402LF-4.7K,1%,1/16W,CHIA':;

SECTION_NUMBER 1
 '@SCM_LIB.SCM(SCH_1):PAGE14_I231@PURE_QUANTA.Q_RES(CHIPS)':
 C_PATH='@scm_lib.scm(sch_1):page14_i231@pure_quanta.q_res(chips)',
 P_PATH='@scm_lib.scm(sch_1):page14_i231@pure_quanta.q_res(chips)',
 PATH='I231',
 DRAWING='@SCM_LIB.SCM(SCH_1):PAGE14',
 PHYS_PAGE='14',
 XY='(3100,4875)',
 ROT='0',
 VER='2',
 PACK_TYPE='0402LF',
 CDS_LIB='pure_quanta',
 CDS_PART_NAME='Q_RES_0402LF-4.7K,1%,1/16W,CHIA',
 WATTAGE='1/16W',
 TOLERANCE='1%',
 MATERIAL='CHIP',
 VALUE='4.7K',
 PRIM_FILE='W:/<user>/logical/q_res/chips/chips.prt';

PART_NAME
 R886 'Q_RES_0402LF-4.7K,1%,1/16W,CHIA':;

SECTION_NUMBER 1
 '@SCM_LIB.SCM(SCH_1):PAGE35_I151@PURE_QUANTA.Q_RES(CHIPS)':
 C_PATH='@scm_lib.scm(sch_1):page35_i151@pure_quanta.q_res(chips)',
 P_PATH='@scm_lib.scm(sch_1):page35_i151@pure_quanta.q_res(chips)',
 PATH='I151',
 DRAWING='@SCM_LIB.SCM(SCH_1):PAGE35',
 PHYS_PAGE='35',
 XY='(-2950,1775)',
 ROT='0',
 VER='1',
 PACK_TYPE='0402LF',
 CDS_LIB='pure_quanta',
 CDS_PART_NAME='Q_RES_0402LF-4.7K,1%,1/16W,CHIA',
 WATTAGE='1/16W',
 TOLERANCE='1%',
 MATERIAL='CHIP',
 VALUE='4.7K',
 PRIM_FILE='W:/<user>/logical/q_res/chips/chips.prt';

PART_NAME
 R887 'Q_RES_0402LF-4.7K,1%,1/16W,EMPA':;

SECTION_NUMBER 1
 '@SCM_LIB.SCM(SCH_1):PAGE22_I106@PURE_QUANTA.Q_RES(CHIPS)':
 C_PATH='@scm_lib.scm(sch_1):page22_i106@pure_quanta.q_res(chips)',
 P_PATH='@scm_lib.scm(sch_1):page22_i106@pure_quanta.q_res(chips)',
 PATH='I106',
 DRAWING='@SCM_LIB.SCM(SCH_1):PAGE22',
 PHYS_PAGE='22',
 XY='(-4000,2375)',
 ROT='0',
 VER='2',
 PACK_TYPE='0402LF',
 CDS_LIB='pure_quanta',
 CDS_PART_NAME='Q_RES_0402LF-4.7K,1%,1/16W,EMPA',
 WATTAGE='1/16W',
 TOLERANCE='1%',
 MATERIAL='EMPTY',
 VALUE='4.7K',
 PRIM_FILE='W:/<user>/logical/q_res/chips/chips.prt';

PART_NAME
 R888 'Q_RES_0402LF-1K,1%,1/16W,EMPTYA':;

SECTION_NUMBER 1
 '@SCM_LIB.SCM(SCH_1):PAGE22_I102@PURE_QUANTA.Q_RES(CHIPS)':
 C_PATH='@scm_lib.scm(sch_1):page22_i102@pure_quanta.q_res(chips)',
 P_PATH='@scm_lib.scm(sch_1):page22_i102@pure_quanta.q_res(chips)',
 PATH='I102',
 DRAWING='@SCM_LIB.SCM(SCH_1):PAGE22',
 PHYS_PAGE='22',
 XY='(-3750,3275)',
 ROT='0',
 VER='2',
 PACK_TYPE='0402LF',
 CDS_LIB='pure_quanta',
 CDS_PART_NAME='Q_RES_0402LF-1K,1%,1/16W,EMPTYA',
 WATTAGE='1/16W',
 TOLERANCE='1%',
 MATERIAL='EMPTY',
 VALUE='1K',
 PRIM_FILE='W:/<user>/logical/q_res/chips/chips.prt';

PART_NAME
 R898 'Q_RES_0402LF-0,5%,1/16W,CHIP,CA':;

SECTION_NUMBER 1
 '@SCM_LIB.SCM(SCH_1):PAGE36_I42@PURE_QUANTA.Q_RES(CHIPS)':
 C_PATH='@scm_lib.scm(sch_1):page36_i42@pure_quanta.q_res(chips)',
 P_PATH='@scm_lib.scm(sch_1):page36_i42@pure_quanta.q_res(chips)',
 PATH='I42',
 DRAWING='@SCM_LIB.SCM(SCH_1):PAGE36',
 SEC_TYPE='0402LF',
 PHYS_PAGE='36',
 XY='(-2575,4825)',
 ROT='0',
 VER='1',
 PACK_TYPE='0402LF',
 LOCATION='R898',
 SEC='1',
 CDS_LIB='pure_quanta',
 CDS_PART_NAME='Q_RES_0402LF-0,5%,1/16W,CHIP,CA',
 WATTAGE='1/16W',
 TOLERANCE='5%',
 MATERIAL='CHIP',
 VALUE='0',
 PRIM_FILE='W:/<user>/logical/q_res/chips/chips.prt';

PART_NAME
 R899 'Q_RES_0402LF-0,5%,1/16W,CHIP,CA':;

SECTION_NUMBER 1
 '@SCM_LIB.SCM(SCH_1):PAGE36_I43@PURE_QUANTA.Q_RES(CHIPS)':
 C_PATH='@scm_lib.scm(sch_1):page36_i43@pure_quanta.q_res(chips)',
 P_PATH='@scm_lib.scm(sch_1):page36_i43@pure_quanta.q_res(chips)',
 PATH='I43',
 DRAWING='@SCM_LIB.SCM(SCH_1):PAGE36',
 SEC_TYPE='0402LF',
 PHYS_PAGE='36',
 XY='(-2575,4775)',
 ROT='0',
 VER='1',
 PACK_TYPE='0402LF',
 LOCATION='R899',
 SEC='1',
 CDS_LIB='pure_quanta',
 CDS_PART_NAME='Q_RES_0402LF-0,5%,1/16W,CHIP,CA',
 WATTAGE='1/16W',
 TOLERANCE='5%',
 MATERIAL='CHIP',
 VALUE='0',
 PRIM_FILE='W:/<user>/logical/q_res/chips/chips.prt';

PART_NAME
 R900 'Q_RES_0402LF-0,5%,1/16W,CHIP,CA':;

SECTION_NUMBER 1
 '@SCM_LIB.SCM(SCH_1):PAGE31_I70@PURE_QUANTA.Q_RES(CHIPS)':
 C_PATH='@scm_lib.scm(sch_1):page31_i70@pure_quanta.q_res(chips)',
 P_PATH='@scm_lib.scm(sch_1):page31_i70@pure_quanta.q_res(chips)',
 PATH='I70',
 DRAWING='@SCM_LIB.SCM(SCH_1):PAGE31',
 PHYS_PAGE='31',
 XY='(-6175,5550)',
 ROT='0',
 VER='1',
 PACK_TYPE='0402LF',
 LOCATION='R900',
 CDS_LIB='pure_quanta',
 CDS_PART_NAME='Q_RES_0402LF-0,5%,1/16W,CHIP,CA',
 WATTAGE='1/16W',
 TOLERANCE='5%',
 MATERIAL='CHIP',
 VALUE='0',
 PRIM_FILE='W:/<user>/logical/q_res/chips/chips.prt';

PART_NAME
 R901 'Q_RES_0402LF-0,5%,1/16W,CHIP,CA':;

SECTION_NUMBER 1
 '@SCM_LIB.SCM(SCH_1):PAGE31_I71@PURE_QUANTA.Q_RES(CHIPS)':
 C_PATH='@scm_lib.scm(sch_1):page31_i71@pure_quanta.q_res(chips)',
 P_PATH='@scm_lib.scm(sch_1):page31_i71@pure_quanta.q_res(chips)',
 PATH='I71',
 DRAWING='@SCM_LIB.SCM(SCH_1):PAGE31',
 PHYS_PAGE='31',
 XY='(-6300,5450)',
 ROT='0',
 VER='1',
 PACK_TYPE='0402LF',
 LOCATION='R901',
 CDS_LIB='pure_quanta',
 CDS_PART_NAME='Q_RES_0402LF-0,5%,1/16W,CHIP,CA',
 WATTAGE='1/16W',
 TOLERANCE='5%',
 MATERIAL='CHIP',
 VALUE='0',
 PRIM_FILE='W:/<user>/logical/q_res/chips/chips.prt';

PART_NAME
 R902 'Q_RES_0402LF-0,5%,1/16W,CHIP,CA':;

SECTION_NUMBER 1
 '@SCM_LIB.SCM(SCH_1):PAGE31_I72@PURE_QUANTA.Q_RES(CHIPS)':
 C_PATH='@scm_lib.scm(sch_1):page31_i72@pure_quanta.q_res(chips)',
 P_PATH='@scm_lib.scm(sch_1):page31_i72@pure_quanta.q_res(chips)',
 PATH='I72',
 DRAWING='@SCM_LIB.SCM(SCH_1):PAGE31',
 PHYS_PAGE='31',
 XY='(-6200,4400)',
 ROT='0',
 VER='1',
 PACK_TYPE='0402LF',
 LOCATION='R902',
 CDS_LIB='pure_quanta',
 CDS_PART_NAME='Q_RES_0402LF-0,5%,1/16W,CHIP,CA',
 WATTAGE='1/16W',
 TOLERANCE='5%',
 MATERIAL='CHIP',
 VALUE='0',
 PRIM_FILE='W:/<user>/logical/q_res/chips/chips.prt';

PART_NAME
 R903 'Q_RES_0402LF-0,5%,1/16W,CHIP,CA':;

SECTION_NUMBER 1
 '@SCM_LIB.SCM(SCH_1):PAGE31_I73@PURE_QUANTA.Q_RES(CHIPS)':
 C_PATH='@scm_lib.scm(sch_1):page31_i73@pure_quanta.q_res(chips)',
 P_PATH='@scm_lib.scm(sch_1):page31_i73@pure_quanta.q_res(chips)',
 PATH='I73',
 DRAWING='@SCM_LIB.SCM(SCH_1):PAGE31',
 PHYS_PAGE='31',
 XY='(-6200,4300)',
 ROT='0',
 VER='1',
 PACK_TYPE='0402LF',
 LOCATION='R903',
 CDS_LIB='pure_quanta',
 CDS_PART_NAME='Q_RES_0402LF-0,5%,1/16W,CHIP,CA',
 WATTAGE='1/16W',
 TOLERANCE='5%',
 MATERIAL='CHIP',
 VALUE='0',
 PRIM_FILE='W:/<user>/logical/q_res/chips/chips.prt';

PART_NAME
 SW6 'SW_PUSHBUTTON4P_12_G34_H2-SW4SA':;

SECTION_NUMBER 1
 '@SCM_LIB.SCM(SCH_1):PAGE50_I292@PURE_QUANTA.SW_PUSHBUTTON4P_12_G34_H2(CHIPS)':
 C_PATH='@scm_lib.scm(sch_1):page50_i292@pure_quanta.sw_pushbutton4p_12_g34_h2(c~
hips)',
 P_PATH='@scm_lib.scm(sch_1):page50_i292@pure_quanta.sw_pushbutton4p_12_g34_h2(c~
hips)',
 PATH='I292',
 DRAWING='@SCM_LIB.SCM(SCH_1):PAGE50',
 PART_TYPE='SMLF',
 PHYS_PAGE='50',
 XY='(-2700,4750)',
 ROT='0',
 VER='1',
 LOCATION='SW6',
 CDS_LIB='pure_quanta',
 CDS_PART_NAME='SW_PUSHBUTTON4P_12_G34_H2-SW4SA',
 MATERIAL='MECH',
 VALUE='SW4S_DTSAM-63N/K-S-Q-T/R',
 PRIM_FILE='W:/<user>/logical/sw_pushbutton4p_12_g34_h2/chips/chips.prt';

PART_NAME
 SW7 'SW_PUSHBUTTON4P_12_G34_H2-SW4SA':;

SECTION_NUMBER 1
 '@SCM_LIB.SCM(SCH_1):PAGE50_I204@PURE_QUANTA.SW_PUSHBUTTON4P_12_G34_H2(CHIPS)':
 C_PATH='@scm_lib.scm(sch_1):page50_i204@pure_quanta.sw_pushbutton4p_12_g34_h2(c~
hips)',
 P_PATH='@scm_lib.scm(sch_1):page50_i204@pure_quanta.sw_pushbutton4p_12_g34_h2(c~
hips)',
 PATH='I204',
 DRAWING='@SCM_LIB.SCM(SCH_1):PAGE50',
 PART_TYPE='SMLF',
 PHYS_PAGE='50',
 XY='(-2850,3350)',
 ROT='0',
 VER='1',
 LOCATION='SW7',
 CDS_LIB='pure_quanta',
 CDS_PART_NAME='SW_PUSHBUTTON4P_12_G34_H2-SW4SA',
 MATERIAL='MECH',
 VALUE='SW4S_DTSAM-63N/K-S-Q-T/R',
 PRIM_FILE='W:/<user>/logical/sw_pushbutton4p_12_g34_h2/chips/chips.prt';

PART_NAME
 SW8 'SW_PUSHBUTTON4P_12_G34_H2-SW4SA':;

SECTION_NUMBER 1
 '@SCM_LIB.SCM(SCH_1):PAGE50_I293@PURE_QUANTA.SW_PUSHBUTTON4P_12_G34_H2(CHIPS)':
 C_PATH='@scm_lib.scm(sch_1):page50_i293@pure_quanta.sw_pushbutton4p_12_g34_h2(c~
hips)',
 P_PATH='@scm_lib.scm(sch_1):page50_i293@pure_quanta.sw_pushbutton4p_12_g34_h2(c~
hips)',
 PATH='I293',
 DRAWING='@SCM_LIB.SCM(SCH_1):PAGE50',
 PART_TYPE='SMLF',
 PHYS_PAGE='50',
 XY='(1925,2550)',
 ROT='0',
 VER='1',
 LOCATION='SW8',
 CDS_LIB='pure_quanta',
 CDS_PART_NAME='SW_PUSHBUTTON4P_12_G34_H2-SW4SA',
 MATERIAL='MECH',
 VALUE='SW4S_DTSAM-63N/K-S-Q-T/R',
 PRIM_FILE='W:/<user>/logical/sw_pushbutton4p_12_g34_h2/chips/chips.prt';

PART_NAME
 U1 'K4A8G165WCBCTD-K4A8G165WC-BCTDA':;

SECTION_NUMBER 1
 '@SCM_LIB.SCM(SCH_1):PAGE20_I196@PURE_QUANTA.K4A8G165WCBCTD(CHIPS)':
 C_PATH='@scm_lib.scm(sch_1):page20_i196@pure_quanta.k4a8g165wcbctd(chips)',
 P_PATH='@scm_lib.scm(sch_1):page20_i196@pure_quanta.k4a8g165wcbctd(chips)',
 PATH='I196',
 DRAWING='@SCM_LIB.SCM(SCH_1):PAGE20',
 PART_TYPE='SMLF',
 PHYS_PAGE='20',
 XY='(-1075,3100)',
 ROT='0',
 VER='1',
 LOCATION='U1',
 CDS_LIB='pure_quanta',
 CDS_PART_NAME='K4A8G165WCBCTD-K4A8G165WC-BCTDA',
 MATERIAL='IC',
 VALUE='K4A8G165WC-BCTD',
 PRIM_FILE='W:/<user>/logical/k4a8g165wcbctd/chips/chips.prt';

PART_NAME
 U2 'FSA3357K8X-FSA3357K8X,SMLF,IC,A':;

SECTION_NUMBER 1
 '@SCM_LIB.SCM(SCH_1):PAGE30_I250@PURE_QUANTA.FSA3357K8X(CHIPS)':
 C_PATH='@scm_lib.scm(sch_1):page30_i250@pure_quanta.fsa3357k8x(chips)',
 P_PATH='@scm_lib.scm(sch_1):page30_i250@pure_quanta.fsa3357k8x(chips)',
 PATH='I250',
 DRAWING='@SCM_LIB.SCM(SCH_1):PAGE30',
 PIN_NAMES_ROTATE='True',
 PART_TYPE='SMLF',
 PHYS_PAGE='30',
 XY='(3600,4100)',
 ROT='2',
 VER='1',
 LOCATION='U2',
 CDS_LIB='pure_quanta',
 CDS_PART_NAME='FSA3357K8X-FSA3357K8X,SMLF,IC,A',
 MATERIAL='IC',
 VALUE='FSA3357K8X',
 PRIM_FILE='W:/<user>/logical/fsa3357k8x/chips/chips.prt';

PART_NAME
 U3 'FSA3357K8X-FSA3357K8X,SMLF,IC,A':;

SECTION_NUMBER 1
 '@SCM_LIB.SCM(SCH_1):PAGE30_I251@PURE_QUANTA.FSA3357K8X(CHIPS)':
 C_PATH='@scm_lib.scm(sch_1):page30_i251@pure_quanta.fsa3357k8x(chips)',
 P_PATH='@scm_lib.scm(sch_1):page30_i251@pure_quanta.fsa3357k8x(chips)',
 PATH='I251',
 DRAWING='@SCM_LIB.SCM(SCH_1):PAGE30',
 PIN_NAMES_ROTATE='True',
 PART_TYPE='SMLF',
 PHYS_PAGE='30',
 XY='(3425,3125)',
 ROT='2',
 VER='1',
 LOCATION='U3',
 CDS_LIB='pure_quanta',
 CDS_PART_NAME='FSA3357K8X-FSA3357K8X,SMLF,IC,A',
 MATERIAL='IC',
 VALUE='FSA3357K8X',
 PRIM_FILE='W:/<user>/logical/fsa3357k8x/chips/chips.prt';

PART_NAME
 U5 'AST2600A3GP-AST2600A3-GP,SMLF,A':;

SECTION_NUMBER 1
 '@SCM_LIB.SCM(SCH_1):PAGE12_I436@PURE_QUANTA.AST2600A3GP(CHIPS)':
 C_PATH='@scm_lib.scm(sch_1):page12_i436@pure_quanta.ast2600a3gp(chips)',
 P_PATH='@scm_lib.scm(sch_1):page12_i436@pure_quanta.ast2600a3gp(chips)',
 PATH='I436',
 DRAWING='@SCM_LIB.SCM(SCH_1):PAGE12',
 PART_TYPE='SMLF',
 PHYS_PAGE='12',
 XY='(1825,2250)',
 ROT='0',
 VER='1',
 LOCATION='U5',
 CDS_LIB='pure_quanta',
 CDS_PART_NAME='AST2600A3GP-AST2600A3-GP,SMLF,A',
 MATERIAL='IC',
 VALUE='AST2600A3-GP',
 PRIM_FILE='W:/<user>/logical/ast2600a3gp/chips/chips.prt';

SECTION_NUMBER 2
 '@SCM_LIB.SCM(SCH_1):PAGE13_I363@PURE_QUANTA.AST2600A3GP(CHIPS)':
 C_PATH='@scm_lib.scm(sch_1):page13_i363@pure_quanta.ast2600a3gp(chips)',
 P_PATH='@scm_lib.scm(sch_1):page13_i363@pure_quanta.ast2600a3gp(chips)',
 PATH='I363',
 DRAWING='@SCM_LIB.SCM(SCH_1):PAGE13',
 PART_TYPE='SMLF',
 PHYS_PAGE='13',
 XY='(725,2675)',
 ROT='0',
 VER='2',
 LOCATION='U5',
 CDS_LIB='pure_quanta',
 CDS_PART_NAME='AST2600A3GP-AST2600A3-GP,SMLF,A',
 MATERIAL='IC',
 VALUE='AST2600A3-GP',
 PRIM_FILE='W:/<user>/logical/ast2600a3gp/chips/chips.prt';

SECTION_NUMBER 3
 '@SCM_LIB.SCM(SCH_1):PAGE14_I149@PURE_QUANTA.AST2600A3GP(CHIPS)':
 C_PATH='@scm_lib.scm(sch_1):page14_i149@pure_quanta.ast2600a3gp(chips)',
 P_PATH='@scm_lib.scm(sch_1):page14_i149@pure_quanta.ast2600a3gp(chips)',
 PATH='I149',
 DRAWING='@SCM_LIB.SCM(SCH_1):PAGE14',
 PART_TYPE='SMLF',
 PHYS_PAGE='14',
 XY='(525,3950)',
 ROT='0',
 VER='3',
 LOCATION='U5',
 CDS_LIB='pure_quanta',
 CDS_PART_NAME='AST2600A3GP-AST2600A3-GP,SMLF,A',
 MATERIAL='IC',
 VALUE='AST2600A3-GP',
 PRIM_FILE='W:/<user>/logical/ast2600a3gp/chips/chips.prt';

SECTION_NUMBER 4
 '@SCM_LIB.SCM(SCH_1):PAGE15_I350@PURE_QUANTA.AST2600A3GP(CHIPS)':
 C_PATH='@scm_lib.scm(sch_1):page15_i350@pure_quanta.ast2600a3gp(chips)',
 P_PATH='@scm_lib.scm(sch_1):page15_i350@pure_quanta.ast2600a3gp(chips)',
 PATH='I350',
 DRAWING='@SCM_LIB.SCM(SCH_1):PAGE15',
 PART_TYPE='SMLF',
 PHYS_PAGE='15',
 XY='(1350,2900)',
 ROT='0',
 VER='4',
 LOCATION='U5',
 CDS_LIB='pure_quanta',
 CDS_PART_NAME='AST2600A3GP-AST2600A3-GP,SMLF,A',
 MATERIAL='IC',
 VALUE='AST2600A3-GP',
 PRIM_FILE='W:/<user>/logical/ast2600a3gp/chips/chips.prt';

SECTION_NUMBER 5
 '@SCM_LIB.SCM(SCH_1):PAGE16_I188@PURE_QUANTA.AST2600A3GP(CHIPS)':
 C_PATH='@scm_lib.scm(sch_1):page16_i188@pure_quanta.ast2600a3gp(chips)',
 P_PATH='@scm_lib.scm(sch_1):page16_i188@pure_quanta.ast2600a3gp(chips)',
 PATH='I188',
 DRAWING='@SCM_LIB.SCM(SCH_1):PAGE16',
 PART_TYPE='SMLF',
 PHYS_PAGE='16',
 XY='(1125,2150)',
 ROT='0',
 VER='5',
 LOCATION='U5',
 CDS_LIB='pure_quanta',
 CDS_PART_NAME='AST2600A3GP-AST2600A3-GP,SMLF,A',
 MATERIAL='IC',
 VALUE='AST2600A3-GP',
 PRIM_FILE='W:/<user>/logical/ast2600a3gp/chips/chips.prt';

SECTION_NUMBER 6
 '@SCM_LIB.SCM(SCH_1):PAGE17_I286@PURE_QUANTA.AST2600A3GP(CHIPS)':
 C_PATH='@scm_lib.scm(sch_1):page17_i286@pure_quanta.ast2600a3gp(chips)',
 P_PATH='@scm_lib.scm(sch_1):page17_i286@pure_quanta.ast2600a3gp(chips)',
 PATH='I286',
 DRAWING='@SCM_LIB.SCM(SCH_1):PAGE17',
 PART_TYPE='SMLF',
 PHYS_PAGE='17',
 XY='(-3075,1675)',
 ROT='0',
 VER='6',
 LOCATION='U5',
 CDS_LIB='pure_quanta',
 CDS_PART_NAME='AST2600A3GP-AST2600A3-GP,SMLF,A',
 MATERIAL='IC',
 VALUE='AST2600A3-GP',
 PRIM_FILE='W:/<user>/logical/ast2600a3gp/chips/chips.prt';

PART_NAME
 U6 '74LVC2G07DW7-74LVC2G07DW-7,SMLA':;

SECTION_NUMBER 1
 '@SCM_LIB.SCM(SCH_1):PAGE22_I87@PURE_QUANTA.74LVC2G07DW7(CHIPS)':
 C_PATH='@scm_lib.scm(sch_1):page22_i87@pure_quanta.\74lvc2g07dw7\(chips)',
 P_PATH='@scm_lib.scm(sch_1):page22_i87@pure_quanta.\74lvc2g07dw7\(chips)',
 PATH='I87',
 DRAWING='@SCM_LIB.SCM(SCH_1):PAGE22',
 PART_TYPE='SMLF',
 PHYS_PAGE='22',
 XY='(-1275,1050)',
 ROT='0',
 VER='1',
 LOCATION='U6',
 CDS_LIB='pure_quanta',
 CDS_PART_NAME='74LVC2G07DW7-74LVC2G07DW-7,SMLA',
 MATERIAL='IC',
 VALUE='74LVC2G07DW-7',
 PRIM_FILE='W:/<user>/logical/74lvc2g07dw7/chips/chips.prt';

PART_NAME
 U7 'NC7SB3157_SMLF-NC7SB3157P6X,NCA':;

SECTION_NUMBER 1
 '@SCM_LIB.SCM(SCH_1):PAGE31_I27@PURE_QUANTA.NC7SB3157(CHIPS)':
 C_PATH='@scm_lib.scm(sch_1):page31_i27@pure_quanta.nc7sb3157(chips)',
 P_PATH='@scm_lib.scm(sch_1):page31_i27@pure_quanta.nc7sb3157(chips)',
 PATH='I27',
 DRAWING='@SCM_LIB.SCM(SCH_1):PAGE31',
 PHYS_PAGE='31',
 XY='(-4600,2925)',
 ROT='0',
 VER='1',
 PACK_TYPE='SMLF',
 CDS_LIB='pure_quanta',
 CDS_PART_NAME='NC7SB3157_SMLF-NC7SB3157P6X,NCA',
 MATERIAL='IC',
 MANUF_PN='NC7SB3157P6X',
 VALUE='NC7SB3157P6X',
 PRIM_FILE='W:/<user>/logical/nc7sb3157/chips/chips.prt';

PART_NAME
 U8 '74LVC1G126SE7-74LVC1G126SE-7,SA':;

SECTION_NUMBER 1
 '@SCM_LIB.SCM(SCH_1):PAGE49_I11@PURE_QUANTA.74LVC1G126SE7(CHIPS)':
 C_PATH='@scm_lib.scm(sch_1):page49_i11@pure_quanta.\74lvc1g126se7\(chips)',
 P_PATH='@scm_lib.scm(sch_1):page49_i11@pure_quanta.\74lvc1g126se7\(chips)',
 PATH='I11',
 DRAWING='@SCM_LIB.SCM(SCH_1):PAGE49',
 PART_TYPE='SMLF',
 PHYS_PAGE='49',
 XY='(-7775,5150)',
 ROT='0',
 VER='1',
 CDS_LIB='pure_quanta',
 CDS_PART_NAME='74LVC1G126SE7-74LVC1G126SE-7,SA',
 MATERIAL='IC',
 VALUE='74LVC1G126SE-7',
 PRIM_FILE='W:/<user>/logical/74lvc1g126se7/chips/chips.prt';

PART_NAME
 U9 'MC74VHC1G32DTT1G-MC74VHC1G32DTA':;

SECTION_NUMBER 1
 '@SCM_LIB.SCM(SCH_1):PAGE49_I5@PURE_QUANTA.MC74VHC1G32DTT1G(CHIPS)':
 C_PATH='@scm_lib.scm(sch_1):page49_i5@pure_quanta.mc74vhc1g32dtt1g(chips)',
 P_PATH='@scm_lib.scm(sch_1):page49_i5@pure_quanta.mc74vhc1g32dtt1g(chips)',
 PATH='I5',
 DRAWING='@SCM_LIB.SCM(SCH_1):PAGE49',
 PART_TYPE='SMLF',
 PHYS_PAGE='49',
 XY='(-6325,4975)',
 ROT='0',
 VER='1',
 CDS_LIB='pure_quanta',
 CDS_PART_NAME='MC74VHC1G32DTT1G-MC74VHC1G32DTA',
 MATERIAL='IC',
 VALUE='MC74VHC1G32DTT1G',
 PRIM_FILE='W:/<user>/logical/mc74vhc1g32dtt1g/chips/chips.prt';

PART_NAME
 U10 'NCP380HSNAJAAT1G-NCP380HSNAJAAA':;

SECTION_NUMBER 1
 '@SCM_LIB.SCM(SCH_1):PAGE28_I179@PURE_QUANTA.NCP380HSNAJAAT1G(CHIPS)':
 C_PATH='@scm_lib.scm(sch_1):page28_i179@pure_quanta.ncp380hsnajaat1g(chips)',
 P_PATH='@scm_lib.scm(sch_1):page28_i179@pure_quanta.ncp380hsnajaat1g(chips)',
 PATH='I179',
 DRAWING='@SCM_LIB.SCM(SCH_1):PAGE28',
 SEC_TYPE='',
 PART_TYPE='SMLF',
 PHYS_PAGE='28',
 XY='(-50,1250)',
 ROT='0',
 VER='1',
 LOCATION='U10',
 SEC='1',
 CDS_LIB='pure_quanta',
 CDS_PART_NAME='NCP380HSNAJAAT1G-NCP380HSNAJAAA',
 MATERIAL='IC',
 VALUE='NCP380HSNAJAAT1G',
 PRIM_FILE='W:/<user>/logical/ncp380hsnajaat1g/chips/chips.prt';

PART_NAME
 U11 'BAT54C-BAT54C,SMLF,IC,BCBAT54CA':;

SECTION_NUMBER 1
 '@SCM_LIB.SCM(SCH_1):PAGE27_I185@PURE_QUANTA.BAT54C(CHIPS)':
 C_PATH='@scm_lib.scm(sch_1):page27_i185@pure_quanta.bat54c(chips)',
 P_PATH='@scm_lib.scm(sch_1):page27_i185@pure_quanta.bat54c(chips)',
 PATH='I185',
 DRAWING='@SCM_LIB.SCM(SCH_1):PAGE27',
 PART_TYPE='SMLF',
 PHYS_PAGE='27',
 XY='(2800,2150)',
 ROT='6',
 VER='1',
 LOCATION='U11',
 CDS_LIB='pure_quanta',
 CDS_PART_NAME='BAT54C-BAT54C,SMLF,IC,BCBAT54CA',
 MATERIAL='IC',
 VALUE='BAT54C',
 PRIM_FILE='W:/<user>/logical/bat54c/chips/chips.prt';

PART_NAME
 U12 'MOSFET_N_SMLF-BSS138K,BSS138K,A':;

SECTION_NUMBER 1
 '@SCM_LIB.SCM(SCH_1):PAGE22_I14@PURE_QUANTA.MOSFET_N(CHIPS)':
 C_PATH='@scm_lib.scm(sch_1):page22_i14@pure_quanta.mosfet_n(chips)',
 P_PATH='@scm_lib.scm(sch_1):page22_i14@pure_quanta.mosfet_n(chips)',
 PATH='I14',
 DRAWING='@SCM_LIB.SCM(SCH_1):PAGE22',
 PHYS_PAGE='22',
 XY='(650,2875)',
 ROT='0',
 VER='1',
 PACK_TYPE='SMLF',
 LOCATION='U12',
 CDS_LIB='pure_quanta',
 CDS_PART_NAME='MOSFET_N_SMLF-BSS138K,BSS138K,A',
 MATERIAL='IC',
 MANUF_PN='BSS138K',
 VALUE='BSS138K',
 PRIM_FILE='W:/<user>/logical/mosfet_n/chips/chips.prt';

PART_NAME
 U13 'MC74VHC1G07DFT2G-MC74VHC1G07DFA':;

SECTION_NUMBER 1
 '@SCM_LIB.SCM(SCH_1):PAGE22_I89@PURE_QUANTA.MC74VHC1G07DFT2G(CHIPS)':
 C_PATH='@scm_lib.scm(sch_1):page22_i89@pure_quanta.mc74vhc1g07dft2g(chips)',
 P_PATH='@scm_lib.scm(sch_1):page22_i89@pure_quanta.mc74vhc1g07dft2g(chips)',
 PATH='I89',
 DRAWING='@SCM_LIB.SCM(SCH_1):PAGE22',
 PART_TYPE='SMLF',
 PHYS_PAGE='22',
 XY='(3125,2125)',
 ROT='0',
 VER='1',
 LOCATION='U13',
 CDS_LIB='pure_quanta',
 CDS_PART_NAME='MC74VHC1G07DFT2G-MC74VHC1G07DFA',
 MATERIAL='EMPTY',
 VALUE='MC74VHC1G07DFT2G',
 PRIM_FILE='W:/<user>/logical/mc74vhc1g07dft2g/chips/chips.prt';

PART_NAME
 U14 'AP22811AW57-AP22811AW5-7,SMLF,A':;

SECTION_NUMBER 1
 '@SCM_LIB.SCM(SCH_1):PAGE52_I79@PURE_QUANTA.AP22811AW57(CHIPS)':
 C_PATH='@scm_lib.scm(sch_1):page52_i79@pure_quanta.ap22811aw57(chips)',
 P_PATH='@scm_lib.scm(sch_1):page52_i79@pure_quanta.ap22811aw57(chips)',
 PATH='I79',
 DRAWING='@SCM_LIB.SCM(SCH_1):PAGE52',
 L='DELAY: 1.7MS',
 PART_TYPE='SMLF',
 PHYS_PAGE='52',
 XY='(-1275,-1750)',
 ROT='2',
 VER='1',
 LOCATION='U14',
 CDS_LIB='pure_quanta',
 CDS_PART_NAME='AP22811AW57-AP22811AW5-7,SMLF,A',
 MATERIAL='IC',
 VALUE='AP22811AW5-7',
 PRIM_FILE='W:/<user>/logical/ap22811aw57/chips/chips.prt';

PART_NAME
 U15 '74LVC1G08GW_SM-74LVC1G08GW,IC,A':;

SECTION_NUMBER 1
 '@SCM_LIB.SCM(SCH_1):PAGE15_I393@PURE_QUANTA.74LVC1G08GW(CHIPS)':
 C_PATH='@scm_lib.scm(sch_1):page15_i393@pure_quanta.\74lvc1g08gw\(chips)',
 P_PATH='@scm_lib.scm(sch_1):page15_i393@pure_quanta.\74lvc1g08gw\(chips)',
 PATH='I393',
 DRAWING='@SCM_LIB.SCM(SCH_1):PAGE15',
 PHYS_PAGE='15',
 XY='(5225,1625)',
 ROT='0',
 VER='1',
 PACK_TYPE='SM',
 CDS_LIB='pure_quanta',
 CDS_PART_NAME='74LVC1G08GW_SM-74LVC1G08GW,IC,A',
 MATERIAL='IC',
 VALUE='74LVC1G08GW',
 PRIM_FILE='W:/<user>/logical/74lvc1g08gw/chips/chips.prt';

PART_NAME
 U16 '74LVC1G07GW-74LVC1G07GW,SMLF,EA':;

SECTION_NUMBER 1
 '@SCM_LIB.SCM(SCH_1):PAGE50_I227@PURE_QUANTA.74LVC1G07GW(CHIPS)':
 C_PATH='@scm_lib.scm(sch_1):page50_i227@pure_quanta.\74lvc1g07gw\(chips)',
 P_PATH='@scm_lib.scm(sch_1):page50_i227@pure_quanta.\74lvc1g07gw\(chips)',
 PATH='I227',
 DRAWING='@SCM_LIB.SCM(SCH_1):PAGE50',
 SEC_TYPE='',
 PART_TYPE='SMLF',
 PHYS_PAGE='50',
 XY='(4050,3275)',
 ROT='0',
 VER='1',
 SEC='1',
 CDS_LIB='pure_quanta',
 CDS_PART_NAME='74LVC1G07GW-74LVC1G07GW,SMLF,EA',
 MATERIAL='EMPTY',
 VALUE='74LVC1G07GW',
 PRIM_FILE='W:/<user>/logical/74lvc1g07gw/chips/chips.prt';

PART_NAME
 U17 'MX25L51245GMI10G-MX25L51245GMIA':;

SECTION_NUMBER 1
 '@SCM_LIB.SCM(SCH_1):PAGE45_I54@PURE_QUANTA.MX25L51245GMI10G(CHIPS)':
 C_PATH='@scm_lib.scm(sch_1):page45_i54@pure_quanta.mx25l51245gmi10g(chips)',
 P_PATH='@scm_lib.scm(sch_1):page45_i54@pure_quanta.mx25l51245gmi10g(chips)',
 PATH='I54',
 DRAWING='@SCM_LIB.SCM(SCH_1):PAGE45',
 PART_TYPE='SMLF',
 PHYS_PAGE='45',
 XY='(1325,750)',
 ROT='0',
 VER='1',
 CDS_LIB='pure_quanta',
 CDS_PART_NAME='MX25L51245GMI10G-MX25L51245GMIA',
 MATERIAL='EMPTY',
 VALUE='MX25L51245GMI-10G',
 PRIM_FILE='W:/<user>/logical/mx25l51245gmi10g/chips/chips.prt';

PART_NAME
 U18 '74LVC1G08GW_SM-74LVC1G08GW,IC,A':;

SECTION_NUMBER 1
 '@SCM_LIB.SCM(SCH_1):PAGE52_I114@PURE_QUANTA.74LVC1G08GW(CHIPS)':
 C_PATH='@scm_lib.scm(sch_1):page52_i114@pure_quanta.\74lvc1g08gw\(chips)',
 P_PATH='@scm_lib.scm(sch_1):page52_i114@pure_quanta.\74lvc1g08gw\(chips)',
 PATH='I114',
 DRAWING='@SCM_LIB.SCM(SCH_1):PAGE52',
 PHYS_PAGE='52',
 XY='(3600,-1400)',
 ROT='0',
 VER='1',
 PACK_TYPE='SM',
 CDS_LIB='pure_quanta',
 CDS_PART_NAME='74LVC1G08GW_SM-74LVC1G08GW,IC,A',
 MATERIAL='IC',
 VALUE='74LVC1G08GW',
 PRIM_FILE='W:/<user>/logical/74lvc1g08gw/chips/chips.prt';

PART_NAME
 U19 'M24128BWDW6TP-M24128-BWDW6TP,SA':;

SECTION_NUMBER 1
 '@SCM_LIB.SCM(SCH_1):PAGE26_I15@PURE_QUANTA.M24128BWDW6TP(CHIPS)':
 C_PATH='@scm_lib.scm(sch_1):page26_i15@pure_quanta.m24128bwdw6tp(chips)',
 P_PATH='@scm_lib.scm(sch_1):page26_i15@pure_quanta.m24128bwdw6tp(chips)',
 PATH='I15',
 DRAWING='@SCM_LIB.SCM(SCH_1):PAGE26',
 PART_TYPE='SMLF',
 PHYS_PAGE='26',
 XY='(225,775)',
 ROT='0',
 VER='1',
 LOCATION='U19',
 CDS_LIB='pure_quanta',
 CDS_PART_NAME='M24128BWDW6TP-M24128-BWDW6TP,SA',
 MATERIAL='IC',
 VALUE='M24128-BWDW6TP',
 PRIM_FILE='W:/<user>/logical/m24128bwdw6tp/chips/chips.prt';

PART_NAME
 U20 'NC7SB3157_SMLF-NC7SB3157P6X,NCA':;

SECTION_NUMBER 1
 '@SCM_LIB.SCM(SCH_1):PAGE31_I38@PURE_QUANTA.NC7SB3157(CHIPS)':
 C_PATH='@scm_lib.scm(sch_1):page31_i38@pure_quanta.nc7sb3157(chips)',
 P_PATH='@scm_lib.scm(sch_1):page31_i38@pure_quanta.nc7sb3157(chips)',
 PATH='I38',
 DRAWING='@SCM_LIB.SCM(SCH_1):PAGE31',
 PHYS_PAGE='31',
 XY='(-4500,1325)',
 ROT='0',
 VER='1',
 PACK_TYPE='SMLF',
 CDS_LIB='pure_quanta',
 CDS_PART_NAME='NC7SB3157_SMLF-NC7SB3157P6X,NCA',
 MATERIAL='IC',
 MANUF_PN='NC7SB3157P6X',
 VALUE='NC7SB3157P6X',
 PRIM_FILE='W:/<user>/logical/nc7sb3157/chips/chips.prt';

PART_NAME
 U21 'IDTQS3VH257PAG_SMLF-IDTQS3VH25A':;

SECTION_NUMBER 1
 '@SCM_LIB.SCM(SCH_1):PAGE44_I296@PURE_QUANTA.IDTQS3VH257PAG(CHIPS)':
 C_PATH='@scm_lib.scm(sch_1):page44_i296@pure_quanta.idtqs3vh257pag(chips)',
 P_PATH='@scm_lib.scm(sch_1):page44_i296@pure_quanta.idtqs3vh257pag(chips)',
 PATH='I296',
 DRAWING='@SCM_LIB.SCM(SCH_1):PAGE44',
 SEC_TYPE='SMLF',
 PHYS_PAGE='44',
 XY='(2350,-650)',
 ROT='2',
 VER='1',
 PACK_TYPE='SMLF',
 LOCATION='U21',
 SEC='1',
 CDS_LIB='pure_quanta',
 CDS_PART_NAME='IDTQS3VH257PAG_SMLF-IDTQS3VH25A',
 MATERIAL='IC',
 MANUF_PN='IDTQS3VH257PAG',
 VALUE='IDTQS3VH257PAG',
 PRIM_FILE='W:/<user>/logical/idtqs3vh257pag/chips/chips.prt';

PART_NAME
 U22 'PI3PCIE3212ZBEX-PI3PCIE3212ZBEA':;

SECTION_NUMBER 1
 '@SCM_LIB.SCM(SCH_1):PAGE29_I206@PURE_QUANTA.PI3PCIE3212ZBEX(CHIPS)':
 C_PATH='@scm_lib.scm(sch_1):page29_i206@pure_quanta.pi3pcie3212zbex(chips)',
 P_PATH='@scm_lib.scm(sch_1):page29_i206@pure_quanta.pi3pcie3212zbex(chips)',
 PATH='I206',
 DRAWING='@SCM_LIB.SCM(SCH_1):PAGE29',
 PIN_NAMES_ROTATE='True',
 PART_TYPE='SMLF',
 PHYS_PAGE='29',
 XY='(-1675,-825)',
 ROT='0',
 VER='1',
 CDS_LIB='pure_quanta',
 CDS_PART_NAME='PI3PCIE3212ZBEX-PI3PCIE3212ZBEA',
 MATERIAL='IC',
 VALUE='PI3PCIE3212ZBEX',
 PRIM_FILE='W:/<user>/logical/pi3pcie3212zbex/chips/chips.prt';

PART_NAME
 U23 '74LVC1G07W57-74LVC1G07W5-7,SMLA':;

SECTION_NUMBER 1
 '@SCM_LIB.SCM(SCH_1):PAGE28_I180@PURE_QUANTA.74LVC1G07W57(CHIPS)':
 C_PATH='@scm_lib.scm(sch_1):page28_i180@pure_quanta.\74lvc1g07w57\(chips)',
 P_PATH='@scm_lib.scm(sch_1):page28_i180@pure_quanta.\74lvc1g07w57\(chips)',
 PATH='I180',
 DRAWING='@SCM_LIB.SCM(SCH_1):PAGE28',
 PART_TYPE='SMLF',
 PHYS_PAGE='28',
 XY='(-2450,3475)',
 ROT='0',
 VER='1',
 LOCATION='U23',
 CDS_LIB='pure_quanta',
 CDS_PART_NAME='74LVC1G07W57-74LVC1G07W5-7,SMLA',
 MATERIAL='IC',
 VALUE='74LVC1G07W5-7',
 PRIM_FILE='W:/<user>/logical/74lvc1g07w57/chips/chips.prt';

PART_NAME
 U24 '74LVC2G07DW7-74LVC2G07DW-7,SMLA':;

SECTION_NUMBER 1
 '@SCM_LIB.SCM(SCH_1):PAGE30_I246@PURE_QUANTA.74LVC2G07DW7(CHIPS)':
 C_PATH='@scm_lib.scm(sch_1):page30_i246@pure_quanta.\74lvc2g07dw7\(chips)',
 P_PATH='@scm_lib.scm(sch_1):page30_i246@pure_quanta.\74lvc2g07dw7\(chips)',
 PATH='I246',
 DRAWING='@SCM_LIB.SCM(SCH_1):PAGE30',
 PART_TYPE='SMLF',
 PHYS_PAGE='30',
 XY='(1425,900)',
 ROT='0',
 VER='1',
 LOCATION='U24',
 CDS_LIB='pure_quanta',
 CDS_PART_NAME='74LVC2G07DW7-74LVC2G07DW-7,SMLA',
 MATERIAL='IC',
 VALUE='74LVC2G07DW-7',
 PRIM_FILE='W:/<user>/logical/74lvc2g07dw7/chips/chips.prt';

PART_NAME
 U25 'LCMXO3LF2100C5BG256C-LCMXO3LF-A':;

SECTION_NUMBER 1
 '@SCM_LIB.SCM(SCH_1):PAGE34_I1@PURE_QUANTA.LCMXO3LF2100C5BG256C(CHIPS)':
 C_PATH='@scm_lib.scm(sch_1):page34_i1@pure_quanta.lcmxo3lf2100c5bg256c(chips)',
 P_PATH='@scm_lib.scm(sch_1):page34_i1@pure_quanta.lcmxo3lf2100c5bg256c(chips)',
 PATH='I1',
 DRAWING='@SCM_LIB.SCM(SCH_1):PAGE34',
 PART_TYPE='SMLF',
 PHYS_PAGE='34',
 XY='(-4900,4100)',
 ROT='0',
 VER='1',
 LOCATION='U25',
 CDS_LIB='pure_quanta',
 CDS_PART_NAME='LCMXO3LF2100C5BG256C-LCMXO3LF-A',
 MATERIAL='IC',
 VALUE='LCMXO3LF-2100C-5BG256C',
 PRIM_FILE='W:/<user>/logical/lcmxo3lf2100c5bg256c/chips/chips.prt';

SECTION_NUMBER 2
 '@SCM_LIB.SCM(SCH_1):PAGE35_I1@PURE_QUANTA.LCMXO3LF2100C5BG256C(CHIPS)':
 C_PATH='@scm_lib.scm(sch_1):page35_i1@pure_quanta.lcmxo3lf2100c5bg256c(chips)',
 P_PATH='@scm_lib.scm(sch_1):page35_i1@pure_quanta.lcmxo3lf2100c5bg256c(chips)',
 PATH='I1',
 DRAWING='@SCM_LIB.SCM(SCH_1):PAGE35',
 PART_TYPE='SMLF',
 PHYS_PAGE='35',
 XY='(-4750,3875)',
 ROT='0',
 VER='2',
 LOCATION='U25',
 CDS_LIB='pure_quanta',
 CDS_PART_NAME='LCMXO3LF2100C5BG256C-LCMXO3LF-A',
 MATERIAL='IC',
 VALUE='LCMXO3LF-2100C-5BG256C',
 PRIM_FILE='W:/<user>/logical/lcmxo3lf2100c5bg256c/chips/chips.prt';

SECTION_NUMBER 3
 '@SCM_LIB.SCM(SCH_1):PAGE36_I1@PURE_QUANTA.LCMXO3LF2100C5BG256C(CHIPS)':
 C_PATH='@scm_lib.scm(sch_1):page36_i1@pure_quanta.lcmxo3lf2100c5bg256c(chips)',
 P_PATH='@scm_lib.scm(sch_1):page36_i1@pure_quanta.lcmxo3lf2100c5bg256c(chips)',
 PATH='I1',
 DRAWING='@SCM_LIB.SCM(SCH_1):PAGE36',
 PART_TYPE='SMLF',
 PHYS_PAGE='36',
 XY='(-4800,4150)',
 ROT='0',
 VER='3',
 LOCATION='U25',
 CDS_LIB='pure_quanta',
 CDS_PART_NAME='LCMXO3LF2100C5BG256C-LCMXO3LF-A',
 MATERIAL='IC',
 VALUE='LCMXO3LF-2100C-5BG256C',
 PRIM_FILE='W:/<user>/logical/lcmxo3lf2100c5bg256c/chips/chips.prt';

SECTION_NUMBER 4
 '@SCM_LIB.SCM(SCH_1):PAGE37_I1@PURE_QUANTA.LCMXO3LF2100C5BG256C(CHIPS)':
 C_PATH='@scm_lib.scm(sch_1):page37_i1@pure_quanta.lcmxo3lf2100c5bg256c(chips)',
 P_PATH='@scm_lib.scm(sch_1):page37_i1@pure_quanta.lcmxo3lf2100c5bg256c(chips)',
 PATH='I1',
 DRAWING='@SCM_LIB.SCM(SCH_1):PAGE37',
 PART_TYPE='SMLF',
 PHYS_PAGE='37',
 XY='(-4825,4625)',
 ROT='0',
 VER='4',
 LOCATION='U25',
 CDS_LIB='pure_quanta',
 CDS_PART_NAME='LCMXO3LF2100C5BG256C-LCMXO3LF-A',
 MATERIAL='IC',
 VALUE='LCMXO3LF-2100C-5BG256C',
 PRIM_FILE='W:/<user>/logical/lcmxo3lf2100c5bg256c/chips/chips.prt';

SECTION_NUMBER 5
 '@SCM_LIB.SCM(SCH_1):PAGE38_I1@PURE_QUANTA.LCMXO3LF2100C5BG256C(CHIPS)':
 C_PATH='@scm_lib.scm(sch_1):page38_i1@pure_quanta.lcmxo3lf2100c5bg256c(chips)',
 P_PATH='@scm_lib.scm(sch_1):page38_i1@pure_quanta.lcmxo3lf2100c5bg256c(chips)',
 PATH='I1',
 DRAWING='@SCM_LIB.SCM(SCH_1):PAGE38',
 PART_TYPE='SMLF',
 PHYS_PAGE='38',
 XY='(-4775,4475)',
 ROT='0',
 VER='5',
 LOCATION='U25',
 CDS_LIB='pure_quanta',
 CDS_PART_NAME='LCMXO3LF2100C5BG256C-LCMXO3LF-A',
 MATERIAL='IC',
 VALUE='LCMXO3LF-2100C-5BG256C',
 PRIM_FILE='W:/<user>/logical/lcmxo3lf2100c5bg256c/chips/chips.prt';

SECTION_NUMBER 6
 '@SCM_LIB.SCM(SCH_1):PAGE39_I1@PURE_QUANTA.LCMXO3LF2100C5BG256C(CHIPS)':
 C_PATH='@scm_lib.scm(sch_1):page39_i1@pure_quanta.lcmxo3lf2100c5bg256c(chips)',
 P_PATH='@scm_lib.scm(sch_1):page39_i1@pure_quanta.lcmxo3lf2100c5bg256c(chips)',
 PATH='I1',
 DRAWING='@SCM_LIB.SCM(SCH_1):PAGE39',
 PART_TYPE='SMLF',
 PHYS_PAGE='39',
 XY='(-4800,4375)',
 ROT='0',
 VER='6',
 LOCATION='U25',
 CDS_LIB='pure_quanta',
 CDS_PART_NAME='LCMXO3LF2100C5BG256C-LCMXO3LF-A',
 MATERIAL='IC',
 VALUE='LCMXO3LF-2100C-5BG256C',
 PRIM_FILE='W:/<user>/logical/lcmxo3lf2100c5bg256c/chips/chips.prt';

SECTION_NUMBER 7
 '@SCM_LIB.SCM(SCH_1):PAGE40_I1@PURE_QUANTA.LCMXO3LF2100C5BG256C(CHIPS)':
 C_PATH='@scm_lib.scm(sch_1):page40_i1@pure_quanta.lcmxo3lf2100c5bg256c(chips)',
 P_PATH='@scm_lib.scm(sch_1):page40_i1@pure_quanta.lcmxo3lf2100c5bg256c(chips)',
 PATH='I1',
 DRAWING='@SCM_LIB.SCM(SCH_1):PAGE40',
 PART_TYPE='SMLF',
 PHYS_PAGE='40',
 XY='(-4750,4425)',
 ROT='0',
 VER='7',
 LOCATION='U25',
 CDS_LIB='pure_quanta',
 CDS_PART_NAME='LCMXO3LF2100C5BG256C-LCMXO3LF-A',
 MATERIAL='IC',
 VALUE='LCMXO3LF-2100C-5BG256C',
 PRIM_FILE='W:/<user>/logical/lcmxo3lf2100c5bg256c/chips/chips.prt';

PART_NAME
 U26 '74HC1G126GW-74HC1G126GW,SMLF,IA':;

SECTION_NUMBER 1
 '@SCM_LIB.SCM(SCH_1):PAGE23_I33@PURE_QUANTA.74HC1G126GW(CHIPS)':
 C_PATH='@scm_lib.scm(sch_1):page23_i33@pure_quanta.\74hc1g126gw\(chips)',
 P_PATH='@scm_lib.scm(sch_1):page23_i33@pure_quanta.\74hc1g126gw\(chips)',
 PATH='I33',
 DRAWING='@SCM_LIB.SCM(SCH_1):PAGE23',
 PART_TYPE='SMLF',
 PHYS_PAGE='23',
 XY='(-1025,2725)',
 ROT='0',
 VER='1',
 LOCATION='U26',
 CDS_LIB='pure_quanta',
 CDS_PART_NAME='74HC1G126GW-74HC1G126GW,SMLF,IA',
 MATERIAL='IC',
 VALUE='74HC1G126GW',
 PRIM_FILE='W:/<user>/logical/74hc1g126gw/chips/chips.prt';

PART_NAME
 U27 'DT1240E04LP7-DT1240E-04LP-7,SMA':;

SECTION_NUMBER 1
 '@SCM_LIB.SCM(SCH_1):PAGE29_I211@PURE_QUANTA.DT1240E04LP7(CHIPS)':
 C_PATH='@scm_lib.scm(sch_1):page29_i211@pure_quanta.dt1240e04lp7(chips)',
 P_PATH='@scm_lib.scm(sch_1):page29_i211@pure_quanta.dt1240e04lp7(chips)',
 PATH='I211',
 DRAWING='@SCM_LIB.SCM(SCH_1):PAGE29',
 SEC_TYPE='',
 PART_TYPE='SMLF',
 PHYS_PAGE='29',
 XY='(-2400,3050)',
 ROT='0',
 VER='1',
 LOCATION='U27',
 SEC='1',
 CDS_LIB='pure_quanta',
 CDS_PART_NAME='DT1240E04LP7-DT1240E-04LP-7,SMA',
 MATERIAL='IC',
 VALUE='DT1240E-04LP-7',
 PRIM_FILE='W:/<user>/logical/dt1240e04lp7/chips/chips.prt';

PART_NAME
 U28 '74LVC1G66GV-74LVC1G66GV,SMLF,IA':;

SECTION_NUMBER 1
 '@SCM_LIB.SCM(SCH_1):PAGE13_I435@PURE_QUANTA.74LVC1G66GV(CHIPS)':
 C_PATH='@scm_lib.scm(sch_1):page13_i435@pure_quanta.\74lvc1g66gv\(chips)',
 P_PATH='@scm_lib.scm(sch_1):page13_i435@pure_quanta.\74lvc1g66gv\(chips)',
 PATH='I435',
 DRAWING='@SCM_LIB.SCM(SCH_1):PAGE13',
 PIN_NAMES_ROTATE='True',
 PART_TYPE='SMLF',
 PHYS_PAGE='13',
 XY='(-1925,4775)',
 ROT='0',
 VER='1',
 CDS_LIB='pure_quanta',
 CDS_PART_NAME='74LVC1G66GV-74LVC1G66GV,SMLF,IA',
 MATERIAL='IC',
 VALUE='74LVC1G66GV',
 PRIM_FILE='W:/<user>/logical/74lvc1g66gv/chips/chips.prt';

PART_NAME
 U29 '74HC1G126GW-74HC1G126GW,SMLF,IA':;

SECTION_NUMBER 1
 '@SCM_LIB.SCM(SCH_1):PAGE29_I174@PURE_QUANTA.74HC1G126GW(CHIPS)':
 C_PATH='@scm_lib.scm(sch_1):page29_i174@pure_quanta.\74hc1g126gw\(chips)',
 P_PATH='@scm_lib.scm(sch_1):page29_i174@pure_quanta.\74hc1g126gw\(chips)',
 PATH='I174',
 DRAWING='@SCM_LIB.SCM(SCH_1):PAGE29',
 SEC_TYPE='',
 PART_TYPE='SMLF',
 PHYS_PAGE='29',
 XY='(2625,2275)',
 ROT='0',
 VER='1',
 LOCATION='U29',
 SEC='1',
 CDS_LIB='pure_quanta',
 CDS_PART_NAME='74HC1G126GW-74HC1G126GW,SMLF,IA',
 MATERIAL='IC',
 VALUE='74HC1G126GW',
 PRIM_FILE='W:/<user>/logical/74hc1g126gw/chips/chips.prt';

PART_NAME
 U30 'IDTQS3VH257PAG_SMLF-IDTQS3VH25A':;

SECTION_NUMBER 1
 '@SCM_LIB.SCM(SCH_1):PAGE44_I271@PURE_QUANTA.IDTQS3VH257PAG(CHIPS)':
 C_PATH='@scm_lib.scm(sch_1):page44_i271@pure_quanta.idtqs3vh257pag(chips)',
 P_PATH='@scm_lib.scm(sch_1):page44_i271@pure_quanta.idtqs3vh257pag(chips)',
 PATH='I271',
 DRAWING='@SCM_LIB.SCM(SCH_1):PAGE44',
 SEC_TYPE='SMLF',
 PHYS_PAGE='44',
 XY='(2325,1050)',
 ROT='2',
 VER='1',
 PACK_TYPE='SMLF',
 LOCATION='U30',
 SEC='1',
 CDS_LIB='pure_quanta',
 CDS_PART_NAME='IDTQS3VH257PAG_SMLF-IDTQS3VH25A',
 MATERIAL='IC',
 MANUF_PN='IDTQS3VH257PAG',
 VALUE='IDTQS3VH257PAG',
 PRIM_FILE='W:/<user>/logical/idtqs3vh257pag/chips/chips.prt';

PART_NAME
 U31 '74LVC1G07GW-74LVC1G07GW,SMLF,IA':;

SECTION_NUMBER 1
 '@SCM_LIB.SCM(SCH_1):PAGE50_I151@PURE_QUANTA.74LVC1G07GW(CHIPS)':
 C_PATH='@scm_lib.scm(sch_1):page50_i151@pure_quanta.\74lvc1g07gw\(chips)',
 P_PATH='@scm_lib.scm(sch_1):page50_i151@pure_quanta.\74lvc1g07gw\(chips)',
 PATH='I151',
 DRAWING='@SCM_LIB.SCM(SCH_1):PAGE50',
 SEC_TYPE='',
 PART_TYPE='SMLF',
 PHYS_PAGE='50',
 XY='(-125,4650)',
 ROT='0',
 VER='1',
 LOCATION='U31',
 SEC='1',
 CDS_LIB='pure_quanta',
 CDS_PART_NAME='74LVC1G07GW-74LVC1G07GW,SMLF,IA',
 MATERIAL='IC',
 VALUE='74LVC1G07GW',
 PRIM_FILE='W:/<user>/logical/74lvc1g07gw/chips/chips.prt';

PART_NAME
 U32 '74LVC1G17GW-74LVC1G17GW,SMLF,IA':;

SECTION_NUMBER 1
 '@SCM_LIB.SCM(SCH_1):PAGE50_I49@PURE_QUANTA.74LVC1G17GW(CHIPS)':
 C_PATH='@scm_lib.scm(sch_1):page50_i49@pure_quanta.\74lvc1g17gw\(chips)',
 P_PATH='@scm_lib.scm(sch_1):page50_i49@pure_quanta.\74lvc1g17gw\(chips)',
 PATH='I49',
 DRAWING='@SCM_LIB.SCM(SCH_1):PAGE50',
 PIN_NAMES_ROTATE='True',
 PART_TYPE='SMLF',
 PHYS_PAGE='50',
 XY='(-125,3250)',
 ROT='0',
 VER='1',
 LOCATION='U32',
 CDS_LIB='pure_quanta',
 CDS_PART_NAME='74LVC1G17GW-74LVC1G17GW,SMLF,IA',
 MATERIAL='IC',
 VALUE='74LVC1G17GW',
 PRIM_FILE='W:/<user>/logical/74lvc1g17gw/chips/chips.prt';

PART_NAME
 U33 '74HC1G126GW-74HC1G126GW,SMLF,IA':;

SECTION_NUMBER 1
 '@SCM_LIB.SCM(SCH_1):PAGE23_I32@PURE_QUANTA.74HC1G126GW(CHIPS)':
 C_PATH='@scm_lib.scm(sch_1):page23_i32@pure_quanta.\74hc1g126gw\(chips)',
 P_PATH='@scm_lib.scm(sch_1):page23_i32@pure_quanta.\74hc1g126gw\(chips)',
 PATH='I32',
 DRAWING='@SCM_LIB.SCM(SCH_1):PAGE23',
 PART_TYPE='SMLF',
 PHYS_PAGE='23',
 XY='(-625,2325)',
 ROT='0',
 VER='1',
 LOCATION='U33',
 CDS_LIB='pure_quanta',
 CDS_PART_NAME='74HC1G126GW-74HC1G126GW,SMLF,IA',
 MATERIAL='IC',
 VALUE='74HC1G126GW',
 PRIM_FILE='W:/<user>/logical/74hc1g126gw/chips/chips.prt';

PART_NAME
 U34 'DT1240E04LP7-DT1240E-04LP-7,SMA':;

SECTION_NUMBER 1
 '@SCM_LIB.SCM(SCH_1):PAGE23_I156@PURE_QUANTA.DT1240E04LP7(CHIPS)':
 C_PATH='@scm_lib.scm(sch_1):page23_i156@pure_quanta.dt1240e04lp7(chips)',
 P_PATH='@scm_lib.scm(sch_1):page23_i156@pure_quanta.dt1240e04lp7(chips)',
 PATH='I156',
 DRAWING='@SCM_LIB.SCM(SCH_1):PAGE23',
 PART_TYPE='SMLF',
 PHYS_PAGE='23',
 XY='(1550,4000)',
 ROT='0',
 VER='1',
 LOCATION='U34',
 CDS_LIB='pure_quanta',
 CDS_PART_NAME='DT1240E04LP7-DT1240E-04LP-7,SMA',
 MATERIAL='IC',
 VALUE='DT1240E-04LP-7',
 PRIM_FILE='W:/<user>/logical/dt1240e04lp7/chips/chips.prt';

PART_NAME
 U35 'DT1240E04LP7-DT1240E-04LP-7,SMA':;

SECTION_NUMBER 1
 '@SCM_LIB.SCM(SCH_1):PAGE23_I155@PURE_QUANTA.DT1240E04LP7(CHIPS)':
 C_PATH='@scm_lib.scm(sch_1):page23_i155@pure_quanta.dt1240e04lp7(chips)',
 P_PATH='@scm_lib.scm(sch_1):page23_i155@pure_quanta.dt1240e04lp7(chips)',
 PATH='I155',
 DRAWING='@SCM_LIB.SCM(SCH_1):PAGE23',
 PART_TYPE='SMLF',
 PHYS_PAGE='23',
 XY='(3300,4000)',
 ROT='0',
 VER='1',
 LOCATION='U35',
 CDS_LIB='pure_quanta',
 CDS_PART_NAME='DT1240E04LP7-DT1240E-04LP-7,SMA',
 MATERIAL='IC',
 VALUE='DT1240E-04LP-7',
 PRIM_FILE='W:/<user>/logical/dt1240e04lp7/chips/chips.prt';

PART_NAME
 U36 '74HC1G126GW-74HC1G126GW,SMLF,IA':;

SECTION_NUMBER 1
 '@SCM_LIB.SCM(SCH_1):PAGE29_I164@PURE_QUANTA.74HC1G126GW(CHIPS)':
 C_PATH='@scm_lib.scm(sch_1):page29_i164@pure_quanta.\74hc1g126gw\(chips)',
 P_PATH='@scm_lib.scm(sch_1):page29_i164@pure_quanta.\74hc1g126gw\(chips)',
 PATH='I164',
 DRAWING='@SCM_LIB.SCM(SCH_1):PAGE29',
 SEC_TYPE='',
 PART_TYPE='SMLF',
 PHYS_PAGE='29',
 XY='(2850,3475)',
 ROT='2',
 VER='1',
 LOCATION='U36',
 SEC='1',
 CDS_LIB='pure_quanta',
 CDS_PART_NAME='74HC1G126GW-74HC1G126GW,SMLF,IA',
 MATERIAL='IC',
 VALUE='74HC1G126GW',
 PRIM_FILE='W:/<user>/logical/74hc1g126gw/chips/chips.prt';

PART_NAME
 U37 'PCA9517ADP_SMLF-PCA9517ADP,IC,A':;

SECTION_NUMBER 1
 '@SCM_LIB.SCM(SCH_1):PAGE28_I99@PURE_QUANTA.PCA9517ADP(CHIPS)':
 C_PATH='@scm_lib.scm(sch_1):page28_i99@pure_quanta.pca9517adp(chips)',
 P_PATH='@scm_lib.scm(sch_1):page28_i99@pure_quanta.pca9517adp(chips)',
 PATH='I99',
 DRAWING='@SCM_LIB.SCM(SCH_1):PAGE28',
 PHYS_PAGE='28',
 XY='(825,2175)',
 ROT='0',
 VER='1',
 PACK_TYPE='SMLF',
 LOCATION='U37',
 CDS_LIB='pure_quanta',
 CDS_PART_NAME='PCA9517ADP_SMLF-PCA9517ADP,IC,A',
 MATERIAL='IC',
 VALUE='PCA9517ADP',
 PRIM_FILE='W:/<user>/logical/pca9517adp/chips/chips.prt';

PART_NAME
 U38 'PRTR5V0U2X-PRTR5V0U2X,SMLF,IC,A':;

SECTION_NUMBER 1
 '@SCM_LIB.SCM(SCH_1):PAGE29_I99@PURE_QUANTA.PRTR5V0U2X(CHIPS)':
 C_PATH='@scm_lib.scm(sch_1):page29_i99@pure_quanta.prtr5v0u2x(chips)',
 P_PATH='@scm_lib.scm(sch_1):page29_i99@pure_quanta.prtr5v0u2x(chips)',
 PATH='I99',
 DRAWING='@SCM_LIB.SCM(SCH_1):PAGE29',
 PART_TYPE='SMLF',
 PHYS_PAGE='29',
 XY='(-725,1075)',
 ROT='0',
 VER='1',
 LOCATION='U38',
 CDS_LIB='pure_quanta',
 CDS_PART_NAME='PRTR5V0U2X-PRTR5V0U2X,SMLF,IC,A',
 MATERIAL='IC',
 VALUE='PRTR5V0U2X',
 PRIM_FILE='W:/<user>/logical/prtr5v0u2x/chips/chips.prt';

PART_NAME
 U39 'RT9059GQW-RT9059GQW,SMLF,IC,ALA':;

SECTION_NUMBER 1
 '@SCM_LIB.SCM(SCH_1):PAGE53_I60@PURE_QUANTA.RT9059GQW(CHIPS)':
 C_PATH='@scm_lib.scm(sch_1):page53_i60@pure_quanta.rt9059gqw(chips)',
 P_PATH='@scm_lib.scm(sch_1):page53_i60@pure_quanta.rt9059gqw(chips)',
 PATH='I60',
 DRAWING='@SCM_LIB.SCM(SCH_1):PAGE53',
 PIN_NAMES_ROTATE='True',
 PART_TYPE='SMLF',
 PHYS_PAGE='53',
 XY='(-650,375)',
 ROT='0',
 VER='1',
 LOCATION='U39',
 CDS_LIB='pure_quanta',
 CDS_PART_NAME='RT9059GQW-RT9059GQW,SMLF,IC,ALA',
 MATERIAL='IC',
 VALUE='RT9059GQW',
 PRIM_FILE='W:/<user>/logical/rt9059gqw/chips/chips.prt';

PART_NAME
 U40 'PCA9555PW_SMLF-PCA9555PW,IC,TMA':;

SECTION_NUMBER 1
 '@SCM_LIB.SCM(SCH_1):PAGE28_I141@PURE_QUANTA.PCA9555PW(CHIPS)':
 C_PATH='@scm_lib.scm(sch_1):page28_i141@pure_quanta.pca9555pw(chips)',
 P_PATH='@scm_lib.scm(sch_1):page28_i141@pure_quanta.pca9555pw(chips)',
 PATH='I141',
 DRAWING='@SCM_LIB.SCM(SCH_1):PAGE28',
 SEC_TYPE='SMLF',
 PHYS_PAGE='28',
 XY='(-425,-975)',
 ROT='0',
 VER='1',
 PACK_TYPE='SMLF',
 LOCATION='U40',
 SEC='1',
 CDS_LIB='pure_quanta',
 CDS_PART_NAME='PCA9555PW_SMLF-PCA9555PW,IC,TMA',
 MATERIAL='IC',
 VALUE='PCA9555PW',
 PRIM_FILE='W:/<user>/logical/pca9555pw/chips/chips.prt';

PART_NAME
 U41 'RT9059GQW-RT9059GQW,SMLF,IC,ALA':;

SECTION_NUMBER 1
 '@SCM_LIB.SCM(SCH_1):PAGE54_I96@PURE_QUANTA.RT9059GQW(CHIPS)':
 C_PATH='@scm_lib.scm(sch_1):page54_i96@pure_quanta.rt9059gqw(chips)',
 P_PATH='@scm_lib.scm(sch_1):page54_i96@pure_quanta.rt9059gqw(chips)',
 PATH='I96',
 DRAWING='@SCM_LIB.SCM(SCH_1):PAGE54',
 PIN_NAMES_ROTATE='True',
 PART_TYPE='SMLF',
 PHYS_PAGE='54',
 XY='(0,2125)',
 ROT='0',
 VER='1',
 LOCATION='U41',
 CDS_LIB='pure_quanta',
 CDS_PART_NAME='RT9059GQW-RT9059GQW,SMLF,IC,ALA',
 MATERIAL='IC',
 VALUE='RT9059GQW',
 PRIM_FILE='W:/<user>/logical/rt9059gqw/chips/chips.prt';

PART_NAME
 U42 'MC74VHC1G32DTT1G-MC74VHC1G32DTA':;

SECTION_NUMBER 1
 '@SCM_LIB.SCM(SCH_1):PAGE52_I104@PURE_QUANTA.MC74VHC1G32DTT1G(CHIPS)':
 C_PATH='@scm_lib.scm(sch_1):page52_i104@pure_quanta.mc74vhc1g32dtt1g(chips)',
 P_PATH='@scm_lib.scm(sch_1):page52_i104@pure_quanta.mc74vhc1g32dtt1g(chips)',
 PATH='I104',
 DRAWING='@SCM_LIB.SCM(SCH_1):PAGE52',
 PART_TYPE='SMLF',
 PHYS_PAGE='52',
 XY='(1725,2600)',
 ROT='0',
 VER='1',
 CDS_LIB='pure_quanta',
 CDS_PART_NAME='MC74VHC1G32DTT1G-MC74VHC1G32DTA',
 MATERIAL='IC',
 VALUE='MC74VHC1G32DTT1G',
 PRIM_FILE='W:/<user>/logical/mc74vhc1g32dtt1g/chips/chips.prt';

PART_NAME
 U43 'TPS3808G18DBVR-TPS3808G01DBVR,A':;

SECTION_NUMBER 1
 '@SCM_LIB.SCM(SCH_1):PAGE22_I90@PURE_QUANTA.TPS3808G18DBVR(CHIPS)':
 C_PATH='@scm_lib.scm(sch_1):page22_i90@pure_quanta.tps3808g18dbvr(chips)',
 P_PATH='@scm_lib.scm(sch_1):page22_i90@pure_quanta.tps3808g18dbvr(chips)',
 PATH='I90',
 DRAWING='@SCM_LIB.SCM(SCH_1):PAGE22',
 PART_TYPE='SMLF',
 PHYS_PAGE='22',
 XY='(-1125,-225)',
 ROT='0',
 VER='1',
 LOCATION='U43',
 CDS_LIB='pure_quanta',
 CDS_PART_NAME='TPS3808G18DBVR-TPS3808G01DBVR,A',
 MATERIAL='IC',
 VALUE='TPS3808G01DBVR',
 PRIM_FILE='W:/<user>/logical/tps3808g18dbvr/chips/chips.prt';

PART_NAME
 U44 'SN74LVC1G07DCKR-SN74LVC1G07DCKA':;

SECTION_NUMBER 1
 '@SCM_LIB.SCM(SCH_1):PAGE25_I61@PURE_QUANTA.SN74LVC1G07DCKR(CHIPS)':
 C_PATH='@scm_lib.scm(sch_1):page25_i61@pure_quanta.sn74lvc1g07dckr(chips)',
 P_PATH='@scm_lib.scm(sch_1):page25_i61@pure_quanta.sn74lvc1g07dckr(chips)',
 PATH='I61',
 DRAWING='@SCM_LIB.SCM(SCH_1):PAGE25',
 PART_TYPE='SMLF',
 PHYS_PAGE='25',
 XY='(450,-950)',
 ROT='0',
 VER='1',
 LOCATION='U44',
 CDS_LIB='pure_quanta',
 CDS_PART_NAME='SN74LVC1G07DCKR-SN74LVC1G07DCKA',
 MATERIAL='IC',
 VALUE='SN74LVC1G07DCKR',
 PRIM_FILE='W:/<user>/logical/sn74lvc1g07dckr/chips/chips.prt';

PART_NAME
 U47 '74LVC2G07DW7-74LVC2G07DW-7,SMLA':;

SECTION_NUMBER 1
 '@SCM_LIB.SCM(SCH_1):PAGE30_I247@PURE_QUANTA.74LVC2G07DW7(CHIPS)':
 C_PATH='@scm_lib.scm(sch_1):page30_i247@pure_quanta.\74lvc2g07dw7\(chips)',
 P_PATH='@scm_lib.scm(sch_1):page30_i247@pure_quanta.\74lvc2g07dw7\(chips)',
 PATH='I247',
 DRAWING='@SCM_LIB.SCM(SCH_1):PAGE30',
 PART_TYPE='SMLF',
 PHYS_PAGE='30',
 XY='(-250,2100)',
 ROT='0',
 VER='1',
 LOCATION='U47',
 CDS_LIB='pure_quanta',
 CDS_PART_NAME='74LVC2G07DW7-74LVC2G07DW-7,SMLA',
 MATERIAL='IC',
 VALUE='74LVC2G07DW-7',
 PRIM_FILE='W:/<user>/logical/74lvc2g07dw7/chips/chips.prt';

PART_NAME
 U48 'BAS70057F-BAS70-05-7-F,SMLF,ICA':;

SECTION_NUMBER 1
 '@SCM_LIB.SCM(SCH_1):PAGE50_I161@PURE_QUANTA.BAS70057F(CHIPS)':
 C_PATH='@scm_lib.scm(sch_1):page50_i161@pure_quanta.bas70057f(chips)',
 P_PATH='@scm_lib.scm(sch_1):page50_i161@pure_quanta.bas70057f(chips)',
 PATH='I161',
 DRAWING='@SCM_LIB.SCM(SCH_1):PAGE50',
 SEC_TYPE='',
 PART_TYPE='SMLF',
 PHYS_PAGE='50',
 XY='(3975,4950)',
 ROT='7',
 VER='1',
 LOCATION='U48',
 SEC='1',
 CDS_LIB='pure_quanta',
 CDS_PART_NAME='BAS70057F-BAS70-05-7-F,SMLF,ICA',
 MATERIAL='IC',
 VALUE='BAS70-05-7-F',
 PRIM_FILE='W:/<user>/logical/bas70057f/chips/chips.prt';

PART_NAME
 U49 'MC74VHC1G32DTT1G-MC74VHC1G32DTA':;

SECTION_NUMBER 1
 '@SCM_LIB.SCM(SCH_1):PAGE54_I116@PURE_QUANTA.MC74VHC1G32DTT1G(CHIPS)':
 C_PATH='@scm_lib.scm(sch_1):page54_i116@pure_quanta.mc74vhc1g32dtt1g(chips)',
 P_PATH='@scm_lib.scm(sch_1):page54_i116@pure_quanta.mc74vhc1g32dtt1g(chips)',
 PATH='I116',
 DRAWING='@SCM_LIB.SCM(SCH_1):PAGE54',
 PART_TYPE='SMLF',
 PHYS_PAGE='54',
 XY='(975,-600)',
 ROT='0',
 VER='1',
 CDS_LIB='pure_quanta',
 CDS_PART_NAME='MC74VHC1G32DTT1G-MC74VHC1G32DTA',
 MATERIAL='IC',
 VALUE='MC74VHC1G32DTT1G',
 PRIM_FILE='W:/<user>/logical/mc74vhc1g32dtt1g/chips/chips.prt';

PART_NAME
 U50 'NC7SB3157_SMLF-NC7SB3157P6X,NCA':;

SECTION_NUMBER 1
 '@SCM_LIB.SCM(SCH_1):PAGE31_I23@PURE_QUANTA.NC7SB3157(CHIPS)':
 C_PATH='@scm_lib.scm(sch_1):page31_i23@pure_quanta.nc7sb3157(chips)',
 P_PATH='@scm_lib.scm(sch_1):page31_i23@pure_quanta.nc7sb3157(chips)',
 PATH='I23',
 DRAWING='@SCM_LIB.SCM(SCH_1):PAGE31',
 PHYS_PAGE='31',
 XY='(-4650,5550)',
 ROT='0',
 VER='1',
 PACK_TYPE='SMLF',
 LOCATION='U50',
 CDS_LIB='pure_quanta',
 CDS_PART_NAME='NC7SB3157_SMLF-NC7SB3157P6X,NCA',
 MATERIAL='IC',
 MANUF_PN='NC7SB3157P6X',
 VALUE='NC7SB3157P6X',
 PRIM_FILE='W:/<user>/logical/nc7sb3157/chips/chips.prt';

PART_NAME
 U51 'NC7SB3157_SMLF-NC7SB3157P6X,NCA':;

SECTION_NUMBER 1
 '@SCM_LIB.SCM(SCH_1):PAGE31_I24@PURE_QUANTA.NC7SB3157(CHIPS)':
 C_PATH='@scm_lib.scm(sch_1):page31_i24@pure_quanta.nc7sb3157(chips)',
 P_PATH='@scm_lib.scm(sch_1):page31_i24@pure_quanta.nc7sb3157(chips)',
 PATH='I24',
 DRAWING='@SCM_LIB.SCM(SCH_1):PAGE31',
 PHYS_PAGE='31',
 XY='(-4625,4400)',
 ROT='0',
 VER='1',
 PACK_TYPE='SMLF',
 LOCATION='U51',
 CDS_LIB='pure_quanta',
 CDS_PART_NAME='NC7SB3157_SMLF-NC7SB3157P6X,NCA',
 MATERIAL='IC',
 MANUF_PN='NC7SB3157P6X',
 VALUE='NC7SB3157P6X',
 PRIM_FILE='W:/<user>/logical/nc7sb3157/chips/chips.prt';

PART_NAME
 U52 '74LVC1G08GW_SM-74LVC1G08GW,IC,A':;

SECTION_NUMBER 1
 '@SCM_LIB.SCM(SCH_1):PAGE55_I63@PURE_QUANTA.74LVC1G08GW(CHIPS)':
 C_PATH='@scm_lib.scm(sch_1):page55_i63@pure_quanta.\74lvc1g08gw\(chips)',
 P_PATH='@scm_lib.scm(sch_1):page55_i63@pure_quanta.\74lvc1g08gw\(chips)',
 PATH='I63',
 DRAWING='@SCM_LIB.SCM(SCH_1):PAGE55',
 PHYS_PAGE='55',
 XY='(-2000,2950)',
 ROT='0',
 VER='1',
 PACK_TYPE='SM',
 CDS_LIB='pure_quanta',
 CDS_PART_NAME='74LVC1G08GW_SM-74LVC1G08GW,IC,A',
 MATERIAL='IC',
 VALUE='74LVC1G08GW',
 PRIM_FILE='W:/<user>/logical/74lvc1g08gw/chips/chips.prt';

PART_NAME
 U53 '74LVC1G08GW_SM-74LVC1G08GW,IC,A':;

SECTION_NUMBER 1
 '@SCM_LIB.SCM(SCH_1):PAGE56_I66@PURE_QUANTA.74LVC1G08GW(CHIPS)':
 C_PATH='@scm_lib.scm(sch_1):page56_i66@pure_quanta.\74lvc1g08gw\(chips)',
 P_PATH='@scm_lib.scm(sch_1):page56_i66@pure_quanta.\74lvc1g08gw\(chips)',
 PATH='I66',
 DRAWING='@SCM_LIB.SCM(SCH_1):PAGE56',
 PHYS_PAGE='56',
 XY='(-3750,2775)',
 ROT='0',
 VER='1',
 PACK_TYPE='SM',
 CDS_LIB='pure_quanta',
 CDS_PART_NAME='74LVC1G08GW_SM-74LVC1G08GW,IC,A',
 MATERIAL='IC',
 VALUE='74LVC1G08GW',
 PRIM_FILE='W:/<user>/logical/74lvc1g08gw/chips/chips.prt';

PART_NAME
 U54 '74LVC1G74DP-74LVC1G74DP,SMLF,IA':;

SECTION_NUMBER 1
 '@SCM_LIB.SCM(SCH_1):PAGE25_I138@PURE_QUANTA.74LVC1G74DP(CHIPS)':
 C_PATH='@scm_lib.scm(sch_1):page25_i138@pure_quanta.\74lvc1g74dp\(chips)',
 P_PATH='@scm_lib.scm(sch_1):page25_i138@pure_quanta.\74lvc1g74dp\(chips)',
 PATH='I138',
 DRAWING='@SCM_LIB.SCM(SCH_1):PAGE25',
 PART_TYPE='SMLF',
 PHYS_PAGE='25',
 XY='(3075,3500)',
 ROT='0',
 VER='1',
 CDS_LIB='pure_quanta',
 CDS_PART_NAME='74LVC1G74DP-74LVC1G74DP,SMLF,IA',
 MATERIAL='IC',
 VALUE='74LVC1G74DP',
 PRIM_FILE='W:/<user>/logical/74lvc1g74dp/chips/chips.prt';

PART_NAME
 U55 'SN74LVC1G14DCKR_SMLF-IC,SN74LVA':;

SECTION_NUMBER 1
 '@SCM_LIB.SCM(SCH_1):PAGE25_I150@PURE_QUANTA.SN74LVC1G14DCKR(CHIPS)':
 C_PATH='@scm_lib.scm(sch_1):page25_i150@pure_quanta.sn74lvc1g14dckr(chips)',
 P_PATH='@scm_lib.scm(sch_1):page25_i150@pure_quanta.sn74lvc1g14dckr(chips)',
 PATH='I150',
 DRAWING='@SCM_LIB.SCM(SCH_1):PAGE25',
 PHYS_PAGE='25',
 XY='(4275,2600)',
 ROT='2',
 VER='1',
 PACK_TYPE='SMLF',
 CDS_LIB='pure_quanta',
 CDS_PART_NAME='SN74LVC1G14DCKR_SMLF-IC,SN74LVA',
 MATERIAL='IC',
 VALUE='SN74LVC1G14DCKR',
 PRIM_FILE='W:/<user>/logical/sn74lvc1g14dckr/chips/chips.prt';

PART_NAME
 U56 'AP2205W57-AP2205-W5-7,SMLF,IC,A':;

SECTION_NUMBER 1
 '@SCM_LIB.SCM(SCH_1):PAGE51_I56@PURE_QUANTA.AP2205W57(CHIPS)':
 C_PATH='@scm_lib.scm(sch_1):page51_i56@pure_quanta.ap2205w57(chips)',
 P_PATH='@scm_lib.scm(sch_1):page51_i56@pure_quanta.ap2205w57(chips)',
 PATH='I56',
 DRAWING='@SCM_LIB.SCM(SCH_1):PAGE51',
 PART_TYPE='SMLF',
 PHYS_PAGE='51',
 XY='(-425,3500)',
 ROT='0',
 VER='1',
 CDS_LIB='pure_quanta',
 CDS_PART_NAME='AP2205W57-AP2205-W5-7,SMLF,IC,A',
 MATERIAL='IC',
 VALUE='AP2205-W5-7',
 PRIM_FILE='W:/<user>/logical/ap2205w57/chips/chips.prt';

PART_NAME
 U57 '74LVC1G07GW-74LVC1G07GW,SMLF,IA':;

SECTION_NUMBER 1
 '@SCM_LIB.SCM(SCH_1):PAGE50_I278@PURE_QUANTA.74LVC1G07GW(CHIPS)':
 C_PATH='@scm_lib.scm(sch_1):page50_i278@pure_quanta.\74lvc1g07gw\(chips)',
 P_PATH='@scm_lib.scm(sch_1):page50_i278@pure_quanta.\74lvc1g07gw\(chips)',
 PATH='I278',
 DRAWING='@SCM_LIB.SCM(SCH_1):PAGE50',
 SEC_TYPE='',
 PART_TYPE='SMLF',
 PHYS_PAGE='50',
 XY='(4100,1050)',
 ROT='0',
 VER='1',
 SEC='1',
 CDS_LIB='pure_quanta',
 CDS_PART_NAME='74LVC1G07GW-74LVC1G07GW,SMLF,IA',
 MATERIAL='IC',
 VALUE='74LVC1G07GW',
 PRIM_FILE='W:/<user>/logical/74lvc1g07gw/chips/chips.prt';

PART_NAME
 U58 'MC74VHC1G32DTT1G-MC74VHC1G32DTA':;

SECTION_NUMBER 1
 '@SCM_LIB.SCM(SCH_1):PAGE22_I94@PURE_QUANTA.MC74VHC1G32DTT1G(CHIPS)':
 C_PATH='@scm_lib.scm(sch_1):page22_i94@pure_quanta.mc74vhc1g32dtt1g(chips)',
 P_PATH='@scm_lib.scm(sch_1):page22_i94@pure_quanta.mc74vhc1g32dtt1g(chips)',
 PATH='I94',
 DRAWING='@SCM_LIB.SCM(SCH_1):PAGE22',
 PART_TYPE='SMLF',
 PHYS_PAGE='22',
 XY='(-2475,2475)',
 ROT='0',
 VER='1',
 CDS_LIB='pure_quanta',
 CDS_PART_NAME='MC74VHC1G32DTT1G-MC74VHC1G32DTA',
 MATERIAL='IC',
 VALUE='MC74VHC1G32DTT1G',
 PRIM_FILE='W:/<user>/logical/mc74vhc1g32dtt1g/chips/chips.prt';

PART_NAME
 X1 'TP_TDR_4P_FTS_TH-TP_TDR_4P_DIPA':;

SECTION_NUMBER 1
 '@SCM_LIB.SCM(SCH_1):PAGE60_I13@PURE_QUANTA.TP_TDR_4P_FTS(CHIPS)':
 C_PATH='@scm_lib.scm(sch_1):page60_i13@pure_quanta.tp_tdr_4p_fts(chips)',
 P_PATH='@scm_lib.scm(sch_1):page60_i13@pure_quanta.tp_tdr_4p_fts(chips)',
 PATH='I13',
 DRAWING='@SCM_LIB.SCM(SCH_1):PAGE60',
 SEC_TYPE='TH',
 PHYS_PAGE='60',
 XY='(-6450,5700)',
 ROT='0',
 VER='1',
 PACK_TYPE='TH',
 LOCATION='X1',
 SEC='1',
 CDS_LIB='pure_quanta',
 CDS_PART_NAME='TP_TDR_4P_FTS_TH-TP_TDR_4P_DIPA',
 MATERIAL='EMPTY',
 VALUE='TP_TDR_4P_DIP',
 PRIM_FILE='W:/<user>/logical/tp_tdr_4p_fts/chips/chips.prt';

PART_NAME
 X2 'TP_TDR_4P_FTS_TH-TP_TDR_4P_DIPA':;

SECTION_NUMBER 1
 '@SCM_LIB.SCM(SCH_1):PAGE60_I35@PURE_QUANTA.TP_TDR_4P_FTS(CHIPS)':
 C_PATH='@scm_lib.scm(sch_1):page60_i35@pure_quanta.tp_tdr_4p_fts(chips)',
 P_PATH='@scm_lib.scm(sch_1):page60_i35@pure_quanta.tp_tdr_4p_fts(chips)',
 PATH='I35',
 DRAWING='@SCM_LIB.SCM(SCH_1):PAGE60',
 SEC_TYPE='TH',
 PHYS_PAGE='60',
 XY='(-6450,5000)',
 ROT='0',
 VER='1',
 PACK_TYPE='TH',
 LOCATION='X2',
 SEC='1',
 CDS_LIB='pure_quanta',
 CDS_PART_NAME='TP_TDR_4P_FTS_TH-TP_TDR_4P_DIPA',
 MATERIAL='EMPTY',
 VALUE='TP_TDR_4P_DIP',
 PRIM_FILE='W:/<user>/logical/tp_tdr_4p_fts/chips/chips.prt';

PART_NAME
 X5 'TP_TDR_4P_FTS_TH-TP_TDR_4P_DIPA':;

SECTION_NUMBER 1
 '@SCM_LIB.SCM(SCH_1):PAGE60_I23@PURE_QUANTA.TP_TDR_4P_FTS(CHIPS)':
 C_PATH='@scm_lib.scm(sch_1):page60_i23@pure_quanta.tp_tdr_4p_fts(chips)',
 P_PATH='@scm_lib.scm(sch_1):page60_i23@pure_quanta.tp_tdr_4p_fts(chips)',
 PATH='I23',
 DRAWING='@SCM_LIB.SCM(SCH_1):PAGE60',
 SEC_TYPE='TH',
 PHYS_PAGE='60',
 XY='(-6450,2900)',
 ROT='0',
 VER='1',
 PACK_TYPE='TH',
 LOCATION='X5',
 SEC='1',
 CDS_LIB='pure_quanta',
 CDS_PART_NAME='TP_TDR_4P_FTS_TH-TP_TDR_4P_DIPA',
 MATERIAL='EMPTY',
 VALUE='TP_TDR_4P_DIP',
 PRIM_FILE='W:/<user>/logical/tp_tdr_4p_fts/chips/chips.prt';

PART_NAME
 X6 'TP_TDR_4P_FTS_TH-TP_TDR_4P_DIPA':;

SECTION_NUMBER 1
 '@SCM_LIB.SCM(SCH_1):PAGE60_I19@PURE_QUANTA.TP_TDR_4P_FTS(CHIPS)':
 C_PATH='@scm_lib.scm(sch_1):page60_i19@pure_quanta.tp_tdr_4p_fts(chips)',
 P_PATH='@scm_lib.scm(sch_1):page60_i19@pure_quanta.tp_tdr_4p_fts(chips)',
 PATH='I19',
 DRAWING='@SCM_LIB.SCM(SCH_1):PAGE60',
 SEC_TYPE='TH',
 PHYS_PAGE='60',
 XY='(-6450,2200)',
 ROT='0',
 VER='1',
 PACK_TYPE='TH',
 LOCATION='X6',
 SEC='1',
 CDS_LIB='pure_quanta',
 CDS_PART_NAME='TP_TDR_4P_FTS_TH-TP_TDR_4P_DIPA',
 MATERIAL='EMPTY',
 VALUE='TP_TDR_4P_DIP',
 PRIM_FILE='W:/<user>/logical/tp_tdr_4p_fts/chips/chips.prt';

PART_NAME
 X7 'TP_TDR_4P_FTS_TH-TP_TDR_4P_DIPA':;

SECTION_NUMBER 1
 '@SCM_LIB.SCM(SCH_1):PAGE60_I14@PURE_QUANTA.TP_TDR_4P_FTS(CHIPS)':
 C_PATH='@scm_lib.scm(sch_1):page60_i14@pure_quanta.tp_tdr_4p_fts(chips)',
 P_PATH='@scm_lib.scm(sch_1):page60_i14@pure_quanta.tp_tdr_4p_fts(chips)',
 PATH='I14',
 DRAWING='@SCM_LIB.SCM(SCH_1):PAGE60',
 SEC_TYPE='TH',
 PHYS_PAGE='60',
 XY='(-4925,5700)',
 ROT='4',
 VER='1',
 PACK_TYPE='TH',
 LOCATION='X7',
 SEC='1',
 CDS_LIB='pure_quanta',
 CDS_PART_NAME='TP_TDR_4P_FTS_TH-TP_TDR_4P_DIPA',
 MATERIAL='EMPTY',
 VALUE='TP_TDR_4P_DIP',
 PRIM_FILE='W:/<user>/logical/tp_tdr_4p_fts/chips/chips.prt';

PART_NAME
 X8 'TP_TDR_4P_FTS_TH-TP_TDR_4P_DIPA':;

SECTION_NUMBER 1
 '@SCM_LIB.SCM(SCH_1):PAGE60_I34@PURE_QUANTA.TP_TDR_4P_FTS(CHIPS)':
 C_PATH='@scm_lib.scm(sch_1):page60_i34@pure_quanta.tp_tdr_4p_fts(chips)',
 P_PATH='@scm_lib.scm(sch_1):page60_i34@pure_quanta.tp_tdr_4p_fts(chips)',
 PATH='I34',
 DRAWING='@SCM_LIB.SCM(SCH_1):PAGE60',
 SEC_TYPE='TH',
 PHYS_PAGE='60',
 XY='(-4925,5000)',
 ROT='4',
 VER='1',
 PACK_TYPE='TH',
 LOCATION='X8',
 SEC='1',
 CDS_LIB='pure_quanta',
 CDS_PART_NAME='TP_TDR_4P_FTS_TH-TP_TDR_4P_DIPA',
 MATERIAL='EMPTY',
 VALUE='TP_TDR_4P_DIP',
 PRIM_FILE='W:/<user>/logical/tp_tdr_4p_fts/chips/chips.prt';

PART_NAME
 X11 'TP_TDR_4P_FTS_TH-TP_TDR_4P_DIPA':;

SECTION_NUMBER 1
 '@SCM_LIB.SCM(SCH_1):PAGE60_I22@PURE_QUANTA.TP_TDR_4P_FTS(CHIPS)':
 C_PATH='@scm_lib.scm(sch_1):page60_i22@pure_quanta.tp_tdr_4p_fts(chips)',
 P_PATH='@scm_lib.scm(sch_1):page60_i22@pure_quanta.tp_tdr_4p_fts(chips)',
 PATH='I22',
 DRAWING='@SCM_LIB.SCM(SCH_1):PAGE60',
 SEC_TYPE='TH',
 PHYS_PAGE='60',
 XY='(-4925,2900)',
 ROT='4',
 VER='1',
 PACK_TYPE='TH',
 LOCATION='X11',
 SEC='1',
 CDS_LIB='pure_quanta',
 CDS_PART_NAME='TP_TDR_4P_FTS_TH-TP_TDR_4P_DIPA',
 MATERIAL='EMPTY',
 VALUE='TP_TDR_4P_DIP',
 PRIM_FILE='W:/<user>/logical/tp_tdr_4p_fts/chips/chips.prt';

PART_NAME
 X12 'TP_TDR_4P_FTS_TH-TP_TDR_4P_DIPA':;

SECTION_NUMBER 1
 '@SCM_LIB.SCM(SCH_1):PAGE60_I18@PURE_QUANTA.TP_TDR_4P_FTS(CHIPS)':
 C_PATH='@scm_lib.scm(sch_1):page60_i18@pure_quanta.tp_tdr_4p_fts(chips)',
 P_PATH='@scm_lib.scm(sch_1):page60_i18@pure_quanta.tp_tdr_4p_fts(chips)',
 PATH='I18',
 DRAWING='@SCM_LIB.SCM(SCH_1):PAGE60',
 SEC_TYPE='TH',
 PHYS_PAGE='60',
 XY='(-4925,2200)',
 ROT='4',
 VER='1',
 PACK_TYPE='TH',
 LOCATION='X12',
 SEC='1',
 CDS_LIB='pure_quanta',
 CDS_PART_NAME='TP_TDR_4P_FTS_TH-TP_TDR_4P_DIPA',
 MATERIAL='EMPTY',
 VALUE='TP_TDR_4P_DIP',
 PRIM_FILE='W:/<user>/logical/tp_tdr_4p_fts/chips/chips.prt';

PART_NAME
 X13 'TP_TDR_4P_FTS_TH-TP_TDR_4P_DIPA':;

SECTION_NUMBER 1
 '@SCM_LIB.SCM(SCH_1):PAGE60_I39@PURE_QUANTA.TP_TDR_4P_FTS(CHIPS)':
 C_PATH='@scm_lib.scm(sch_1):page60_i39@pure_quanta.tp_tdr_4p_fts(chips)',
 P_PATH='@scm_lib.scm(sch_1):page60_i39@pure_quanta.tp_tdr_4p_fts(chips)',
 PATH='I39',
 DRAWING='@SCM_LIB.SCM(SCH_1):PAGE60',
 SEC_TYPE='TH',
 PHYS_PAGE='60',
 XY='(-3325,5700)',
 ROT='0',
 VER='1',
 PACK_TYPE='TH',
 LOCATION='X13',
 SEC='1',
 CDS_LIB='pure_quanta',
 CDS_PART_NAME='TP_TDR_4P_FTS_TH-TP_TDR_4P_DIPA',
 MATERIAL='EMPTY',
 VALUE='TP_TDR_4P_DIP',
 PRIM_FILE='W:/<user>/logical/tp_tdr_4p_fts/chips/chips.prt';

PART_NAME
 X14 'TP_TDR_4P_FTS_TH-TP_TDR_4P_DIPA':;

SECTION_NUMBER 1
 '@SCM_LIB.SCM(SCH_1):PAGE60_I58@PURE_QUANTA.TP_TDR_4P_FTS(CHIPS)':
 C_PATH='@scm_lib.scm(sch_1):page60_i58@pure_quanta.tp_tdr_4p_fts(chips)',
 P_PATH='@scm_lib.scm(sch_1):page60_i58@pure_quanta.tp_tdr_4p_fts(chips)',
 PATH='I58',
 DRAWING='@SCM_LIB.SCM(SCH_1):PAGE60',
 SEC_TYPE='TH',
 PHYS_PAGE='60',
 XY='(-3325,5000)',
 ROT='0',
 VER='1',
 PACK_TYPE='TH',
 LOCATION='X14',
 SEC='1',
 CDS_LIB='pure_quanta',
 CDS_PART_NAME='TP_TDR_4P_FTS_TH-TP_TDR_4P_DIPA',
 MATERIAL='EMPTY',
 VALUE='TP_TDR_4P_DIP',
 PRIM_FILE='W:/<user>/logical/tp_tdr_4p_fts/chips/chips.prt';

PART_NAME
 X17 'TP_TDR_4P_FTS_TH-TP_TDR_4P_DIPA':;

SECTION_NUMBER 1
 '@SCM_LIB.SCM(SCH_1):PAGE60_I46@PURE_QUANTA.TP_TDR_4P_FTS(CHIPS)':
 C_PATH='@scm_lib.scm(sch_1):page60_i46@pure_quanta.tp_tdr_4p_fts(chips)',
 P_PATH='@scm_lib.scm(sch_1):page60_i46@pure_quanta.tp_tdr_4p_fts(chips)',
 PATH='I46',
 DRAWING='@SCM_LIB.SCM(SCH_1):PAGE60',
 SEC_TYPE='TH',
 PHYS_PAGE='60',
 XY='(-3325,2900)',
 ROT='0',
 VER='1',
 PACK_TYPE='TH',
 LOCATION='X17',
 SEC='1',
 CDS_LIB='pure_quanta',
 CDS_PART_NAME='TP_TDR_4P_FTS_TH-TP_TDR_4P_DIPA',
 MATERIAL='EMPTY',
 VALUE='TP_TDR_4P_DIP',
 PRIM_FILE='W:/<user>/logical/tp_tdr_4p_fts/chips/chips.prt';

PART_NAME
 X18 'TP_TDR_4P_FTS_TH-TP_TDR_4P_DIPA':;

SECTION_NUMBER 1
 '@SCM_LIB.SCM(SCH_1):PAGE60_I42@PURE_QUANTA.TP_TDR_4P_FTS(CHIPS)':
 C_PATH='@scm_lib.scm(sch_1):page60_i42@pure_quanta.tp_tdr_4p_fts(chips)',
 P_PATH='@scm_lib.scm(sch_1):page60_i42@pure_quanta.tp_tdr_4p_fts(chips)',
 PATH='I42',
 DRAWING='@SCM_LIB.SCM(SCH_1):PAGE60',
 SEC_TYPE='TH',
 PHYS_PAGE='60',
 XY='(-3325,2200)',
 ROT='0',
 VER='1',
 PACK_TYPE='TH',
 LOCATION='X18',
 SEC='1',
 CDS_LIB='pure_quanta',
 CDS_PART_NAME='TP_TDR_4P_FTS_TH-TP_TDR_4P_DIPA',
 MATERIAL='EMPTY',
 VALUE='TP_TDR_4P_DIP',
 PRIM_FILE='W:/<user>/logical/tp_tdr_4p_fts/chips/chips.prt';

PART_NAME
 X19 'TP_TDR_4P_FTS_TH-TP_TDR_4P_DIPA':;

SECTION_NUMBER 1
 '@SCM_LIB.SCM(SCH_1):PAGE60_I38@PURE_QUANTA.TP_TDR_4P_FTS(CHIPS)':
 C_PATH='@scm_lib.scm(sch_1):page60_i38@pure_quanta.tp_tdr_4p_fts(chips)',
 P_PATH='@scm_lib.scm(sch_1):page60_i38@pure_quanta.tp_tdr_4p_fts(chips)',
 PATH='I38',
 DRAWING='@SCM_LIB.SCM(SCH_1):PAGE60',
 SEC_TYPE='TH',
 PHYS_PAGE='60',
 XY='(-1800,5700)',
 ROT='4',
 VER='1',
 PACK_TYPE='TH',
 LOCATION='X19',
 SEC='1',
 CDS_LIB='pure_quanta',
 CDS_PART_NAME='TP_TDR_4P_FTS_TH-TP_TDR_4P_DIPA',
 MATERIAL='EMPTY',
 VALUE='TP_TDR_4P_DIP',
 PRIM_FILE='W:/<user>/logical/tp_tdr_4p_fts/chips/chips.prt';

PART_NAME
 X20 'TP_TDR_4P_FTS_TH-TP_TDR_4P_DIPA':;

SECTION_NUMBER 1
 '@SCM_LIB.SCM(SCH_1):PAGE60_I59@PURE_QUANTA.TP_TDR_4P_FTS(CHIPS)':
 C_PATH='@scm_lib.scm(sch_1):page60_i59@pure_quanta.tp_tdr_4p_fts(chips)',
 P_PATH='@scm_lib.scm(sch_1):page60_i59@pure_quanta.tp_tdr_4p_fts(chips)',
 PATH='I59',
 DRAWING='@SCM_LIB.SCM(SCH_1):PAGE60',
 SEC_TYPE='TH',
 PHYS_PAGE='60',
 XY='(-1800,5000)',
 ROT='4',
 VER='1',
 PACK_TYPE='TH',
 LOCATION='X20',
 SEC='1',
 CDS_LIB='pure_quanta',
 CDS_PART_NAME='TP_TDR_4P_FTS_TH-TP_TDR_4P_DIPA',
 MATERIAL='EMPTY',
 VALUE='TP_TDR_4P_DIP',
 PRIM_FILE='W:/<user>/logical/tp_tdr_4p_fts/chips/chips.prt';

PART_NAME
 X23 'TP_TDR_4P_FTS_TH-TP_TDR_4P_DIPA':;

SECTION_NUMBER 1
 '@SCM_LIB.SCM(SCH_1):PAGE60_I47@PURE_QUANTA.TP_TDR_4P_FTS(CHIPS)':
 C_PATH='@scm_lib.scm(sch_1):page60_i47@pure_quanta.tp_tdr_4p_fts(chips)',
 P_PATH='@scm_lib.scm(sch_1):page60_i47@pure_quanta.tp_tdr_4p_fts(chips)',
 PATH='I47',
 DRAWING='@SCM_LIB.SCM(SCH_1):PAGE60',
 SEC_TYPE='TH',
 PHYS_PAGE='60',
 XY='(-1800,2900)',
 ROT='4',
 VER='1',
 PACK_TYPE='TH',
 LOCATION='X23',
 SEC='1',
 CDS_LIB='pure_quanta',
 CDS_PART_NAME='TP_TDR_4P_FTS_TH-TP_TDR_4P_DIPA',
 MATERIAL='EMPTY',
 VALUE='TP_TDR_4P_DIP',
 PRIM_FILE='W:/<user>/logical/tp_tdr_4p_fts/chips/chips.prt';

PART_NAME
 X24 'TP_TDR_4P_FTS_TH-TP_TDR_4P_DIPA':;

SECTION_NUMBER 1
 '@SCM_LIB.SCM(SCH_1):PAGE60_I43@PURE_QUANTA.TP_TDR_4P_FTS(CHIPS)':
 C_PATH='@scm_lib.scm(sch_1):page60_i43@pure_quanta.tp_tdr_4p_fts(chips)',
 P_PATH='@scm_lib.scm(sch_1):page60_i43@pure_quanta.tp_tdr_4p_fts(chips)',
 PATH='I43',
 DRAWING='@SCM_LIB.SCM(SCH_1):PAGE60',
 SEC_TYPE='TH',
 PHYS_PAGE='60',
 XY='(-1800,2200)',
 ROT='4',
 VER='1',
 PACK_TYPE='TH',
 LOCATION='X24',
 SEC='1',
 CDS_LIB='pure_quanta',
 CDS_PART_NAME='TP_TDR_4P_FTS_TH-TP_TDR_4P_DIPA',
 MATERIAL='EMPTY',
 VALUE='TP_TDR_4P_DIP',
 PRIM_FILE='W:/<user>/logical/tp_tdr_4p_fts/chips/chips.prt';

END.
